G04 ================== begin FILE IDENTIFICATION RECORD ==================*
G04 Layout Name:  9127_F0T_Expander_BD_F_v02_0110_1240.brd*
G04 Film Name:    in3*
G04 File Format:  Gerber RS274X*
G04 File Origin:  Cadence Allegro 17.2-S081*
G04 Origin Date:  Wed Jan 11 16:06:17 2023*
G04 *
G04 Layer:  VIA CLASS/IN3*
G04 Layer:  PIN/IN3*
G04 Layer:  ETCH/IN3*
G04 Layer:  PIN/SPECIAL_DRILL*
G04 Layer:  DRAWING FORMAT/TITLE_BLOCK_A*
G04 Layer:  MANUFACTURING/PHOTOPLOT_OUTLINE*
G04 Layer:  DRAWING FORMAT/TITLE_BLOCK*
G04 Layer:  DRAWING FORMAT/TITLE_DATA_IN3*
G04 *
G04 Offset:    (0.00 0.00)*
G04 Mirror:    No*
G04 Mode:      Positive*
G04 Rotation:  0*
G04 FullContactRelief:  No*
G04 UndefLineWidth:     6.00*
G04 ================== end FILE IDENTIFICATION RECORD ====================*
%FSLAX25Y25*MOIN*%
%IR0*IPPOS*OFA0.00000B0.00000*MIA0B0*SFA1.00000B1.00000*%
%ADD20O,.137X.062*%
%ADD10C,.02*%
%ADD16C,.03*%
%ADD13O,.137X.064*%
%ADD26C,.061*%
%ADD15C,.016*%
%ADD21C,.0315*%
%ADD14C,.018*%
%ADD19C,.064*%
%ADD25C,.048*%
%ADD18C,.0282*%
%ADD27C,.085*%
%ADD24C,.07051*%
%ADD22C,.0193*%
%ADD17C,.03568*%
%ADD28O,.044X.071*%
%ADD23C,.315*%
%ADD29O,.044X.087*%
%ADD11C,.256*%
%ADD12C,.394*%
%ADD30C,.01*%
%ADD31C,.006*%
%ADD32C,.0061*%
%ADD33C,.0035*%
%ADD34C,.0045*%
%ADD35C,.0055*%
%ADD36C,.0065*%
%ADD37C,.03004*%
%ADD59C,.03006*%
%ADD52C,.02404*%
%ADD62C,.07005*%
%ADD50C,.02604*%
%ADD48C,.07104*%
%ADD38C,.0921*%
%ADD44C,.0841*%
%ADD51C,.02804*%
%ADD45C,.08411*%
%ADD69C,.07404*%
%ADD49C,.08304*%
%ADD42C,.08404*%
%ADD64C,.05804*%
%ADD61C,.03824*%
%ADD47C,.02934*%
%ADD43C,.08406*%
%ADD60C,.07606*%
%ADD66C,.08408*%
%ADD53C,.02576*%
%ADD65C,.08409*%
%ADD58C,.07608*%
%ADD70O,.1621X.2251*%
%ADD39O,.03604X.07004*%
%ADD55O,.03006X.06406*%
%ADD68C,.41406*%
%ADD67C,.16206*%
%ADD40O,.03606X.07006*%
%ADD46C,.17406*%
%ADD41C,.16506*%
%ADD56C,.16804*%
%ADD57C,.37406*%
%ADD63C,.41376*%
%ADD54C,.21786*%
G75*
%LPD*%
G75*
G36*
G01X2000Y1212277D02*
X3998D01*
Y970425D01*
G03X5133Y967685I3877J1D01*
G01X15480Y957338D01*
G02X18958Y948943I-8394J-8396D01*
G01Y344836D01*
G02X15480Y336442I-11871J1D01*
G01X5132Y326094D01*
G03X3998Y323355I2742J-2739D01*
G01Y7874D01*
G03X7874Y3998I3876J0D01*
G01X23484D01*
G03X27360Y7874I0J3876D01*
G01Y46654D01*
G02X35295Y54588I7935J-1D01*
G01X64100D01*
X64454Y54234D01*
Y52945D01*
X64100Y52591D01*
X35295D01*
G03X29358Y46654I0J-5937D01*
G01Y7874D01*
G02X23484Y2000I-5874J0D01*
G01X7874D01*
G02X2000Y7874I0J5874D01*
G01Y323354D01*
G02X3720Y327506I5873J-1D01*
G01X14068Y337855D01*
G03X16961Y344836I-6980J6983D01*
G01Y948943D01*
G03X14068Y955925I-9875J-1D01*
G01X3720Y966273D01*
G02X2000Y970426I4154J4153D01*
G01Y1212277D01*
G37*
G36*
G01X1081725Y1645992D02*
X1833071D01*
G02X1838945Y1640118I0J-5874D01*
G01Y970426D01*
G02X1837225Y966273I-5874J0D01*
G01X1826876Y955925D01*
G03X1823984Y948944I6982J-6982D01*
G01Y344836D01*
G03X1826876Y337855I9873J0D01*
G01X1837225Y327506D01*
G02X1838945Y323354I-4153J-4153D01*
G01Y7874D01*
G02X1833071Y2000I-5874J0D01*
G01X1756949D01*
G02X1751075Y7874I0J5874D01*
G01Y46654D01*
G03X1749600Y50571I-5938J0D01*
G01Y50666D01*
X1749606Y50672D01*
X1751979D01*
G02X1753072Y46654I-6841J-4019D01*
G01Y7874D01*
G03X1756947Y3998I3876J0D01*
G01X1833071D01*
G03X1836948Y7874I0J3877D01*
G01Y323354D01*
G03X1835813Y326094I-3876J0D01*
G01X1825464Y336443D01*
G02X1821987Y344836I8393J8394D01*
G01X1821986D01*
Y948944D01*
X1821987D01*
G02X1825464Y957337I11871J-1D01*
G01X1835813Y967685D01*
G03X1836948Y970426I-2742J2741D01*
G01Y1640118D01*
G03X1833073Y1643994I-3876J0D01*
G01X1633526D01*
Y1644873D01*
X1578560D01*
Y1643994D01*
X1285912D01*
Y1644677D01*
X1232543D01*
Y1643994D01*
X1081724D01*
G03X1078854Y1642722I1J-3877D01*
G02X1070058Y1638822I-8797J7971D01*
G01X800966D01*
G02X792169Y1642722I0J11872D01*
G03X789299Y1643994I-2871J-2603D01*
G01X608951D01*
Y1644464D01*
X555228D01*
Y1643994D01*
X262776D01*
Y1644377D01*
X208818D01*
Y1643994D01*
X7874D01*
G03X3998Y1640118I0J-3876D01*
G01Y1529720D01*
X2421Y1528143D01*
Y1514948D01*
X3998Y1513371D01*
Y970425D01*
G03X5133Y967685I3877J1D01*
G01X15480Y957338D01*
G02X18958Y948943I-8394J-8396D01*
G01Y344836D01*
G02X15480Y336442I-11871J1D01*
G01X5132Y326094D01*
G03X3998Y323355I2742J-2739D01*
G01Y7874D01*
G03X7874Y3998I3876J0D01*
G01X23484D01*
G03X27360Y7874I0J3876D01*
G01Y46654D01*
G02X35295Y54588I7935J-1D01*
G01X64100D01*
X64454Y54234D01*
Y52945D01*
X64100Y52591D01*
X35295D01*
G03X29358Y46654I0J-5937D01*
G01Y7874D01*
G02X23484Y2000I-5874J0D01*
G01X7874D01*
G02X2000Y7874I0J5874D01*
G01Y323354D01*
G02X3720Y327506I5873J-1D01*
G01X14068Y337855D01*
G03X16961Y344836I-6980J6983D01*
G01Y948943D01*
G03X14068Y955925I-9875J-1D01*
G01X3720Y966273D01*
G02X2000Y970426I4154J4153D01*
G01Y1640118D01*
G02X7874Y1645992I5874J0D01*
G01X789298D01*
G02X793649Y1644063I-1J-5873D01*
G03X800966Y1640819I7317J6631D01*
G01X1070058D01*
G03X1077374Y1644063I-1J9873D01*
G02X1081725Y1645992I4352J-3945D01*
G37*
G36*
G01X635658Y1103926D02*
X635699Y1103922D01*
X635701D01*
G03X635827Y1103915I130J1195D01*
G03Y1106319I0J1202D01*
G03X635701Y1106312I4J-1202D01*
G01X635699D01*
X635658Y1106308D01*
X635578Y1106334D01*
X635324Y1106561D01*
G02X635258Y1106710I134J149D01*
G01Y1106988D01*
G03X635255Y1107074I-1302J-2D01*
G03X635251Y1107123I-1300J-81D01*
G02X635308Y1107285I199J21D01*
G01X635561Y1107538D01*
X635646Y1107568D01*
X635690Y1107563D01*
G03X635827Y1107556I135J1295D01*
G03X636831Y1108029I0J1302D01*
G02X636985Y1108102I154J-127D01*
G01X638409D01*
G02X638563Y1108029I0J-200D01*
G03X639567Y1107556I1004J829D01*
G03X639700Y1107563I-2J1302D01*
G01X639745Y1107568D01*
X639830Y1107538D01*
X640082Y1107285D01*
G02X640139Y1107123I-142J-141D01*
G03X640135Y1107074I1296J-130D01*
G03X640132Y1106988I1299J-88D01*
G01Y1103248D01*
G03X641435Y1101945I1303J0D01*
G01X641438D01*
G03X641674Y1101967I-2J1303D01*
G01X641676D01*
X641697Y1101971D01*
X641787Y1101943D01*
X642054Y1101689D01*
G02X642114Y1101521I-139J-144D01*
G01Y1101520D01*
G03X642105Y1101376I1193J-147D01*
G03X643307Y1102578I1202J0D01*
G03X643163Y1102569I3J-1202D01*
G01X643162D01*
G02X642994Y1102629I-24J199D01*
G01X642740Y1102896D01*
X642712Y1102986D01*
X642716Y1103008D01*
G03X642738Y1103245I-1281J238D01*
G01Y1103524D01*
G02X642804Y1103673I200J0D01*
G01X643058Y1103900D01*
X643138Y1103926D01*
X643180Y1103922D01*
G03X643307Y1103915I130J1195D01*
G03Y1106319I0J1202D01*
G03X643181Y1106312I4J-1202D01*
G01X643179D01*
X643138Y1106308D01*
X643058Y1106334D01*
X642804Y1106561D01*
G02X642738Y1106710I134J149D01*
G01Y1106988D01*
G03X642735Y1107074I-1302J-2D01*
G03X642731Y1107123I-1300J-81D01*
G02X642788Y1107285I199J21D01*
G01X643041Y1107538D01*
X643126Y1107568D01*
X643170Y1107563D01*
G03X643307Y1107556I135J1295D01*
G03X644311Y1108029I0J1302D01*
G02X644465Y1108102I154J-127D01*
G01X645889D01*
G02X646043Y1108029I0J-200D01*
G03X647047Y1107556I1004J829D01*
G01X647049D01*
G03X647419Y1107610I-1J1302D01*
G02X647671Y1107373I57J-192D01*
G03X647637Y1107236I1245J-382D01*
G01Y1107231D01*
X647633Y1107211D01*
G03X647628Y1107185I1276J-259D01*
G01Y1107176D01*
X647625Y1107160D01*
G03X647621Y1107132I1287J-198D01*
G01X647620Y1107124D01*
G03X647614Y1106992I1296J-125D01*
G01Y1103248D01*
G03X648916Y1101946I1302J0D01*
G03X649142Y1101966I-1J1302D01*
G01X649145D01*
X649179Y1101972D01*
X649268Y1101944D01*
X649534Y1101690D01*
G02X649594Y1101522I-139J-144D01*
G01Y1101521D01*
G03X649585Y1101376I1193J-147D01*
G03X650787Y1102578I1202J0D01*
G03X650643Y1102569I3J-1202D01*
G01X650642D01*
G02X650474Y1102629I-24J199D01*
G01X650220Y1102896D01*
X650192Y1102986D01*
X650196Y1103009D01*
G03X650218Y1103247I-1280J238D01*
G01Y1103524D01*
G02X650284Y1103673I200J0D01*
G01X650538Y1103900D01*
X650618Y1103926D01*
X650660Y1103922D01*
G03X650787Y1103915I130J1195D01*
G03Y1106319I0J1202D01*
G03X650661Y1106312I4J-1202D01*
G01X650659D01*
X650618Y1106308D01*
X650538Y1106334D01*
X650284Y1106561D01*
G02X650218Y1106710I134J149D01*
G01Y1106989D01*
G03X650208Y1107148I-1302J-2D01*
G01Y1107152D01*
X650206Y1107170D01*
X650236Y1107254D01*
X650489Y1107506D01*
G02X650651Y1107563I141J-142D01*
G03X650785Y1107556I135J1295D01*
G01X650787D01*
G03X651791Y1108029I0J1302D01*
G02X651945Y1108102I154J-127D01*
G01X653369D01*
G02X653523Y1108029I0J-200D01*
G03X654527Y1107556I1004J829D01*
G01X654529D01*
G03X654899Y1107610I-1J1302D01*
G02X655151Y1107373I57J-192D01*
G03X655117Y1107236I1245J-382D01*
G01Y1107231D01*
X655113Y1107211D01*
G03X655108Y1107185I1276J-259D01*
G01Y1107176D01*
X655105Y1107160D01*
G03X655101Y1107132I1287J-198D01*
G01X655100Y1107124D01*
G03X655094Y1106992I1296J-125D01*
G01Y1103248D01*
G03X656396Y1101946I1302J0D01*
G03X656612Y1101964I0J1302D01*
G01X656658Y1101972D01*
X656748Y1101944D01*
X657015Y1101690D01*
G02X657075Y1101522I-139J-144D01*
G01Y1101521D01*
G03X657066Y1101376I1193J-147D01*
G03X658268Y1102578I1202J0D01*
G03X658123Y1102569I2J-1202D01*
G01X658122D01*
G02X657954Y1102629I-24J199D01*
G01X657700Y1102896D01*
X657672Y1102986D01*
X657680Y1103032D01*
G03X657698Y1103248I-1284J216D01*
G01Y1103524D01*
G02X657764Y1103673I200J0D01*
G01X658018Y1103900D01*
X658098Y1103926D01*
X658140Y1103922D01*
G03X658268Y1103915I130J1195D01*
G03Y1106319I0J1202D01*
G03X658141Y1106312I3J-1202D01*
G01X658139D01*
X658098Y1106308D01*
X658018Y1106334D01*
X657764Y1106561D01*
G02X657698Y1106710I134J149D01*
G01Y1106989D01*
G03X657688Y1107148I-1302J-2D01*
G01Y1107152D01*
X657686Y1107170D01*
X657716Y1107254D01*
X657969Y1107506D01*
G02X658131Y1107563I141J-142D01*
G03X658268Y1107556I135J1295D01*
G03X659272Y1108029I0J1302D01*
G02X659426Y1108102I154J-127D01*
G01X660850D01*
G02X661004Y1108029I0J-200D01*
G03X662008Y1107556I1004J829D01*
G03X662379Y1107610I0J1301D01*
G02X662631Y1107372I57J-192D01*
G03X662597Y1107236I1245J-383D01*
G01Y1107231D01*
X662593Y1107211D01*
G03X662588Y1107185I1276J-259D01*
G01Y1107176D01*
X662585Y1107160D01*
G03X662581Y1107132I1287J-198D01*
G01X662580Y1107124D01*
G03X662574Y1106992I1296J-125D01*
G01Y1103248D01*
G03X663876Y1101946I1302J0D01*
G03X664092Y1101964I0J1302D01*
G01X664138Y1101972D01*
X664228Y1101944D01*
X664495Y1101690D01*
G02X664555Y1101522I-139J-144D01*
G01Y1101521D01*
G03X664546Y1101376I1193J-147D01*
G03X665748Y1102578I1202J0D01*
G03X665603Y1102569I2J-1202D01*
G01X665602D01*
G02X665434Y1102629I-24J199D01*
G01X665180Y1102896D01*
X665152Y1102986D01*
X665160Y1103032D01*
G03X665178Y1103248I-1284J216D01*
G01Y1103524D01*
G02X665244Y1103673I200J0D01*
G01X665498Y1103900D01*
X665578Y1103926D01*
X665620Y1103922D01*
G03X665748Y1103915I130J1195D01*
G03Y1106319I0J1202D01*
G03X665621Y1106312I3J-1202D01*
G01X665619D01*
X665578Y1106308D01*
X665498Y1106334D01*
X665244Y1106561D01*
G02X665178Y1106710I134J149D01*
G01Y1106989D01*
G03X665168Y1107148I-1302J-2D01*
G01Y1107152D01*
X665166Y1107170D01*
X665196Y1107254D01*
X665449Y1107506D01*
G02X665611Y1107563I141J-142D01*
G03X665748Y1107556I135J1295D01*
G03X666752Y1108029I0J1302D01*
G02X666906Y1108102I154J-127D01*
G01X668330D01*
G02X668484Y1108029I0J-200D01*
G03X669488Y1107556I1004J829D01*
G03X669622Y1107563I-1J1302D01*
G01X669667Y1107568D01*
X669752Y1107538D01*
X670004Y1107285D01*
G02X670061Y1107123I-142J-141D01*
G03X670057Y1107074I1296J-130D01*
G03X670054Y1106988I1299J-88D01*
G01Y1103248D01*
G03X671357Y1101945I1303J0D01*
G01X671360D01*
G03X671585Y1101965I-2J1303D01*
G01X671587D01*
X671619Y1101970D01*
X671708Y1101943D01*
X671974Y1101689D01*
G02X672035Y1101520I-137J-145D01*
G03X672026Y1101376I1193J-147D01*
G03X673228Y1102578I1202J0D01*
G03X673084Y1102569I3J-1202D01*
G01X673038Y1102563D01*
X672948Y1102595D01*
X672662Y1102896D01*
X672634Y1102985D01*
X672640Y1103020D01*
G03X672660Y1103247I-1283J227D01*
G01Y1103524D01*
G02X672726Y1103673I200J0D01*
G01X672947Y1103872D01*
G02X673101Y1103922I134J-149D01*
G01X673102D01*
G03X673228Y1103915I130J1195D01*
G03Y1106319I0J1202D01*
G03X673103Y1106312I5J-1202D01*
G01X673101D01*
G02X672947Y1106362I-20J199D01*
G01X672726Y1106561D01*
G02X672660Y1106710I134J149D01*
G01Y1106988D01*
G03X672657Y1107074I-1302J-2D01*
G03X672653Y1107123I-1300J-81D01*
G02X672710Y1107285I199J21D01*
G01X672962Y1107538D01*
X673047Y1107568D01*
X673092Y1107563D01*
G03X673226Y1107556I135J1295D01*
G01X673228D01*
G03X674232Y1108029I0J1302D01*
G02X674386Y1108102I154J-127D01*
G01X675810D01*
G02X675964Y1108029I0J-200D01*
G03X676968Y1107556I1004J829D01*
G03X677341Y1107611I-1J1302D01*
G02X677346Y1107613I76J-184D01*
G02X677542Y1107558I51J-194D01*
G02X677590Y1107362I-143J-139D01*
G03X677559Y1107236I1248J-374D01*
G01Y1107231D01*
X677555Y1107211D01*
G03X677550Y1107185I1276J-259D01*
G01Y1107176D01*
X677547Y1107160D01*
G03X677543Y1107132I1287J-198D01*
G01X677542Y1107124D01*
G03X677536Y1106992I1296J-125D01*
G01Y1103248D01*
G03X678838Y1101946I1302J0D01*
G03X679072Y1101967I1J1302D01*
G01X679074D01*
X679100Y1101971D01*
X679189Y1101944D01*
X679489Y1101656D01*
X679521Y1101568D01*
X679515Y1101521D01*
G03X679506Y1101376I1193J-147D01*
G03X680708Y1102578I1202J0D01*
G03X680564Y1102569I3J-1202D01*
G01X680518Y1102563D01*
X680428Y1102595D01*
X680142Y1102896D01*
X680114Y1102985D01*
X680120Y1103021D01*
G03X680140Y1103248I-1282J227D01*
G01Y1103524D01*
G02X680206Y1103673I200J0D01*
G01X680427Y1103872D01*
G02X680581Y1103922I134J-149D01*
G01X680582D01*
G03X680708Y1103915I130J1195D01*
G03Y1106319I0J1202D01*
G03X680583Y1106312I5J-1202D01*
G01X680581D01*
G02X680427Y1106362I-20J199D01*
G01X680206Y1106561D01*
G02X680140Y1106710I134J149D01*
G01Y1106989D01*
G03X680130Y1107148I-1302J-2D01*
G01Y1107152D01*
X680128Y1107170D01*
X680158Y1107254D01*
X680411Y1107506D01*
G02X680573Y1107563I141J-142D01*
G03X680707Y1107556I135J1295D01*
G01X680709D01*
G03X681713Y1108029I0J1302D01*
G02X681867Y1108102I154J-127D01*
G01X683291D01*
G02X683445Y1108029I0J-200D01*
G03X684449Y1107556I1004J829D01*
G03X684572Y1107562I-2J1302D01*
G01X684616Y1107566D01*
X684700Y1107536D01*
X684963Y1107273D01*
G02X685021Y1107114I-141J-142D01*
G01Y1107109D01*
X685019Y1107091D01*
Y1107090D01*
X685018Y1107081D01*
G03X685016Y1107053I1298J-107D01*
G01Y1107045D01*
X685015Y1107036D01*
Y1107001D01*
X685014Y1106994D01*
Y1103247D01*
G03X686317Y1101944I1303J0D01*
G01X686318D01*
G03X686544Y1101964I-1J1303D01*
G01X686546D01*
X686580Y1101970D01*
X686669Y1101942D01*
X686970Y1101656D01*
X687002Y1101566D01*
X686996Y1101520D01*
G03X686987Y1101376I1193J-147D01*
G03X688189Y1100174I1202J0D01*
G03X688260Y1100176I2J1202D01*
G01X688315Y1100179D01*
X688412Y1100128D01*
X688626Y1099780D01*
G02X688628Y1099574I-170J-105D01*
G03X688561Y1099454I3307J-1925D01*
G02X688491Y1099380I-176J96D01*
G03X687915Y1098935I2041J-3237D01*
G02X687833Y1098889I-136J147D01*
G03X686937Y1097993I356J-1252D01*
G02X686891Y1097911I-193J54D01*
G03X685858Y1095298I2793J-2615D01*
G01Y1095141D01*
G02X685744Y1094961I-200J1D01*
G01X685365Y1094780D01*
X685251Y1094794D01*
X685206Y1094831D01*
G03X684449Y1095099I-757J-935D01*
G03Y1092695I0J-1202D01*
G03X685206Y1092963I0J1203D01*
G01X685251Y1093000D01*
X685365Y1093014D01*
X685744Y1092833D01*
G02X685858Y1092653I-86J-181D01*
G01Y1085897D01*
G02X685746Y1085717I-200J0D01*
G01X685745D01*
G03X685014Y1084547I572J-1171D01*
G01Y1080806D01*
G03X685022Y1080659I1302J-3D01*
G01X685027Y1080614D01*
X684998Y1080528D01*
X684746Y1080274D01*
G02X684584Y1080216I-142J141D01*
G01X684583D01*
G03X684450Y1080224I-144J-1279D01*
G01X684448D01*
G03X683161Y1078936I1J-1288D01*
G03X684449Y1077648I1288J0D01*
G03X685218Y1077904I-1J1288D01*
G01X685264Y1077938D01*
X685376Y1077947D01*
X685748Y1077761D01*
G02X685858Y1077582I-90J-179D01*
G01Y1076550D01*
G02X685748Y1076371I-200J0D01*
G01X685427Y1076210D01*
G02X685218Y1076228I-90J179D01*
G03X684449Y1076484I-770J-1032D01*
G03Y1073908I0J-1288D01*
G03X685218Y1074164I-1J1288D01*
G01X685264Y1074198D01*
X685376Y1074207D01*
X685748Y1074021D01*
G02X685858Y1073842I-90J-179D01*
G01Y1070281D01*
G02X685844Y1070209I-200J1D01*
G03X685578Y1068787I3660J-1420D01*
G01Y1047860D01*
G02X685567Y1047796I-200J1D01*
G01X577868Y729610D01*
G02X577828Y729587I-119J161D01*
G01X577575Y729496D01*
X577573D01*
X577525Y729478D01*
G02X577443Y729465I-72J187D01*
G02X577417Y729468I10J200D01*
G01X577381Y729474D01*
X577348Y729495D01*
G03X576556Y729721I-792J-1275D01*
G03X575054Y728219I0J-1502D01*
G03X576412Y726724I1502J0D01*
G01X576448Y726721D01*
X576480Y726705D01*
G02X576559Y726636I-88J-180D01*
G01X576619Y726544D01*
Y726542D01*
X576705Y726409D01*
G02X576727Y726236I-167J-109D01*
G01X548170Y641867D01*
G03X548038Y641374I3719J-1260D01*
G01X545815Y630198D01*
G03X545744Y629625I3851J-768D01*
G01X545094Y616373D01*
G02X545091Y616349I-200J13D01*
G01X544076Y610535D01*
G03X544019Y609941I3834J-668D01*
G01X543959Y606800D01*
G02X543930Y606707I-200J11D01*
G01X543916Y606684D01*
X543893Y606662D01*
X543878Y606651D01*
G03X543860Y606638I870J-1223D01*
G01X543858Y606636D01*
G03X543268Y605443I911J-1193D01*
G03X543831Y604270I1503J0D01*
G01X543839Y604263D01*
X543865Y604237D01*
X543878Y604216D01*
G02X543907Y604108I-171J-104D01*
G01X543770Y596969D01*
X543532Y584576D01*
Y584570D01*
X543425Y582392D01*
X543405Y582354D01*
G03X543236Y581661I1334J-692D01*
G01Y581659D01*
G03X543354Y581074I1504J-1D01*
G01X543360Y581060D01*
X542986Y573435D01*
G02X542971Y573368I-200J10D01*
G01X537179Y559386D01*
G02X537013Y559264I-184J77D01*
G01X536606Y559225D01*
X536505Y559273D01*
X536494Y559291D01*
G03X536315Y559524I-1275J-794D01*
G01X536287Y559554D01*
X536274Y559588D01*
G02X536261Y559659I187J71D01*
G01Y559933D01*
G02X536272Y559999I200J1D01*
G02X536314Y560069I189J-66D01*
G01X536315Y560070D01*
G03Y562124I-1096J1027D01*
G01X536287Y562154D01*
X536274Y562188D01*
G02X536261Y562259I187J71D01*
G01Y562533D01*
G02X536272Y562599I200J1D01*
G02X536314Y562669I189J-66D01*
G01X536315Y562670D01*
G03X536721Y563697I-1096J1027D01*
G03X536132Y564890I-1503J0D01*
G01X536126Y564895D01*
X536101Y564920D01*
G02X536064Y564971I141J141D01*
G01X536027Y565044D01*
X536016Y565066D01*
X536005Y565111D01*
Y565359D01*
G02X536027Y565450I200J0D01*
G01X536064Y565523D01*
G02X536101Y565574I178J-90D01*
G01X536126Y565599D01*
X536132Y565604D01*
G03X536721Y566797I-914J1193D01*
G03X533717I-1502J0D01*
G01X533716D01*
G03X534301Y565607I1503J0D01*
G01X534312Y565599D01*
X534337Y565574D01*
G02X534374Y565523I-141J-141D01*
G01X534411Y565450D01*
X534422Y565428D01*
X534433Y565383D01*
Y565111D01*
X534422Y565066D01*
X534411Y565044D01*
X534374Y564971D01*
G02X534337Y564920I-178J90D01*
G01X534312Y564895D01*
X534306Y564890D01*
G03X533717Y563697I914J-1193D01*
G03X534123Y562670I1502J0D01*
G01X534124Y562669D01*
G02X534166Y562599I-147J-136D01*
G02X534177Y562533I-189J-65D01*
G01Y562259D01*
G02X534164Y562188I-200J0D01*
G01X534151Y562154D01*
X534123Y562124D01*
G03Y560070I1096J-1027D01*
G01X534124Y560069D01*
G02X534166Y559999I-147J-136D01*
G02X534177Y559933I-189J-65D01*
G01Y559659D01*
G02X534164Y559588I-200J0D01*
G01X534151Y559554D01*
X534123Y559524D01*
G03Y557470I1096J-1027D01*
G01X534124Y557469D01*
G02X534166Y557399I-147J-136D01*
G02X534177Y557333I-189J-65D01*
G01Y557059D01*
G02X534164Y556988I-200J0D01*
G01X534151Y556954D01*
X534123Y556924D01*
G03Y554870I1096J-1027D01*
G01X534124Y554869D01*
G02X534166Y554799I-147J-136D01*
G02X534177Y554733I-189J-65D01*
G01Y554459D01*
G02X534164Y554388I-200J0D01*
G01X534151Y554354D01*
X534123Y554324D01*
G03X534122Y552271I1096J-1027D01*
G02X534124Y552269I-140J-142D01*
G01X534151Y552239D01*
X534172Y552124D01*
X533239Y549874D01*
X533168Y549812D01*
X533122Y549801D01*
G03X532502Y549476I368J-1456D01*
G01X532500D01*
Y549475D01*
G02X532370Y549427I-130J152D01*
G01X532106D01*
G02X531976Y549475I0J200D01*
G01X531975Y549476D01*
G03X530001I-987J-1131D01*
G01X530000D01*
Y549475D01*
G02X529870Y549427I-130J152D01*
G01X529606D01*
G02X529476Y549475I0J200D01*
G01X529475Y549476D01*
G03X527501I-987J-1131D01*
G01X527500D01*
Y549475D01*
G02X527370Y549427I-130J152D01*
G01X527106D01*
G02X526976Y549475I0J200D01*
G01X526975Y549476D01*
G03X525988Y549846I-987J-1131D01*
G03X524486Y548344I0J-1502D01*
G03X524837Y547379I1502J0D01*
G01X524868Y547342D01*
X524890Y547250D01*
X524805Y546892D01*
G02X524690Y546755I-195J47D01*
G03X523786Y545377I598J-1378D01*
G03X524156Y544390I1501J0D01*
G01Y544389D01*
X524157D01*
G02X524205Y544259I-152J-130D01*
G01Y543995D01*
G02X524157Y543865I-200J0D01*
G01X524156Y543864D01*
G03Y541890I1131J-987D01*
G01Y541889D01*
X524157D01*
G02X524205Y541759I-152J-130D01*
G01Y541495D01*
G02X524157Y541365I-200J0D01*
G01X524156Y541364D01*
G03Y539390I1131J-987D01*
G01Y539389D01*
X524157D01*
G02X524205Y539259I-152J-130D01*
G01Y538995D01*
G02X524157Y538865I-200J0D01*
G01X524156Y538864D01*
G03X523786Y537877I1131J-987D01*
G03X526790I1502J0D01*
G03X526420Y538864I-1501J0D01*
G01Y538865D01*
X526419D01*
G02X526371Y538995I152J130D01*
G01Y539259D01*
G02X526419Y539389I200J0D01*
G01X526420Y539390D01*
G03Y541364I-1131J987D01*
G01Y541365D01*
X526419D01*
G02X526371Y541495I152J130D01*
G01Y541759D01*
G02X526419Y541889I200J0D01*
G01X526420Y541890D01*
G03Y543864I-1131J987D01*
G01Y543865D01*
X526419D01*
G02X526371Y543995I152J130D01*
G01Y544259D01*
G02X526419Y544389I200J0D01*
G01X526420Y544390D01*
G03X526790Y545377I-1131J987D01*
G03X526439Y546342I-1502J0D01*
G01X526408Y546379D01*
X526386Y546471D01*
X526471Y546829D01*
G02X526586Y546966I195J-47D01*
G03X526974Y547212I-601J1376D01*
G01X526976D01*
Y547213D01*
G02X527106Y547261I130J-152D01*
G01X527370D01*
G02X527500Y547213I0J-200D01*
G01X527501Y547212D01*
G03X529475I987J1131D01*
G01X529476D01*
Y547213D01*
G02X529606Y547261I130J-152D01*
G01X529870D01*
G02X530000Y547213I0J-200D01*
G01X530001Y547212D01*
G03X531975I987J1131D01*
G01X531976D01*
Y547213D01*
G02X532106Y547261I130J-152D01*
G01X532370D01*
G02X532500Y547213I0J-200D01*
G01X532501Y547212D01*
G03X532623Y547116I989J1131D01*
G02X532708Y546952I-115J-164D01*
G01Y521192D01*
G02X532558Y520998I-200J0D01*
G03Y518090I378J-1454D01*
G02X532708Y517896I-50J-194D01*
G01Y514625D01*
G03X532878Y513485I3927J3D01*
G01X556042Y437127D01*
G03X556171Y436764I3760J1132D01*
G01X564521Y416604D01*
G03X565373Y415330I3627J1504D01*
G01X567209Y413494D01*
X567221Y413474D01*
G03X567269Y413397I3326J2020D01*
G03X567796Y412741I3280J2095D01*
G01X587211Y393326D01*
G03X587867Y392799I2751J2753D01*
G03X588474Y392483I2093J3280D01*
G01X597933Y388566D01*
G03X599135Y388281I1487J3595D01*
G02X599155Y388278I-20J-199D01*
G03X599826Y388220I672J3868D01*
G01X602926D01*
G02X603064Y388164I-1J-200D01*
G03X605778Y387074I2715J2837D01*
G03X609143Y388979I0J3924D01*
G02X609193Y389034I170J-105D01*
G03X609776Y390222I-919J1188D01*
G01Y390225D01*
G03X609706Y390680I-1502J2D01*
G02X609697Y390753I190J61D01*
G03X609704Y391001I-3919J235D01*
G03X609355Y392619I-3927J0D01*
G02Y392783I183J82D01*
G03X609704Y394401I-3578J1618D01*
G03X609697Y394652I-3927J16D01*
G02X609705Y394723I199J13D01*
G03X609724Y394788I-1432J454D01*
G01Y394790D01*
G03X609766Y395003I-1448J396D01*
G01X609771Y395051D01*
G03X609777Y395179I-1497J134D01*
G03X609187Y396372I-1501J0D01*
G03X609185Y396374I-141J-139D01*
G03X609164Y396389I-884J-1215D01*
G03X605778Y398328I-3386J-1987D01*
G03X603063Y397238I0J-3926D01*
G01X603034Y397210D01*
X602964Y397182D01*
X601895D01*
G02X601891Y397186I139J143D01*
G01X601822Y397266D01*
G02X601786Y397324I149J133D01*
G01X601775Y397353D01*
X601773Y397389D01*
G03X601772Y397419I-1502J-35D01*
G01Y397423D01*
G03X601704Y397791I-1500J-87D01*
G02X601695Y397864I190J61D01*
G03X601702Y398113I-3919J235D01*
G03X601353Y399731I-3927J0D01*
G02Y399895I183J82D01*
G03X601702Y401513I-3578J1618D01*
G03X601695Y401763I-3926J15D01*
G02X601704Y401836I199J12D01*
G03X601751Y402026I-1432J455D01*
G01Y402028D01*
G03X601756Y402057I-1478J270D01*
G01Y402059D01*
G03X601768Y402153I-1483J237D01*
G01Y402154D01*
X601771Y402184D01*
X601820Y402302D01*
X601842Y402327D01*
X601885Y402375D01*
G02X601887Y402377I142J-140D01*
G02X601902Y402392I149J-134D01*
G01X602925D01*
G02X603063Y402337I0J-200D01*
G03X605776Y401248I2714J2837D01*
G01X605778D01*
G03X609144Y403153I0J3926D01*
G02X609193Y403208I171J-103D01*
G03X609776Y404396I-919J1188D01*
G01Y404398D01*
G03X609706Y404853I-1502J2D01*
G02X609697Y404926I190J61D01*
G03X609704Y405174I-3919J235D01*
G03X609355Y406792I-3927J0D01*
G02Y406956I183J82D01*
G03X609704Y408574I-3578J1618D01*
G03X609697Y408825I-3927J16D01*
G02X609705Y408896I199J13D01*
G03X609724Y408961I-1432J454D01*
G01Y408963D01*
G03X609766Y409176I-1448J396D01*
G01X609771Y409224D01*
G03X609777Y409352I-1497J134D01*
G03X609187Y410545I-1501J0D01*
G03X609185Y410547I-141J-139D01*
G03X609164Y410562I-884J-1215D01*
G03X605778Y412500I-3386J-1989D01*
G01X605777D01*
G03X603234Y411565I0J-3926D01*
G02X603031Y411531I-130J152D01*
G03X601588Y411806I-1444J-3652D01*
G01X599688D01*
G03X599575Y411804I13J-3927D01*
G01X599533Y411803D01*
X599455Y411834D01*
X599334Y411961D01*
X599324Y411971D01*
X599296Y412049D01*
X599298Y412090D01*
G03X599302Y412287I-3922J178D01*
G03X598953Y413905I-3927J0D01*
G02Y414069I183J82D01*
G03X599302Y415687I-3578J1618D01*
G03X599295Y415937I-3926J15D01*
G02X599304Y416010I199J12D01*
G03X599331Y416107I-1433J451D01*
G03X599368Y416326I-1459J359D01*
G01X599371Y416359D01*
X599408Y416445D01*
X599409Y416447D01*
X599422Y416477D01*
X599481Y416546D01*
G02X599501Y416566I151J-131D01*
G01X602926D01*
G02X603064Y416510I-1J-200D01*
G03X605778Y415420I2715J2837D01*
G03X609143Y417325I0J3924D01*
G02X609193Y417380I170J-105D01*
G03X609776Y418568I-919J1188D01*
G01Y418571D01*
G03X609706Y419026I-1502J2D01*
G02X609697Y419099I190J61D01*
G03X609704Y419347I-3919J235D01*
G03X609355Y420965I-3927J0D01*
G02Y421129I183J82D01*
G03X609704Y422747I-3578J1618D01*
G03X609697Y422998I-3927J16D01*
G02X609705Y423069I199J13D01*
G03X609724Y423134I-1432J454D01*
G01Y423136D01*
G03X609766Y423349I-1448J396D01*
G01X609771Y423397D01*
G03X609777Y423525I-1497J134D01*
G03X609187Y424718I-1501J0D01*
G03X609185Y424720I-141J-139D01*
G03X609164Y424735I-884J-1215D01*
G03X605778Y426674I-3386J-1987D01*
G03X603230Y425734I1J-3927D01*
G02X603027Y425701I-129J153D01*
G03X601577Y425978I-1449J-3650D01*
G01X599677D01*
G03X599573Y425977I-14J-3926D01*
G02X599424Y426038I-5J200D01*
G01X599319Y426147D01*
G02X599293Y426181I145J138D01*
G01X599297Y426260D01*
G03X599302Y426456I-3921J198D01*
G01Y426460D01*
G03X598953Y428078I-3927J0D01*
G02Y428242I183J82D01*
G03X599302Y429860I-3578J1618D01*
G03X599295Y430110I-3926J15D01*
G02X599304Y430183I199J12D01*
G03X599351Y430373I-1432J455D01*
G01Y430375D01*
G03X599356Y430404I-1478J270D01*
G01Y430406D01*
G03X599368Y430500I-1483J237D01*
G01Y430501D01*
X599371Y430531D01*
X599418Y430647D01*
X599441Y430673D01*
X599484Y430722D01*
G02X599502Y430740I150J-132D01*
G01X602926D01*
G02X603064Y430684I-1J-200D01*
G03X605778Y429594I2715J2837D01*
G03X609143Y431499I0J3924D01*
G02X609193Y431554I170J-105D01*
G03X609776Y432742I-919J1188D01*
G01Y432745D01*
G03X609706Y433200I-1502J2D01*
G02X609697Y433273I190J61D01*
G03X609704Y433521I-3919J235D01*
G03X609355Y435139I-3927J0D01*
G02Y435303I183J82D01*
G03X609704Y436921I-3578J1618D01*
G03X609697Y437172I-3927J16D01*
G02X609705Y437243I199J13D01*
G03X609724Y437308I-1432J454D01*
G01Y437310D01*
G03X609766Y437523I-1448J396D01*
G01X609771Y437571D01*
G03X609777Y437699I-1497J134D01*
G03X609187Y438892I-1501J0D01*
G03X609185Y438894I-141J-139D01*
G03X609164Y438909I-884J-1215D01*
G03X605778Y440848I-3386J-1987D01*
G03X603318Y439981I1J-3927D01*
G02X603129Y439948I-125J156D01*
G03X601880Y440152I-1249J-3722D01*
G01X599977D01*
G03X599531Y440127I-4J-3926D01*
G02X599316Y440270I-23J199D01*
G03X599304Y440311I-1448J-401D01*
G02X599295Y440384I190J61D01*
G03X599302Y440633I-3919J235D01*
G03X598953Y442251I-3927J0D01*
G02Y442415I183J82D01*
G03X599302Y444033I-3578J1618D01*
G03X599295Y444284I-3927J16D01*
G02X599303Y444355I199J13D01*
G03X599322Y444420I-1432J454D01*
G01Y444422D01*
G03X599364Y444635I-1448J396D01*
G01X599369Y444683D01*
G03X599375Y444811I-1497J134D01*
G03X598785Y446004I-1501J0D01*
G03X598783Y446006I-141J-139D01*
G03X598762Y446021I-884J-1215D01*
G03X595376Y447960I-3386J-1987D01*
G03X594439Y447846I2J-3927D01*
G02X594293Y447866I-48J195D01*
G01X594190Y447925D01*
G02X594097Y448039I98J175D01*
G03X593980Y448361I-3746J-1179D01*
G01X593328Y449932D01*
G03X592735Y450919I-3626J-1507D01*
G02X592691Y451027I155J126D01*
G03X592411Y452146I-3908J-383D01*
G01X591760Y453718D01*
G03X591099Y454787I-3627J-1504D01*
G03X591100Y454794I-3848J553D01*
G03X590801Y456295I-3927J-2D01*
G01X590055Y458098D01*
G03X589312Y459260I-3628J-1501D01*
G02X589260Y459388I148J135D01*
G03X588964Y460730I-3923J-162D01*
G01X588218Y462533D01*
G03X587475Y463695I-3628J-1501D01*
G02X587423Y463823I148J135D01*
G03X587127Y465165I-3923J-162D01*
G01X586381Y466968D01*
G03X585638Y468130I-3628J-1501D01*
G02X585586Y468258I148J135D01*
G03X585290Y469600I-3923J-162D01*
G01X584734Y470945D01*
G02X584808Y471188I185J77D01*
G01X584867Y471228D01*
X585009Y471214D01*
X588428Y467795D01*
G03X589091Y467263I2752J2751D01*
G02X589095Y467261I-87J-179D01*
G03X591265Y466606I2171J3271D01*
G01X592524D01*
G02X592662Y466550I-1J-200D01*
G03X595376Y465460I2715J2837D01*
G03X598741Y467365I0J3924D01*
G02X598791Y467420I170J-105D01*
G03X599374Y468608I-919J1188D01*
G01Y468611D01*
G03X599304Y469066I-1502J2D01*
G02X599295Y469139I190J61D01*
G03X599302Y469387I-3919J235D01*
G03X598953Y471005I-3927J0D01*
G02Y471169I183J82D01*
G03X599302Y472787I-3578J1618D01*
G03X599295Y473036I-3926J14D01*
G02X599304Y473109I199J12D01*
G03X599372Y473477I-1432J455D01*
G01Y473481D01*
G03X599373Y473511I-1501J65D01*
G01X599375Y473547D01*
X599399Y473609D01*
X599420Y473634D01*
X599459Y473678D01*
X599462Y473681D01*
X599473Y473694D01*
G02X599496Y473718I155J-126D01*
G01X602926D01*
G02X603064Y473662I-1J-200D01*
G03X605778Y472572I2715J2837D01*
G03X609143Y474477I0J3924D01*
G02X609193Y474532I170J-105D01*
G03X609776Y475720I-919J1188D01*
G01Y475723D01*
G03X609706Y476178I-1502J2D01*
G02X609697Y476251I190J61D01*
G03X609704Y476499I-3919J235D01*
G03X609355Y478117I-3927J0D01*
G02Y478281I183J82D01*
G03X609704Y479899I-3578J1618D01*
G03X609697Y480150I-3927J16D01*
G02X609705Y480221I199J13D01*
G03X609724Y480286I-1432J454D01*
G01Y480288D01*
G03X609766Y480501I-1448J396D01*
G01X609771Y480549D01*
G03X609777Y480677I-1497J134D01*
G03X609187Y481870I-1501J0D01*
G03X609185Y481872I-141J-139D01*
G03X609164Y481887I-884J-1215D01*
G03X605778Y483826I-3386J-1987D01*
G03X603063Y482736I0J-3926D01*
G01X603034Y482708D01*
X602964Y482680D01*
X602848D01*
X602810Y482697D01*
G03X601228Y483030I-1582J-3593D01*
G01X599531D01*
G02X599519Y483042I135J147D01*
G01X599313Y483259D01*
X599302Y483277D01*
X599294Y483290D01*
Y483291D01*
X599298Y483365D01*
G03X599302Y483560I-3922J178D01*
G03X598953Y485178I-3927J0D01*
G02Y485342I183J82D01*
G03X599302Y486960I-3578J1618D01*
G03X599295Y487209I-3926J14D01*
G02X599304Y487282I199J12D01*
G03X599374Y487737I-1432J453D01*
G01Y487744D01*
G03X599337Y488071I-1502J-4D01*
G02X599334Y488146I195J45D01*
G02X599370Y488233I198J-31D01*
G01X599390Y488259D01*
X599497Y488344D01*
G02X599668Y488382I125J-157D01*
G01X599718Y488370D01*
X599739Y488359D01*
G03X600432Y488089I1753J3475D01*
G03X601264Y487949I1058J3745D01*
G02X601286Y487946I-16J-199D01*
G03X601939Y487892I649J3872D01*
G01X602964D01*
X603034Y487864D01*
X603063Y487836D01*
G03X605778Y486746I2715J2836D01*
G03X609143Y488651I0J3924D01*
G02X609193Y488706I170J-105D01*
G03X609776Y489894I-919J1188D01*
G01Y489897D01*
G03X609706Y490352I-1502J2D01*
G02X609697Y490425I190J61D01*
G03X609704Y490673I-3919J235D01*
G03X609355Y492291I-3927J0D01*
G02Y492455I183J82D01*
G03X609704Y494073I-3578J1618D01*
G03X609697Y494324I-3927J16D01*
G02X609705Y494395I199J13D01*
G03X609724Y494460I-1432J454D01*
G01Y494462D01*
G03X609766Y494675I-1448J396D01*
G01X609771Y494723D01*
G03X609777Y494851I-1497J134D01*
G03X609187Y496044I-1501J0D01*
G03X609185Y496046I-141J-139D01*
G03X609164Y496061I-884J-1215D01*
G03X605778Y498000I-3386J-1987D01*
G03X603787Y497456I3J-3926D01*
G01X603785D01*
X603727Y497422D01*
G02X603678Y497425I-12J200D01*
G01X603578Y497448D01*
G02X603457Y497528I42J196D01*
G03X603393Y497616I-3179J-2245D01*
G03X603034Y498030I-3112J-2336D01*
G01X601803Y499261D01*
G03X601533Y499507I-2753J-2751D01*
G01X601511Y499525D01*
X599955Y501853D01*
X599948Y501895D01*
G03X599346Y503396I-3867J-680D01*
G01X599312Y503446D01*
G03X599964Y504684I-849J1238D01*
G03X598462Y506186I-1502J0D01*
G01X598461D01*
G03X597838Y506050I1J-1501D01*
G01X597836D01*
X597821Y506043D01*
X597740Y506042D01*
X597437Y506164D01*
G02X597327Y506274I75J185D01*
G03X596957Y506970I-3634J-1486D01*
G01X596011Y508385D01*
G03X595561Y508941I-3264J-2182D01*
G02X595516Y509148I143J140D01*
G01X595638Y509487D01*
G02X595804Y509618I188J-68D01*
G03X598741Y511499I-429J3903D01*
G02X598791Y511554I170J-105D01*
G03X599374Y512742I-919J1188D01*
G01Y512745D01*
G03X599304Y513200I-1502J2D01*
G02X599295Y513273I190J61D01*
G03X599302Y513521I-3919J235D01*
G03X598953Y515139I-3927J0D01*
G02Y515303I183J82D01*
G03X599302Y516921I-3578J1618D01*
G03X599295Y517170I-3926J14D01*
G02X599304Y517243I199J12D01*
G03X599328Y517327I-1432J455D01*
G03X599374Y517657I-1456J371D01*
G02X599574Y517852I200J-5D01*
G01X602926D01*
G02X603064Y517796I-1J-200D01*
G03X605778Y516706I2715J2837D01*
G03X609143Y518611I0J3924D01*
G02X609193Y518666I170J-105D01*
G03X609776Y519854I-919J1188D01*
G01Y519857D01*
G03X609706Y520312I-1502J2D01*
G02X609697Y520385I190J61D01*
G03X609704Y520633I-3919J235D01*
G03X609355Y522251I-3927J0D01*
G02Y522415I183J82D01*
G03X609704Y524033I-3578J1618D01*
G03X609697Y524284I-3927J16D01*
G02X609705Y524355I199J13D01*
G03X609724Y524420I-1432J454D01*
G01Y524422D01*
G03X609766Y524635I-1449J396D01*
G01X609771Y524683D01*
G03X609777Y524811I-1497J134D01*
G03X609187Y526004I-1501J0D01*
G03X609185Y526006I-141J-139D01*
G03X609164Y526021I-884J-1215D01*
G03X605778Y527960I-3386J-1987D01*
G03X603063Y526870I0J-3926D01*
G01X603034Y526842D01*
X602964Y526814D01*
X602451D01*
G02X602360Y526836I0J200D01*
G03X600666Y527263I-1783J-3498D01*
G01X600629Y527264D01*
X600006Y527523D01*
G03X599591Y527669I-1497J-3592D01*
G03X599477Y527700I-1078J-3739D01*
G01X599446Y527708D01*
X599421Y527724D01*
G02X599372Y527766I104J171D01*
G01X599346Y527798D01*
X599341Y527804D01*
G02X599296Y527919I155J127D01*
G03X598953Y529312I-3920J-226D01*
G02Y529476I183J82D01*
G03X599302Y531094I-3578J1618D01*
G03X599295Y531342I-3926J13D01*
G02X599304Y531415I199J12D01*
G03X599374Y531870I-1432J453D01*
G01Y531872D01*
G03X599344Y532169I-1502J-2D01*
G02X599354Y532284I196J41D01*
G01X599364Y532308D01*
X599398Y532352D01*
X599669Y532549D01*
G02X599671Y532551I141J-139D01*
G01X599711Y532579D01*
G02X599732Y532592I116J-164D01*
G01X599733D01*
G02X599736Y532593I64J-186D01*
G01X599845Y532532D01*
G03X601775Y532024I1932J3419D01*
G01X602926D01*
G02X603064Y531969I0J-200D01*
G03X605777Y530880I2714J2837D01*
G01X605778D01*
G03X609144Y532785I0J3926D01*
G02X609193Y532840I171J-103D01*
G03X609776Y534028I-919J1188D01*
G01Y534030D01*
G03X609706Y534485I-1502J2D01*
G02X609697Y534558I190J61D01*
G03X609704Y534806I-3919J235D01*
G03X609355Y536424I-3927J0D01*
G02Y536588I183J82D01*
G03X609704Y538206I-3578J1618D01*
G03X609697Y538457I-3926J16D01*
G02X609705Y538528I199J13D01*
G03X609724Y538593I-1432J454D01*
G01Y538595D01*
G03X609766Y538808I-1449J396D01*
G01X609771Y538856D01*
G03X609777Y538984I-1497J134D01*
G03X609187Y540177I-1501J0D01*
G03X609185Y540179I-141J-139D01*
G03X609164Y540194I-884J-1215D01*
G03X608588Y540949I-3387J-1987D01*
G02X608531Y541091I143J140D01*
G01X608532Y541371D01*
G02X608591Y541511I200J-2D01*
G01X608819Y541740D01*
G03X609670Y543013I-2776J2777D01*
G01X611465Y547345D01*
G03X611689Y548084I-3627J1503D01*
G01X611834Y548809D01*
X611851Y548849D01*
X611865Y548867D01*
G03X612567Y550449I-3150J2344D01*
G01X612937Y552314D01*
G03X613012Y553077I-3851J764D01*
G01Y553078D01*
G03X612978Y553594I-3951J-1D01*
G02X613007Y553727I198J26D01*
G03X613532Y555049I-3326J2086D01*
G01X613912Y556963D01*
G03X613988Y557728I-3851J769D01*
G03X613940Y558339I-3927J-1D01*
G02X613967Y558475I198J31D01*
G03X614468Y559758I-3350J2048D01*
G01X614618Y560511D01*
X614681Y560587D01*
X614709Y560599D01*
G03X615678Y562003I-533J1404D01*
G03X615100Y563187I-1502J0D01*
G02X615045Y563436I123J158D01*
G03X615404Y564467I-3493J1794D01*
G01X615784Y566381D01*
G03X615860Y567146I-3851J769D01*
G03X615811Y567758I-3926J-6D01*
G02X615838Y567894I198J31D01*
G03X616339Y569176I-3350J2048D01*
G01X616719Y571090D01*
G03X616794Y571855I-3851J764D01*
G03X616746Y572467I-3926J0D01*
G02X616773Y572603I198J31D01*
G03X617274Y573885I-3350J2048D01*
G01X617654Y575799D01*
G03X617730Y576564I-3851J769D01*
G03X617681Y577176I-3926J-6D01*
G02X617708Y577312I198J31D01*
G03X618209Y578594I-3350J2048D01*
G01X618589Y580508D01*
G03X618664Y581273I-3851J764D01*
G03X618586Y582052I-3926J0D01*
G02X618603Y582180I196J39D01*
G03X618939Y583166I-3516J1748D01*
G01X619387Y585424D01*
G03X619462Y586188I-3851J764D01*
G03X619405Y586856I-3926J1D01*
G01X619399Y586893D01*
X647489Y728343D01*
G02X647496Y728368I196J-41D01*
G01X724792Y956706D01*
G02X724931Y956835I189J-65D01*
G03X726008Y957937I-384J1452D01*
G02X726310Y958059I194J-47D01*
G03X727116Y957824I807J1267D01*
G03Y960828I0J1502D01*
G03X726813Y960797I1J-1502D01*
G01X726812D01*
G02X726623Y960860I-40J196D01*
G01X726393Y961120D01*
G02X726353Y961317I150J133D01*
G01X745245Y1017126D01*
G02X745434Y1017262I189J-64D01*
G01X747817D01*
G02X747964Y1017197I-1J-200D01*
G01X747965D01*
G02X748016Y1017044I-148J-134D01*
G01X743940Y970450D01*
G02X743938Y970436I-199J21D01*
G01X741086Y952531D01*
G02X741065Y952468I-198J31D01*
G01X741057Y952453D01*
G03X741035Y952362I178J-91D01*
G01Y952218D01*
G02X741033Y952186I-200J-4D01*
G01X738831Y938372D01*
X734272Y909747D01*
X734081Y908549D01*
X734052Y908369D01*
Y908364D01*
X734047Y908336D01*
G03X733987Y907658I3833J-681D01*
G01Y907657D01*
G03X733996Y907406I3893J14D01*
G01X735047Y891138D01*
X735049Y891110D01*
X735038Y891058D01*
X735033Y891044D01*
G03X734956Y890697I1419J-497D01*
G03X734951Y890632I1496J-148D01*
G01Y890616D01*
X734950Y890607D01*
Y890584D01*
G03X734949Y890549I1502J-60D01*
G01Y890547D01*
G03X735113Y889866I1503J2D01*
G01X735132Y889829D01*
X735877Y878317D01*
Y878287D01*
X734985Y868099D01*
G03X734970Y867757I3912J-343D01*
G03X734985Y867415I3927J1D01*
G01X735147Y865567D01*
X735107Y865475D01*
X735068Y865444D01*
G03X734498Y864266I932J-1178D01*
G01Y864265D01*
G03X734818Y863338I1504J0D01*
G02X734768Y863046I-157J-123D01*
G03X734074Y861780I808J-1266D01*
G03X735576Y860278I1502J0D01*
G01X735610D01*
X741130Y797182D01*
Y797178D01*
X741145Y796951D01*
X741699Y788382D01*
X741838Y786231D01*
X742380Y777837D01*
G02X742328Y777689I-200J-13D01*
G01X742197Y777546D01*
X742196Y777545D01*
X742133Y777477D01*
X742131Y777475D01*
X742127Y777471D01*
G02X742062Y777426I-144J139D01*
G01X742026Y777411D01*
X741985D01*
G03X740491Y775909I8J-1502D01*
G03X741993Y774407I1502J0D01*
G03X742165Y774417I-1J1502D01*
G01X742177Y774418D01*
X742208D01*
G02X742325Y774378I-3J-200D01*
G01X742554Y774189D01*
X742556Y774187D01*
X742588Y774160D01*
X742624Y774088D01*
X742627Y774038D01*
X742628Y774024D01*
X742629Y773997D01*
Y773983D01*
G02X742584Y773866I-200J10D01*
G01X742558Y773835D01*
X742531Y773818D01*
G03X741765Y772418I896J-1400D01*
G03X742651Y770948I1662J0D01*
G01X742678Y770934D01*
X742700Y770922D01*
X742715Y770911D01*
G02X742758Y770864I-124J-157D01*
G01X742811Y770784D01*
G02X742830Y770747I-167J-109D01*
G01X742842Y770717D01*
X742859Y770449D01*
X742901Y769803D01*
Y769802D01*
X742905Y769747D01*
X742880Y769698D01*
G02X742806Y769619I-177J92D01*
G01X742683Y769543D01*
X742668Y769534D01*
X742576Y769525D01*
X742532Y769542D01*
G03X742000Y769639I-531J-1405D01*
G03X741879Y769634I1J-1502D01*
G02X741826Y769637I-15J200D01*
G03X741540Y769664I-286J-1502D01*
G01X741539D01*
G03Y766610I0J-1527D01*
G03X741826Y766637I1J1528D01*
G02X741879Y766640I38J-197D01*
G03X742000Y766635I122J1497D01*
G03X742757Y766840I0J1502D01*
G02X742943Y766849I102J-172D01*
G01X742989Y766827D01*
G02X743104Y766660I-84J-181D01*
G01X743111Y766562D01*
Y766560D01*
X743124Y766357D01*
X743196Y765219D01*
Y765192D01*
X743195Y765189D01*
G02X743107Y765042I-199J19D01*
G01X742923Y764920D01*
X742921D01*
X742856Y764876D01*
X742854D01*
X742836Y764863D01*
X742785Y764845D01*
X742758Y764843D01*
G02X742654Y764865I-12J200D01*
G01X742607Y764889D01*
G03X741916Y765053I-692J-1376D01*
G01X741915D01*
G03Y761971I0J-1541D01*
G01X741916D01*
G03X742100Y761982I0J1540D01*
G02X742109Y761983I27J-198D01*
G03X742851Y762248I-116J1497D01*
G01X742867Y762259D01*
G02X742982Y762296I116J-163D01*
G01X742986D01*
X743090Y762246D01*
X743092D01*
X743293Y762150D01*
G02X743324Y762133I-80J-183D01*
G02X743407Y761982I-117J-163D01*
G01X743593Y759113D01*
X743628Y758570D01*
X743897Y754418D01*
X747196Y703455D01*
G03X747355Y702575I3884J247D01*
G01X753895Y681038D01*
G02X753897Y681032I-189J-66D01*
G01X756095Y672827D01*
G03X756487Y671880I3793J1015D01*
G01X783678Y624781D01*
X783683Y624740D01*
G03X784186Y623200I3903J423D01*
G01X785162Y621510D01*
G03X785972Y620522I3401J1962D01*
G02X786037Y620411I-131J-151D01*
G03X786487Y619215I3851J766D01*
G01X786863Y618565D01*
G02X786882Y618409I-173J-100D01*
G01X786799Y618131D01*
G02X786698Y618009I-192J56D01*
G03X785116Y616534I1783J-3498D01*
G02X785067Y616479I-171J103D01*
G03X784483Y615291I918J-1189D01*
G01Y615263D01*
G03X784486Y615189I1502J24D01*
G01X784487Y615182D01*
Y615174D01*
X784492Y615103D01*
G03X784493Y615092I199J13D01*
G01X784495Y615081D01*
X784505Y615030D01*
X784506Y615024D01*
G03X784553Y614834I1479J265D01*
G02X784562Y614760I-190J-61D01*
G03X784554Y614511I3919J-251D01*
G03X784903Y612893I3927J0D01*
G02Y612729I-182J-82D01*
G03X784554Y611112I3578J-1618D01*
G01Y611110D01*
G03X784556Y611006I3927J23D01*
G01Y611004D01*
X784558Y610926D01*
G02X784540Y610903I-166J111D01*
G01X784403Y610762D01*
G02X784401Y610760I-142J140D01*
G01X784329Y610688D01*
G02X784262Y610644I-141J142D01*
G01X784228Y610630D01*
X783212D01*
G03X781963Y610424I0J-3892D01*
G01X781959Y610423D01*
X781942Y610418D01*
X781932Y610415D01*
X781922Y610413D01*
G03X781897Y610408I750J-3817D01*
G01X781876Y610403D01*
X781873Y610402D01*
G03X781863Y610400I758J-3817D01*
G01X781862D01*
G03X781495Y610306I781J-3813D01*
G03X781179Y610195I1131J-3725D01*
G01X781167Y610190D01*
G03X781143Y610180I1485J-3598D01*
G01X780893D01*
X780823Y610208D01*
X780794Y610236D01*
G03X778079Y611326I-2715J-2836D01*
G03X774714Y609422I0J-3926D01*
G02X774664Y609367I-170J105D01*
G03X774081Y608179I920J-1188D01*
G01Y608151D01*
G03X774084Y608077I1502J24D01*
G01X774085Y608070D01*
Y608062D01*
X774090Y607991D01*
G03X774091Y607980I199J13D01*
G01X774093Y607969D01*
X774103Y607918D01*
X774104Y607912D01*
G03X774151Y607722I1479J265D01*
G02X774160Y607648I-190J-61D01*
G03X774152Y607399I3919J-251D01*
G03X774501Y605781I3927J0D01*
G02Y605617I-182J-82D01*
G03X774152Y604000I3578J-1618D01*
G01Y603998D01*
G03X774155Y603860I3927J16D01*
G02X774144Y603785I-200J-9D01*
G03X774153Y602759I1415J-501D01*
G01X774157Y602747D01*
X774173Y602698D01*
G03X774185Y602672I187J70D01*
G01X774186Y602670D01*
G03X774201Y602633I1400J546D01*
G01X774205Y602621D01*
X774213Y602605D01*
G03X774548Y602131I1371J614D01*
G03X774664Y602031I1038J1087D01*
G02X774714Y601976I-120J-160D01*
G03X778079Y600072I3365J2022D01*
G03X780793Y601162I-1J3927D01*
G02X780931Y601218I139J-144D01*
G01X784354D01*
G02X784364Y601209I-129J-153D01*
G01X784374Y601199D01*
X784420Y601147D01*
X784436Y601129D01*
X784458Y601104D01*
X784485Y601040D01*
X784487Y601005D01*
G03X784522Y600773I1498J107D01*
G03X784554Y600656I1464J338D01*
G02X784562Y600583I-191J-58D01*
G03X784554Y600338I3919J-251D01*
G03X784903Y598720I3927J0D01*
G02Y598556I-182J-82D01*
G03X784554Y596938I3578J-1618D01*
G03X784562Y596693I3927J6D01*
G02X784553Y596620I-199J-12D01*
G03X784509Y596443I1434J-450D01*
G01Y596442D01*
X784500Y596396D01*
X784473Y596360D01*
G02X784406Y596302I-161J118D01*
G01X784394Y596295D01*
X784376Y596286D01*
X784358Y596280D01*
G03X784095Y596188I1152J-3717D01*
G01X784093D01*
G03X784047Y596169I1463J-3606D01*
G03X783750Y596033I1470J-3603D01*
G03X783740Y596028I1735J-3483D01*
G02X783649Y596006I-91J178D01*
G01X780931D01*
G02X780793Y596062I1J200D01*
G03X778079Y597152I-2715J-2837D01*
G03X774714Y595248I0J-3926D01*
G02X774664Y595193I-170J105D01*
G03X774081Y594005I920J-1188D01*
G01Y593977D01*
G03X774084Y593903I1502J24D01*
G01X774085Y593896D01*
Y593888D01*
X774090Y593817D01*
G03X774091Y593806I199J13D01*
G01X774093Y593795D01*
X774103Y593744D01*
X774104Y593738D01*
G03X774151Y593548I1479J265D01*
G02X774160Y593474I-190J-61D01*
G03X774152Y593225I3919J-251D01*
G03X774501Y591607I3927J0D01*
G02Y591443I-182J-82D01*
G03X774152Y589826I3578J-1618D01*
G01Y589824D01*
G03X774155Y589686I3927J16D01*
G02X774144Y589611I-200J-9D01*
G03X774153Y588585I1415J-501D01*
G01X774157Y588573D01*
X774173Y588524D01*
G03X774185Y588498I187J70D01*
G01X774186Y588496D01*
G03X774201Y588459I1400J546D01*
G01X774205Y588447D01*
X774213Y588431D01*
G03X774548Y587957I1371J614D01*
G03X774664Y587857I1038J1087D01*
G02X774714Y587802I-120J-160D01*
G03X778079Y585898I3365J2022D01*
G03X780793Y586988I-1J3927D01*
G02X780931Y587044I139J-144D01*
G01X784355D01*
G02X784373Y587026I-132J-150D01*
G01X784416Y586977D01*
X784438Y586952D01*
X784486Y586837D01*
X784489Y586806D01*
Y586805D01*
G03X784553Y586485I1497J133D01*
G02X784562Y586412I-190J-61D01*
G03X784554Y586165I3919J-251D01*
G03X784903Y584547I3927J0D01*
G02Y584383I-182J-82D01*
G03X784554Y582765I3578J-1618D01*
G03X784556Y582649I3927J10D01*
G01X784558Y582593D01*
X784532Y582537D01*
X784511Y582515D01*
X784507Y582511D01*
X784415Y582417D01*
X784328Y582328D01*
G02X784215Y582275I-137J146D01*
G02X784191Y582274I-20J199D01*
G01X782822D01*
G03X782069Y582200I2J-3891D01*
G03X782020Y582190I754J-3817D01*
G03X781771Y582129I801J-3808D01*
G03X781067Y581856I1048J-3748D01*
G02X781065Y581854I-135J133D01*
G02X780977Y581834I-87J180D01*
G01X780932D01*
G02X780794Y581889I0J200D01*
G03X778079Y582978I-2714J-2837D01*
G03X774713Y581074I-1J-3926D01*
G02X774664Y581019I-171J103D01*
G03X774081Y579846I919J-1188D01*
G01Y579810D01*
G03X774151Y579372I1503J16D01*
G02X774160Y579299I-190J-61D01*
G03X774152Y579052I3919J-251D01*
G03X774501Y577434I3927J0D01*
G02Y577270I-182J-82D01*
G03X774152Y575652I3578J-1618D01*
G03X774160Y575402I3927J1D01*
G02X774152Y575329I-199J-15D01*
G03X774130Y575254I1429J-460D01*
G03X774082Y574938I1453J-382D01*
G01X774081Y574914D01*
Y574865D01*
G03X774665Y573684I1504J9D01*
G02X774714Y573629I-122J-158D01*
G03X778079Y571726I3365J2024D01*
G01X778080D01*
G03X780793Y572815I-1J3926D01*
G02X780931Y572870I138J-145D01*
G01X784356D01*
G02X784372Y572854I-133J-149D01*
G01X784443Y572776D01*
X784456Y572736D01*
X784487Y572660D01*
X784489Y572630D01*
G03X784492Y572601I1496J140D01*
G03X784553Y572311I1494J163D01*
G02X784562Y572238I-190J-61D01*
G03X784554Y571991I3919J-251D01*
G03X784903Y570373I3927J0D01*
G02Y570209I-182J-82D01*
G03X784554Y568591I3578J-1618D01*
G03X784562Y568344I3927J4D01*
G02X784553Y568271I-199J-12D01*
G03X784483Y567816I1433J-453D01*
G01Y567807D01*
G03X784546Y567379I1502J3D01*
G01X784550Y567366D01*
X784561Y567300D01*
X784555Y567266D01*
X784539Y567174D01*
G02X784498Y567082I-197J33D01*
G01X784410Y566958D01*
X784341Y566860D01*
G02X784314Y566834I-152J131D01*
G03X784312Y566832I140J-142D01*
G02X784304Y566826I-124J157D01*
G01X783931D01*
G02X783854Y566841I-1J200D01*
G01X782598Y567362D01*
G03X781099Y567660I-1500J-3628D01*
G01X780893D01*
X780823Y567688D01*
X780794Y567716D01*
G03X778079Y568806I-2715J-2836D01*
G03X774714Y566902I0J-3926D01*
G02X774664Y566847I-170J105D01*
G03X774081Y565659I920J-1188D01*
G01Y565631D01*
G03X774084Y565557I1502J24D01*
G01X774085Y565550D01*
Y565542D01*
X774090Y565471D01*
G03X774091Y565460I199J13D01*
G01X774093Y565449D01*
X774103Y565398D01*
X774104Y565392D01*
G03X774151Y565202I1479J265D01*
G02X774160Y565128I-190J-61D01*
G03X774152Y564879I3919J-251D01*
G03X774501Y563261I3927J0D01*
G02Y563097I-182J-82D01*
G03X774152Y561480I3578J-1618D01*
G01Y561478D01*
G03X774155Y561340I3927J16D01*
G02X774144Y561265I-200J-9D01*
G03X774153Y560239I1415J-501D01*
G01X774157Y560227D01*
X774173Y560178D01*
G03X774181Y560159I188J68D01*
G02X774189Y560142I-177J-94D01*
G03X774201Y560112I1400J543D01*
G01X774205Y560101D01*
X774212Y560088D01*
X774214Y560082D01*
G03X774462Y559701I1368J620D01*
G03X774663Y559513I1122J998D01*
G02X774713Y559458I-120J-160D01*
G03X778079Y557552I3366J2019D01*
G03X780525Y558408I-1J3927D01*
G01X780568Y558442D01*
X780675Y558457D01*
X781388Y558162D01*
G03X782887Y557864I1500J3628D01*
G01X786395D01*
G03X787893Y558162I-2J3927D01*
G01X791331Y559586D01*
G02X791346Y559591I71J-187D01*
G01X793076Y560150D01*
G03X794310Y560812I-1193J3705D01*
G01X794311Y560813D01*
G03X794333Y560830I-2369J3089D01*
G01X794887Y561059D01*
G03X796160Y561911I-1505J3626D01*
G01X797766Y563516D01*
G02X797785Y563532I138J-144D01*
G01X800019Y565281D01*
X800306Y565507D01*
G02X800551Y565509I124J-158D01*
G01Y565508D01*
G02X800615Y565273I-121J-159D01*
G01X800179Y564222D01*
G02X800129Y564151I-184J77D01*
G03X799869Y563890I2624J-2874D01*
G02X799866Y563886I-161J118D01*
G03X799089Y562688I2851J-2700D01*
G01X798400Y561024D01*
G03X798110Y559788I3628J-1503D01*
G02X798061Y559669I-200J13D01*
G03X797389Y558586I2956J-2584D01*
G01X796700Y556922D01*
G03X796410Y555684I3628J-1503D01*
G02X796361Y555565I-200J13D01*
G03X795731Y554579I2957J-2583D01*
G01X795730Y554578D01*
X795722Y554577D01*
G03X794498Y553101I278J-1476D01*
G01Y553056D01*
G03X794674Y552394I1502J45D01*
G01X794706Y552335D01*
G03X794716Y552319I174J98D01*
G01X794718Y552317D01*
X794725Y552306D01*
G03X794796Y552202I1275J794D01*
G03X794802Y552194I1205J897D01*
G03X794711Y551581I3826J-881D01*
G02X794662Y551464I-199J15D01*
G03X794265Y550922I2958J-2583D01*
G03X794263Y550918I178J-91D01*
G03X794260Y550913I3365J-2023D01*
G01X794256Y550907D01*
X794240Y550881D01*
X794239Y550880D01*
G03X793942Y550308I3294J-2073D01*
G01X793727Y549794D01*
X793270Y548703D01*
X793269Y548701D01*
G03X793256Y548671I3564J-1562D01*
G01Y548670D01*
X793241Y548633D01*
G03X793233Y548613I3609J-1455D01*
G03X793208Y548548I3620J-1429D01*
G01Y548547D01*
X793181Y548475D01*
G03X793180Y548472I189J-65D01*
G01X793179Y548466D01*
X793149Y548376D01*
G03X792998Y547688I3710J-1175D01*
G03X792980Y547519I3860J-497D01*
G03X792975Y547450I3879J-316D01*
G01X792973Y547417D01*
X792936Y547329D01*
X792917Y547307D01*
G03X792740Y547081I3001J-2533D01*
G02X792736Y547075I-168J108D01*
G03X792213Y546182I3067J-2396D01*
G01X792200Y546156D01*
X791707Y544977D01*
X791604Y544731D01*
X791538Y544574D01*
Y544573D01*
X791522Y544535D01*
G03X791514Y544516I3582J-1520D01*
G01Y544515D01*
X791498Y544477D01*
X791492Y544459D01*
X791490Y544454D01*
G03X791458Y544367I3636J-1387D01*
G03X791456Y544364I161J-109D01*
G03X791443Y544325I3685J-1250D01*
G01Y544322D01*
X791432Y544289D01*
G03X791243Y543318I3694J-1223D01*
G01X791241Y543284D01*
X791190Y543163D01*
X791167Y543138D01*
G03X790915Y542826I2898J-2598D01*
G01X790913Y542823D01*
X790903Y542809D01*
G03X790791Y542644I3163J-2267D01*
G03X790479Y542049I3278J-2098D01*
G01X789806Y540444D01*
G03X789695Y540147I3587J-1510D01*
G01X789683Y540110D01*
X789612Y540023D01*
G02X789567Y539986I-148J134D01*
G01X789480Y539938D01*
G02X789459Y539929I-89J179D01*
G01X789387Y539946D01*
G03X788481Y540052I-906J-3821D01*
G03X785116Y538148I0J-3926D01*
G02X785066Y538093I-170J105D01*
G03X784483Y536905I920J-1188D01*
G01Y536877D01*
G03X784486Y536803I1502J24D01*
G01X784487Y536796D01*
Y536788D01*
X784492Y536717D01*
G03X784493Y536706I199J13D01*
G01X784495Y536695D01*
X784505Y536644D01*
X784506Y536638D01*
G03X784553Y536448I1479J265D01*
G02X784562Y536374I-190J-61D01*
G03X784554Y536125I3919J-251D01*
G03X784903Y534507I3927J0D01*
G02Y534343I-182J-82D01*
G03X784554Y532726I3578J-1618D01*
G01Y532724D01*
G03X784556Y532620I3927J23D01*
G01Y532618D01*
X784558Y532540D01*
G02X784540Y532517I-166J111D01*
G01X784403Y532376D01*
G02X784401Y532374I-142J140D01*
G01X784329Y532302D01*
G02X784262Y532258I-141J142D01*
G01X784228Y532244D01*
X783156D01*
G03X782676Y532214I2J-3892D01*
G01X782674D01*
G03X780907Y531794I0J-3927D01*
G01X780850D01*
G03X778079Y532940I-2772J-2780D01*
G03X774714Y531036I0J-3926D01*
G02X774664Y530981I-170J105D01*
G03X774081Y529793I920J-1188D01*
G01Y529765D01*
G03X774084Y529691I1502J24D01*
G01X774085Y529684D01*
Y529676D01*
X774090Y529605D01*
G03X774091Y529594I199J13D01*
G01X774093Y529583D01*
X774103Y529532D01*
X774104Y529526D01*
G03X774151Y529336I1479J265D01*
G02X774160Y529262I-190J-61D01*
G03X774152Y529013I3919J-251D01*
G03X774501Y527395I3927J0D01*
G02Y527231I-182J-82D01*
G03X774152Y525614I3578J-1618D01*
G01Y525612D01*
G03X774155Y525474I3927J16D01*
G02X774144Y525399I-200J-9D01*
G03X774153Y524373I1415J-501D01*
G01X774157Y524361D01*
X774173Y524312D01*
G03X774185Y524286I187J70D01*
G01X774186Y524284D01*
G03X774201Y524247I1400J546D01*
G01X774205Y524235D01*
X774213Y524219D01*
G03X774548Y523745I1371J614D01*
G03X774664Y523645I1038J1086D01*
G02X774714Y523590I-120J-160D01*
G03X778079Y521686I3365J2022D01*
G03X780793Y522776I-1J3927D01*
G02X780931Y522832I139J-144D01*
G01X784354D01*
G02X784364Y522823I-129J-153D01*
G01X784374Y522813D01*
X784420Y522761D01*
X784436Y522743D01*
X784458Y522718D01*
X784485Y522654D01*
X784487Y522615D01*
G03X784553Y522269I1499J107D01*
G02X784562Y522196I-190J-61D01*
G03X784554Y521952I3919J-251D01*
G03X784903Y520334I3927J0D01*
G02Y520170I-182J-82D01*
G03X784554Y518553I3578J-1618D01*
G01Y518551D01*
G03X784556Y518447I3927J23D01*
G01Y518445D01*
X784558Y518369D01*
G02X784533Y518336I-171J104D01*
G01X784403Y518202D01*
G02X784401Y518200I-142J140D01*
G01X784329Y518128D01*
G02X784262Y518084I-141J142D01*
G01X784228Y518070D01*
X783175D01*
G03X781403Y517642I2J-3892D01*
G02X781312Y517620I-91J178D01*
G01X780893D01*
X780823Y517648D01*
X780794Y517676D01*
G03X778079Y518766I-2715J-2836D01*
G03X774714Y516862I0J-3926D01*
G02X774665Y516807I-171J103D01*
G03X774081Y515628I920J-1190D01*
G01Y515614D01*
G03Y515612I1502J-1D01*
G03X774151Y515162I1502J3D01*
G02X774160Y515089I-190J-61D01*
G03X774152Y514839I3919J-251D01*
G03X774501Y513221I3927J0D01*
G02Y513057I-182J-82D01*
G03X774152Y511439I3578J-1618D01*
G03X774160Y511189I3927J1D01*
G02X774152Y511116I-199J-15D01*
G03X774136Y511063I1429J-460D01*
G03X774082Y510725I1447J-404D01*
G01X774081Y510701D01*
Y510652D01*
G03X774665Y509471I1504J9D01*
G02X774714Y509416I-122J-158D01*
G03X778079Y507512I3365J2022D01*
G03X780793Y508602I-1J3927D01*
G02X780931Y508658I139J-144D01*
G01X788820D01*
G03X790323Y508957I0J3927D01*
G01X794377Y510636D01*
G02X794594Y510593I76J-185D01*
G01X794637Y510550D01*
X794661Y510431D01*
X794616Y510325D01*
G03X794321Y509110I3619J-1522D01*
G02X794272Y508994I-200J16D01*
G03X793605Y507930I2950J-2591D01*
G01X792906Y506270D01*
G03X792611Y505055I3619J-1522D01*
G02X792562Y504939I-200J16D01*
G03X791895Y503875I2950J-2591D01*
G01X791196Y502215D01*
G03X790921Y501190I3620J-1521D01*
G02X790911Y501151I-198J30D01*
G03X790717Y500219I3684J-1253D01*
G03X790707Y500058I3878J-322D01*
G02X790693Y499991I-200J7D01*
G03X790478Y499275I3636J-1482D01*
G01X789817Y495949D01*
X789816Y495948D01*
X789573Y495794D01*
G02X789533Y495775I-105J170D01*
G01X789457Y495794D01*
X789455D01*
G03X788481Y495918I-979J-3802D01*
G03X785116Y494014I0J-3926D01*
G02X785067Y493959I-171J103D01*
G03X784483Y492780I920J-1190D01*
G01Y492766D01*
G03Y492764I1502J-1D01*
G03X784553Y492314I1502J3D01*
G02X784562Y492241I-190J-61D01*
G03X784554Y491991I3919J-251D01*
G03X784903Y490373I3927J0D01*
G02Y490209I-182J-82D01*
G03X784554Y488591I3578J-1618D01*
G03X784562Y488343I3927J3D01*
G02X784553Y488270I-199J-12D01*
G03X784497Y488020I1433J-452D01*
G01X784496Y488014D01*
G02X784363Y487851I-198J26D01*
G03X783940Y487679I1265J-3717D01*
G02X783854Y487660I-85J181D01*
G01X780931D01*
G02X780793Y487716I1J200D01*
G03X778079Y488806I-2715J-2837D01*
G03X774714Y486902I0J-3926D01*
G02X774665Y486847I-171J103D01*
G03X774081Y485668I920J-1190D01*
G01Y485654D01*
G03Y485652I1502J-1D01*
G03X774151Y485202I1502J3D01*
G02X774160Y485129I-190J-61D01*
G03X774152Y484879I3919J-251D01*
G03X774501Y483261I3927J0D01*
G02Y483097I-182J-82D01*
G03X774152Y481479I3578J-1618D01*
G03X774160Y481229I3927J1D01*
G02X774152Y481156I-199J-15D01*
G03X774136Y481103I1429J-460D01*
G03X774082Y480765I1447J-404D01*
G01X774081Y480741D01*
Y480692D01*
G03X774665Y479511I1504J9D01*
G02X774714Y479456I-122J-158D01*
G03X778079Y477552I3365J2022D01*
G03X780793Y478642I-1J3927D01*
G02X780931Y478698I139J-144D01*
G01X784354D01*
G02X784364Y478689I-129J-153D01*
G01X784374Y478679D01*
X784420Y478627D01*
X784436Y478609D01*
X784458Y478584D01*
X784485Y478520D01*
X784487Y478481D01*
G03X784553Y478135I1499J107D01*
G02X784562Y478062I-190J-61D01*
G03X784554Y477818I3919J-251D01*
G03X784903Y476200I3927J0D01*
G02Y476036I-182J-82D01*
G03X784554Y474418I3578J-1618D01*
G03X784556Y474303I3927J11D01*
G01X784558Y474247D01*
X784536Y474197D01*
X784513Y474172D01*
X784376Y474025D01*
G02X784369Y474017I-154J128D01*
G02X784320Y473983I-137J146D01*
G01X784215Y473930D01*
X784164Y473927D01*
X784161D01*
G03X783992Y473911I282J-3881D01*
G03X783642Y473854I450J-3866D01*
G03X782889Y473613I804J-3807D01*
G02X782883Y473611I-66J188D01*
G03X782646Y473507I1458J-3646D01*
G01X782644D01*
X782604Y473488D01*
X780931D01*
G02X780793Y473543I0J200D01*
G03X778080Y474632I-2714J-2837D01*
G01X778079D01*
G03X774713Y472728I0J-3927D01*
G02X774664Y472673I-171J103D01*
G03X774081Y471500I919J-1188D01*
G01Y471464D01*
G03X774151Y471026I1503J16D01*
G02X774160Y470953I-190J-61D01*
G03X774152Y470706I3919J-251D01*
G03X774501Y469088I3927J0D01*
G02Y468924I-182J-82D01*
G03X774152Y467306I3578J-1618D01*
G03X774160Y467055I3927J0D01*
G02X774151Y466982I-199J-12D01*
G03X774082Y466592I1432J-454D01*
G01X774081Y466568D01*
Y466519D01*
G03X774665Y465338I1504J9D01*
G02X774714Y465283I-122J-158D01*
G03X778079Y463380I3365J2024D01*
G01X778080D01*
G03X780793Y464469I-1J3926D01*
G02X780931Y464524I138J-145D01*
G01X788669D01*
G03X790850Y465186I-1J3927D01*
G01X802440Y472929D01*
G03X803887Y474691I-2180J3266D01*
G01X819580Y512578D01*
G02X819623Y512643I185J-76D01*
G01X820284Y513305D01*
G03X821136Y514578I-2774J2778D01*
G01X828378Y532063D01*
X828402Y532089D01*
G03X828791Y533029I-1111J1010D01*
G01X828793Y533064D01*
X829355Y534420D01*
X829379Y534446D01*
G03X829773Y535398I-1107J1016D01*
G01X829774Y535433D01*
X855091Y596550D01*
G03X855390Y598053I-3628J1503D01*
G01Y627506D01*
X855391Y627518D01*
G03X855402Y627700I-1491J181D01*
G03X855391Y627882I-1502J1D01*
G01X855390Y627894D01*
Y629791D01*
G03X855389Y629868I-3927J-12D01*
G02X855401Y629940I200J4D01*
G03X855491Y630453I-1414J512D01*
G03X855318Y631152I-1502J-1D01*
G03X855193Y631351I-1330J-697D01*
G01X855191Y631353D01*
X855190Y631355D01*
X855188Y631358D01*
X855173Y631379D01*
G02X855157Y631406I163J115D01*
G01X855136Y631450D01*
G02X855121Y631526I185J76D01*
G01Y631579D01*
G03X855081Y631698I-200J-1D01*
G01X855077Y631705D01*
X855069Y631731D01*
G02X855059Y631794I190J62D01*
G01X855060Y631827D01*
X855069Y631853D01*
X855072Y631860D01*
X855102Y631944D01*
X855127Y631973D01*
G03X855491Y632953I-1137J980D01*
G03X854372Y634406I-1503J0D01*
G01X854370D01*
X854347Y634413D01*
X854272Y634488D01*
X853877Y635966D01*
G03X853485Y636915I-3794J-1012D01*
G01X841808Y657152D01*
G02X841814Y657361I173J100D01*
G01X842038Y657707D01*
X842140Y657755D01*
X842196Y657749D01*
G03X842350Y657741I155J1494D01*
G01X842352D01*
G03Y660745I0J1502D01*
G03X840981Y659855I0J-1501D01*
G01X840958Y659803D01*
X840866Y659741D01*
X840452Y659719D01*
G02X840269Y659819I-10J200D01*
G01X838483Y662912D01*
X838488Y663025D01*
X838516Y663067D01*
G03X838774Y663908I-1245J842D01*
G01Y663910D01*
G03X837272Y665412I-1502J0D01*
G01X837244D01*
G03X837168Y665409I21J-1503D01*
G01X837115Y665405D01*
X837015Y665459D01*
X831772Y674544D01*
X831765Y674569D01*
G03X831393Y675214I-1447J-405D01*
G01X831375Y675232D01*
X830877Y676094D01*
X830871Y676185D01*
X830876Y676198D01*
G03X830998Y676784I-1380J593D01*
G01Y676798D01*
G03X829705Y678281I-1502J-5D01*
G01X829659Y678287D01*
X829583Y678338D01*
X820003Y694939D01*
G02X819983Y694986I172J101D01*
G01X816882Y706354D01*
G02X816875Y706389I192J57D01*
G01X814852Y729515D01*
X814886Y729602D01*
X814920Y729633D01*
G03X815404Y730738I-1019J1105D01*
G03X814712Y732003I-1502J0D01*
G01X814673Y732028D01*
X814626Y732107D01*
X813986Y739409D01*
X814064Y739526D01*
X814131Y739547D01*
G03X815180Y740979I-453J1432D01*
G03X813876Y742468I-1502J0D01*
G02X813703Y742649I26J198D01*
G01X813699Y742691D01*
G03X815068Y744187I-133J1496D01*
G03X814535Y745334I-1501J0D01*
G02X814521Y745347I129J153D01*
G02X814546Y745648I143J140D01*
G03X815155Y746856I-894J1208D01*
G03X813654Y748358I-1502J0D01*
G01X813652D01*
G03X813587Y748357I-9J-1502D01*
G01X813548Y748355D01*
X813476Y748380D01*
X813238Y748588D01*
G02X813171Y748721I132J150D01*
G01X812149Y760404D01*
G02X812248Y760595I199J18D01*
G01X812613Y760806D01*
X812728Y760801D01*
X812776Y760768D01*
G03X813635Y760498I859J1231D01*
G03Y763502I0J1502D01*
G03X812575Y763064I0J-1502D01*
G01X812533Y763023D01*
X812421Y762998D01*
X812026Y763142D01*
G02X811895Y763313I68J188D01*
G01X802284Y873156D01*
G02Y873190I199J17D01*
G01X811586Y979784D01*
G02X811618Y979876I199J-18D01*
G01X823436Y997799D01*
Y997801D01*
X828418Y1005255D01*
G02X828462Y1005260I44J-195D01*
G01X883128D01*
G02X883328Y1005060I0J-200D01*
G01Y998164D01*
G02X883301Y998063I-200J-1D01*
G03X883094Y997302I1299J-762D01*
G01Y995879D01*
X883056Y995799D01*
X883027Y995774D01*
G02X883025Y995772I-142J140D01*
G01X883024Y995771D01*
G02X882898Y995726I-126J155D01*
G01X882861D01*
X882845Y995729D01*
G03X882644Y995747I-234J-1484D01*
G01X882606D01*
G03X882579Y992743I3J-1502D01*
G01X882615D01*
G03X882859Y992764I-6J1502D01*
G01X882903Y992771D01*
X882943Y992760D01*
G02X883020Y992721I-50J-194D01*
G01X883022Y992719D01*
G02X883094Y992565I-128J-154D01*
G01Y960508D01*
G02X883035Y960366I-200J0D01*
G01X872314Y949645D01*
G02X872124Y949593I-141J142D01*
G01X871791Y949677D01*
G02X871648Y949813I49J194D01*
G01Y949814D01*
G03X870209Y950886I-1439J-430D01*
G03X868707Y949384I0J-1502D01*
G03X869779Y947945I1502J0D01*
G01X869780D01*
G02X869916Y947802I-58J-192D01*
G01X870000Y947469D01*
G02X869948Y947279I-194J-49D01*
G01X861014Y938345D01*
G03X860572Y937280I1065J-1066D01*
G01Y932706D01*
G02X860513Y932564I-200J0D01*
G01X858294Y930344D01*
G03X857852Y929279I1065J-1066D01*
G01Y919424D01*
X857834Y919394D01*
G02X857758Y919321I-172J103D01*
G01X857678Y919277D01*
G02X857669Y919272I-102J172D01*
G02X857616Y919255I-87J180D01*
G02X857470Y919287I-33J197D01*
G03X856630Y919544I-840J-1245D01*
G01X856628D01*
G03X856568Y919543I-5J-1502D01*
G03X855126Y918042I60J-1501D01*
G03X856628Y916540I1502J0D01*
G01X856629D01*
G03X857469Y916797I0J1502D01*
G02X857570Y916831I112J-166D01*
G01X857625Y916834D01*
X857807Y916737D01*
X857811Y916735D01*
X857852Y916666D01*
Y906466D01*
G02X857793Y906324I-200J0D01*
G01X854622Y903153D01*
G02X854480Y903094I-142J141D01*
G01X837727D01*
G03X836662Y902652I1J-1507D01*
G01X834075Y900065D01*
G02X833933Y900006I-142J141D01*
G01X830063D01*
G03Y896994I0J-1506D01*
G01X834640D01*
G03X835705Y897435I0J1506D01*
G01X838292Y900021D01*
G02X838434Y900080I142J-141D01*
G01X853086D01*
G02X853256Y899986I0J-200D01*
G01X853463Y899656D01*
X853468Y899553D01*
X853446Y899507D01*
G03X853218Y898509I2078J-1000D01*
G01Y898505D01*
G03X855524Y896198I2307J0D01*
G03X857155Y896874I-1J2307D01*
G01X857446Y897165D01*
G02X857581Y897223I141J-142D01*
G01X857893Y897233D01*
X857965Y897207D01*
X857986Y897188D01*
G03X858084Y897108I998J1122D01*
G03X858615Y896852I905J1199D01*
G01X858639Y896846D01*
X858688Y896819D01*
G02X858695Y896815I-96J-176D01*
G02X858779Y896713I-104J-171D01*
G01X858782Y896705D01*
X858849Y896468D01*
X858850Y896464D01*
X858876Y896362D01*
G02X858826Y896177I-194J-47D01*
G01X858101Y895453D01*
G03X857438Y893852I1603J-1602D01*
G01Y893850D01*
G03X859704Y891584I2266J0D01*
G01X859706D01*
G03X861307Y892247I-1J2266D01*
G01X864359Y895299D01*
G02X864466Y895353I139J-143D01*
G02X864499Y895356I35J-197D01*
G01X864665D01*
X864686Y895347D01*
X864707Y895343D01*
X864765Y895307D01*
X864790Y895276D01*
Y883324D01*
G02X864731Y883182I-200J0D01*
G01X862969Y881421D01*
G02X862827Y881362I-142J141D01*
G01X861524D01*
G03X861487Y881364I-83J-1200D01*
G01X853014D01*
G03X852977Y881362I46J-1202D01*
G01X846591D01*
G03X846554Y881364I-83J-1200D01*
G01X842064D01*
G03X842027Y881362I46J-1202D01*
G01X835652D01*
G03X835615Y881364I-83J-1200D01*
G01X833917D01*
X833891Y881363D01*
X833849D01*
X833823Y881364D01*
X827338D01*
G02X827247Y881386I0J200D01*
G02X827197Y881422I90J178D01*
G01X827184Y881435D01*
X826988Y881666D01*
G02X826950Y881734I152J130D01*
G01X826948Y881741D01*
Y881742D01*
G02X826944Y881835I192J55D01*
G01X826946Y881844D01*
G03X826965Y882081I-1483J238D01*
G01Y882083D01*
G03X825463Y883585I-1502J0D01*
G01X825462D01*
G03X824793Y883428I0J-1502D01*
G01X824773Y883418D01*
X824735Y883408D01*
G02X824629I-53J192D01*
G01X824591Y883418D01*
X824571Y883428D01*
G03X823902Y883585I-669J-1345D01*
G01X823900D01*
G03X822398Y882083I0J-1502D01*
G03X823821Y880583I1502J0D01*
G01X823822D01*
G02X823929Y880545I-11J-200D01*
G01X823953Y880528D01*
X823987Y880484D01*
X824064Y880285D01*
Y880283D01*
X824128Y880117D01*
G02X824108Y879934I-187J-72D01*
G02X824083Y879904I-166J113D01*
G01X816053Y871874D01*
G03X816000Y871817I855J-848D01*
G01X815995Y871811D01*
X815767Y871583D01*
G03X815708Y871441I141J-142D01*
G01Y871126D01*
X815707Y871111D01*
G03X815704Y871027I1202J-85D01*
G01Y865487D01*
G02X815703Y865466I-200J-1D01*
G02X815581Y865302I-199J21D01*
G01X815456Y865259D01*
X815331Y865297D01*
X815292Y865351D01*
G03X814080Y865966I-1212J-887D01*
G03X813209Y865687I1J-1501D01*
G02X813177Y865668I-118J162D01*
G03X812313Y864309I637J-1359D01*
G03X812319Y864172I1502J-3D01*
G01X812322Y864137D01*
X812305Y864070D01*
X812141Y863830D01*
G02X812031Y863751I-165J114D01*
G01X812030D01*
G03X810938Y862306I410J-1445D01*
G03X813942I1502J0D01*
G03X813936Y862443I-1502J3D01*
G01X813933Y862478D01*
X813950Y862545D01*
X814114Y862785D01*
G02X814224Y862864I165J-114D01*
G01X814225D01*
G03X814438Y862942I-408J1445D01*
G03X814687Y863086I-624J1366D01*
G02X814719Y863105I118J-162D01*
G03X815107Y863368I-638J1359D01*
G01X815194Y863449D01*
G02X815218Y863442I-44J-195D01*
G01X815463Y863357D01*
X815476Y863367D01*
X815590Y863313D01*
G02X815704Y863133I-86J-181D01*
G01Y849376D01*
G02X815504Y849176I-200J0D01*
G01X815398D01*
G03X815198Y848976I0J-200D01*
G01Y848172D01*
X815197Y848157D01*
G03X815194Y848073I1202J-85D01*
G01Y846923D01*
G02X815167Y846822I-200J-1D01*
G02X815122Y846769I-173J101D01*
G03Y844387I915J-1191D01*
G02X815167Y844334I-128J-154D01*
G02X815194Y844233I-173J-100D01*
G01Y842710D01*
G02X815122Y842557I-200J1D01*
G01X814869Y842363D01*
G02X814754Y842326I-116J163D01*
G01X814695D01*
X814671Y842332D01*
G03X814299Y842379I-373J-1455D01*
G03X812797Y840877I0J-1502D01*
G03X814298Y839375I1502J0D01*
G01X814300D01*
G03X814349Y839376I-6J1502D01*
G01X814355D01*
G02X814497Y839317I0J-200D01*
G01X814515Y839300D01*
X814707Y838980D01*
G02X814720Y838799I-171J-103D01*
G02X814718Y838795I-180J87D01*
G01X814709Y838780D01*
G03X814514Y838038I1309J-741D01*
G01Y838035D01*
G03X814516Y837963I1502J6D01*
G01Y837951D01*
X814517Y837935D01*
X814520Y837895D01*
G03X814951Y836976I1496J141D01*
G03X815041Y836893I1063J1062D01*
G01X815042Y836892D01*
G02X815093Y836825I-130J-152D01*
G01X815112Y836785D01*
Y836658D01*
Y836656D01*
X815113Y836506D01*
G02X814912Y836305I-200J-1D01*
G01X814867Y836307D01*
X814818Y836326D01*
X814792Y836345D01*
G03X813887Y836648I-905J-1200D01*
G03Y833644I0J-1502D01*
G03X814796Y833951I-1J1502D01*
G01X814798D01*
X814800Y833953D01*
G02X814910Y833993I120J-160D01*
G01X814938Y833994D01*
X814997Y833979D01*
X815041Y833951D01*
X815051Y833943D01*
G03X815112Y833896I974J1201D01*
G02X815194Y833735I-118J-161D01*
G01Y831657D01*
X815190Y831618D01*
G02X815170Y831555I-198J28D01*
G02X815165Y831545I-181J84D01*
G01X815119Y831466D01*
G02X815090Y831427I-174J99D01*
G01X815073Y831410D01*
X815052Y831397D01*
G03Y828797I811J-1300D01*
G01X815073Y828784D01*
X815089Y828767D01*
G02X815120Y828727I-141J-142D01*
G01X815167Y828644D01*
X815173Y828633D01*
G02X815194Y828545I-179J-89D01*
G01Y825624D01*
Y825623D01*
G02X815124Y825472I-200J1D01*
G01X815095Y825447D01*
X815053Y825434D01*
G03X814050Y824392I447J-1434D01*
G03X815053Y822566I1450J-392D01*
G01X815064Y822563D01*
G02X815194Y822390I-70J-188D01*
G01Y819316D01*
G03X815197Y819231I1205J0D01*
G01X815198Y819216D01*
Y816542D01*
X815197Y816527D01*
G03X815194Y816442I1202J-85D01*
G01Y815437D01*
G02X815077Y815255I-200J0D01*
G01X814746Y815104D01*
G02X814532Y815135I-83J182D01*
G03X813548Y815502I-984J-1136D01*
G03Y812498I0J-1502D01*
G03X814532Y812865I0J1503D01*
G02X814746Y812896I131J-151D01*
G01X815077Y812745D01*
G02X815194Y812563I-83J-182D01*
G01Y798994D01*
G03X815197Y798910I1205J1D01*
G01X815198Y798895D01*
Y798580D01*
G03X815257Y798438I200J0D01*
G01X815482Y798213D01*
X815487Y798207D01*
G03X815548Y798142I908J791D01*
G01X815647Y798043D01*
G02X815700Y797941I-143J-139D01*
G02X815704Y797903I-196J-40D01*
G01Y765885D01*
G03X815707Y765800I1205J0D01*
G01X815708Y765785D01*
Y760944D01*
G03X815767Y760802I200J0D01*
G01X815995Y760574D01*
G02X815997Y760572I-140J-142D01*
G02X816050Y760395I-143J-139D01*
G03X815998Y760007I1450J-392D01*
G01Y760000D01*
G03X816621Y758782I1502J0D01*
G01X816622D01*
X816623Y758781D01*
G02X816684Y758708I-119J-161D01*
G01X816694Y758686D01*
X816705Y758637D01*
X816696Y758444D01*
X816689Y758278D01*
G02X816661Y758183I-200J7D01*
G01X816648Y758163D01*
X816616Y758129D01*
X816592Y758115D01*
G03X815863Y756827I773J-1288D01*
G03X817365Y755325I1502J0D01*
G03X817536Y755335I-2J1502D01*
G01X817561Y755338D01*
X817628Y755328D01*
X817642Y755324D01*
G03X818074Y755260I434J1438D01*
G01X818076D01*
G03X819489Y756253I0J1502D01*
G01X819493Y756264D01*
X819509Y756296D01*
X819516Y756307D01*
G02X819571Y756364I169J-108D01*
G01X819602Y756385D01*
X819641Y756394D01*
X819961Y756466D01*
G02X820019Y756470I43J-195D01*
G01X820072Y756467D01*
X820132Y756427D01*
G02X820162Y756402I-112J-165D01*
G01X821606Y754958D01*
G03X821657Y754910I851J853D01*
G01X821667Y754901D01*
X822125Y754443D01*
G02X822181Y754334I-141J-142D01*
G01X822188Y754292D01*
Y754226D01*
G02X822149Y754136I-197J32D01*
G01X822136Y754120D01*
X822134Y754113D01*
X822066Y753903D01*
G02X822006Y753812I-191J60D01*
G01X821986Y753795D01*
X821937Y753773D01*
X821908Y753768D01*
G03X820646Y752283I243J-1485D01*
G03X822151Y750778I1505J0D01*
G03X823656Y752282I0J1505D01*
G01Y752283D01*
G03X823653Y752360I-1504J-20D01*
G01X823652Y752367D01*
Y752382D01*
X823649Y752424D01*
X823663Y752463D01*
G02X823706Y752532I188J-69D01*
G01X823902Y752741D01*
X823910Y752749D01*
G02X824012Y752802I139J-143D01*
G02X824050Y752806I40J-196D01*
G01X824218D01*
G03X824255Y752804I83J1200D01*
G01X832700D01*
X832706Y752806D01*
X832878D01*
G03X832956Y752822I0J200D01*
G01X832992Y752837D01*
X833003Y752848D01*
X833009Y752853D01*
X833137Y752981D01*
X833153Y752987D01*
X833322Y753162D01*
G02X833324Y753164I142J-140D01*
G01X838483Y758323D01*
G03X838533Y758376I-851J853D01*
G01X838542Y758386D01*
X838787Y758631D01*
X838792Y758637D01*
X838803Y758648D01*
X838818Y758684D01*
G03X838834Y758762I-184J78D01*
G01Y759134D01*
G03X838836Y759174I-1200J80D01*
G01Y772103D01*
X838844Y772130D01*
G03X838905Y772552I-1441J424D01*
G01Y772554D01*
G03X838844Y772976I-1502J-2D01*
G01X838836Y773003D01*
Y803525D01*
G02X838839Y803558I200J-2D01*
G02X838893Y803665I197J-32D01*
G01X845645Y810417D01*
G02X845752Y810471I139J-143D01*
G02X845785Y810474I35J-197D01*
G01X847704D01*
G03X847745Y810476I-38J1203D01*
G01X851255D01*
G03X851296Y810474I79J1201D01*
G01X856291D01*
G02X856390Y810448I0J-200D01*
G02X856470Y810363I-99J-174D01*
G01X856475Y810353D01*
X856483Y810335D01*
X856485Y810329D01*
G03X857507Y809402I1408J526D01*
G01X857545Y809392D01*
X857577Y809368D01*
X857672Y809296D01*
X857681Y809280D01*
X857693Y809259D01*
G03X859000Y808498I1307J742D01*
G03X860502Y810000I0J1502D01*
G03X860501Y810060I-1502J5D01*
G01X860499Y810102D01*
X860513Y810139D01*
G02X860555Y810207I188J-69D01*
G01X860610Y810263D01*
Y810265D01*
X860760Y810419D01*
G02X860866Y810472I139J-145D01*
G02X860898Y810474I28J-198D01*
G01X863643D01*
G03X863684Y810476I-38J1203D01*
G01X863826D01*
G02X864008Y810358I0J-200D01*
G01X864009Y810356D01*
G03X864428Y809742I1834J801D01*
G01X865069Y809101D01*
X865158Y809011D01*
G02X865216Y808871I-142J-141D01*
G01Y803664D01*
G02X865092Y803479I-200J0D01*
G01X865044Y803460D01*
G02X864929Y803449I-76J185D01*
G01X864900Y803455D01*
X864850Y803482D01*
X863484Y804848D01*
G02X863440Y804915I142J141D01*
G01X863426Y804949D01*
Y806500D01*
G03X859424I-2001J0D01*
G01Y804076D01*
G03X860010Y802661I2001J0D01*
G01X860105Y802565D01*
X861345Y801325D01*
G02X861399Y801218I-143J-139D01*
G02X861402Y801185I-197J-35D01*
G01Y795595D01*
G03X861989Y794180I2002J1D01*
G01X873071Y783098D01*
G02X873125Y782991I-143J-139D01*
G02X873128Y782958I-197J-35D01*
G01Y780477D01*
G03X873715Y779062I2002J1D01*
G01X885859Y766918D01*
G02X885861Y766916I-140J-142D01*
G02X885915Y766809I-143J-139D01*
G02X885918Y766776I-197J-35D01*
G01Y746268D01*
G03X885928Y746067I2001J-1D01*
G01Y746059D01*
G03X885944Y745905I1998J130D01*
G02X885946Y745882I-198J-29D01*
G02X885595Y745745I-200J-5D01*
G03X884463Y746260I-1132J-987D01*
G03X883143Y745476I0J-1503D01*
G02X882549Y745349I-351J191D01*
G03X881637Y745657I-912J-1196D01*
G03X880147Y744353I0J-1503D01*
G02X879536Y744069I-396J53D01*
G01X879501Y744093D01*
G03X878672Y744343I-830J-1252D01*
G01X878670D01*
G03X877230Y743269I0J-1502D01*
G02X877229Y743266I-379J125D01*
G01X877228Y743262D01*
G02X876556Y743097I-384J112D01*
G03X875473Y743558I-1083J-1042D01*
G03Y740554I0J-1502D01*
G03X876915Y741635I0J1502D01*
G02X877587Y741800I384J-112D01*
G03X878670Y741339I1083J1042D01*
G03X880172Y742841I0J1502D01*
G03X880163Y743004I-1502J-1D01*
G01X880162Y743011D01*
G02X880171Y743087I200J15D01*
G01X880179Y743107D01*
G02X880508Y743162I183J-82D01*
G02X880512Y743158I-139J-143D01*
G03X880749Y742941I1128J994D01*
G02X880846Y742397I-236J-323D01*
G03X880595Y741566I1252J-832D01*
G01Y741565D01*
G03X882098Y740062I1503J0D01*
G03X883057Y740408I0J1502D01*
G02X883454Y740475I256J-308D01*
G02X883570Y740359I-71J-187D01*
G03X884976Y739388I1406J532D01*
G03X886479Y740891I0J1503D01*
G03X886327Y741550I-1505J0D01*
G02X886313Y741588I180J88D01*
G03X884858Y742714I-1455J-377D01*
G03X883899Y742368I0J-1502D01*
G02X883318Y742442I-256J308D01*
G03X882986Y742778I-1222J-875D01*
G02X882889Y743322I236J323D01*
G03X882957Y743435I-1253J831D01*
G02X883551Y743562I351J-191D01*
G03X884463Y743254I912J1196D01*
G03X885966Y744756I0J1503D01*
G01Y744758D01*
G03X885963Y744839I-1503J-15D01*
G01Y744858D01*
G02X885964Y744881I200J3D01*
G01X886027Y745004D01*
G02X886163Y745058I137J-146D01*
G01X886302Y744987D01*
X886337Y744959D01*
X886349Y744943D01*
G03X886399Y744882I1573J1238D01*
G01X886403Y744877D01*
X886409Y744870D01*
G03X886412Y744866I1602J1199D01*
G02X886414Y744864I-139J-141D01*
G03X886605Y744652I1579J1231D01*
G01X886609Y744650D01*
X893767Y737491D01*
G02X893769Y737489I-140J-142D01*
G02X893823Y737382I-143J-139D01*
G02X893826Y737349I-197J-35D01*
G01Y706550D01*
G03X893827Y706496I2002J10D01*
G01Y706470D01*
X893824Y706434D01*
Y706430D01*
G03X893820Y706393I1988J-234D01*
G01X893816Y706352D01*
X893796Y706315D01*
G02X893768Y706275I-177J94D01*
G02X893743Y706252I-147J135D01*
G01X893672Y706197D01*
G02X893670Y706195I-141J139D01*
G01X893645Y706176D01*
G02X893588Y706147I-118J161D01*
G01X893559Y706137D01*
X893492D01*
X893476Y706139D01*
G03X893241Y706158I-238J-1483D01*
G01X893240D01*
G03X891739Y704656I1J-1502D01*
G03X893241Y703154I1502J0D01*
G03X893469Y703171I3J1502D01*
G01X893507Y703177D01*
X893544Y703168D01*
G02X893611Y703139I-45J-195D01*
G01X893682Y703091D01*
X893715Y703069D01*
X893794Y702952D01*
X893803Y702918D01*
G03X893815Y702875I1933J516D01*
G01X893819Y702861D01*
X893828Y702796D01*
X893827Y702777D01*
G03X893826Y702760I1996J-126D01*
G01Y700266D01*
G02X893819Y700215I-200J1D01*
G01X893802Y700149D01*
X893791Y700128D01*
G03X893562Y699198I1773J-930D01*
G01Y699144D01*
G02X893439Y698960I-200J1D01*
G02X893220Y699003I-78J184D01*
G01X886057Y706166D01*
G02X885998Y706308I141J142D01*
G01Y713092D01*
G03X885412Y714507I-2001J0D01*
G01X885250Y714670D01*
X884806Y715114D01*
G02X884782Y715144I143J139D01*
G02X884748Y715255I166J112D01*
G01Y725082D01*
G03X884161Y726497I-2002J-1D01*
G01X870748Y739910D01*
G02X870704Y739977I142J141D01*
G01X870690Y740011D01*
Y752954D01*
G03X870103Y754369I-2002J-1D01*
G01X867380Y757092D01*
G02X867336Y757159I142J141D01*
G01X867322Y757193D01*
Y762340D01*
G02X867325Y762373I200J-2D01*
G02X867379Y762480I197J-32D01*
G01X869351Y764452D01*
G03X869938Y765867I-1415J1416D01*
G01Y773065D01*
G03X869351Y774480I-2002J-1D01*
G01X867560Y776271D01*
G02X867516Y776338I142J141D01*
G01X867502Y776372D01*
Y781426D01*
G03X866915Y782841I-2002J-1D01*
G01X863484Y786272D01*
G02X863440Y786339I142J141D01*
G01X863426Y786373D01*
Y787456D01*
X863427Y788500D01*
G03X861426Y790502I-2002J0D01*
G01X861425D01*
G03X860098Y789998I0J-1999D01*
G03X859805Y789676I1325J-1500D01*
G02X859732Y789613I-163J115D01*
G01X859693Y789593D01*
X859514D01*
G02X859482Y789596I3J200D01*
G01X859322Y789624D01*
X859320D01*
X859235Y789640D01*
G02X859137Y789690I38J196D01*
G01X859117Y789709D01*
X859088Y789755D01*
X859080Y789784D01*
G03X859016Y789969I-1449J-398D01*
G03X859015Y789971I-1341J-669D01*
G03X859012Y789978I-1382J-588D01*
G01Y789979D01*
G02X859019Y790151I184J79D01*
G01X859042Y790195D01*
X859140Y790381D01*
G02X859200Y790449I176J-95D01*
G01X859235Y790475D01*
X859280Y790484D01*
G03X860541Y792000I-281J1516D01*
G03X857459I-1541J0D01*
G03X857596Y791367I1541J2D01*
G01Y791365D01*
X857597D01*
G02X857614Y791277I-183J-81D01*
G01X857612Y791230D01*
X857522Y791061D01*
Y791059D01*
X857495Y791008D01*
X857497Y790956D01*
X857412Y790892D01*
G02X857352Y790861I-121J160D01*
G01X857333Y790857D01*
G03X857301Y790850I305J-1471D01*
G01X857300D01*
X857285Y790847D01*
G03X856130Y789385I348J-1462D01*
G03X857632Y787883I1502J0D01*
G03X859037Y788851I0J1504D01*
G01X859047Y788877D01*
X859082Y788924D01*
G02X859279Y789003I162J-118D01*
G02X859329Y788987I-35J-197D01*
G02X859382Y788951I-85J-182D01*
G01X859398Y788933D01*
G02X859443Y788807I-155J-126D01*
G01Y788783D01*
G03X859440Y788760I1983J-270D01*
G03X859424Y788500I1985J-253D01*
G01Y785500D01*
G03X860010Y784085I2001J0D01*
G01X860929Y783165D01*
X863441Y780653D01*
G02X863498Y780513I-143J-140D01*
G01Y775499D01*
G03X864085Y774084I2002J1D01*
G01X865877Y772292D01*
G02X865930Y772190I-143J-139D01*
G02X865934Y772152I-196J-40D01*
G01Y766779D01*
G02X865920Y766704I-200J-1D01*
G01X865905Y766668D01*
X864783Y765546D01*
G02X864100Y765828I-283J283D01*
G01Y766826D01*
G03X863514Y768241I-2001J0D01*
G01X863484Y768271D01*
G02X863440Y768338I142J141D01*
G01X863426Y768372D01*
Y770500D01*
G03X859424I-2001J0D01*
G01Y767500D01*
G03X860010Y766085I2001J0D01*
G01X860041Y766054D01*
G02X860095Y765947I-143J-139D01*
G02X860098Y765914I-197J-35D01*
G01Y765769D01*
G02X860075Y765675I-200J-1D01*
G01X860064Y765654D01*
X860031Y765618D01*
X860010Y765604D01*
X859740Y765421D01*
G02X859666Y765390I-113J165D01*
G02X859599Y765389I-36J197D01*
G01X859552Y765397D01*
X859533Y765404D01*
G03X859000Y765502I-534J-1404D01*
G03Y762498I0J-1502D01*
G03X859519Y762591I-1J1502D01*
G01X859553Y762603D01*
X859642D01*
G02X859731Y762582I0J-200D01*
G01X859749Y762573D01*
X859810Y762531D01*
X859813Y762529D01*
X860010Y762396D01*
G02X860063Y762343I-112J-165D01*
G02X860098Y762231I-165J-113D01*
G01Y761769D01*
G02X860075Y761675I-200J-1D01*
G01X860064Y761654D01*
X860031Y761618D01*
X860010Y761604D01*
X859740Y761421D01*
G02X859666Y761390I-113J165D01*
G02X859599Y761389I-36J197D01*
G01X859552Y761397D01*
X859533Y761404D01*
G03X859000Y761502I-534J-1404D01*
G03Y758498I0J-1502D01*
G03X859519Y758591I-1J1502D01*
G01X859553Y758603D01*
X859642D01*
G02X859731Y758582I0J-200D01*
G01X859749Y758573D01*
X859810Y758531D01*
X859813Y758529D01*
X860010Y758396D01*
G02X860063Y758343I-112J-165D01*
G02X860098Y758231I-165J-113D01*
G01Y757769D01*
G02X860075Y757675I-200J-1D01*
G01X860064Y757654D01*
X860031Y757618D01*
X860010Y757604D01*
X859740Y757421D01*
G02X859666Y757390I-113J165D01*
G02X859599Y757389I-36J197D01*
G01X859552Y757397D01*
X859533Y757404D01*
G03X859000Y757502I-534J-1404D01*
G03Y754498I0J-1502D01*
G01X859001D01*
G03X859572Y754611I-1J1502D01*
G01X859573D01*
G02X859662Y754626I77J-185D01*
G01X859706Y754623D01*
X859752Y754597D01*
X859779Y754582D01*
X860021Y754445D01*
G02X860087Y754385I-98J-174D01*
G01X860113Y754347D01*
X860120Y754301D01*
G03X860684Y753183I1979J297D01*
G01X863829Y750037D01*
G02X863886Y749897I-143J-140D01*
G01Y737978D01*
G03X864473Y736563I2002J1D01*
G01X877459Y723577D01*
G02X877513Y723470I-143J-139D01*
G02X877516Y723437I-197J-35D01*
G01Y714216D01*
G02X877502Y714141I-200J-1D01*
G01X877487Y714105D01*
X876486Y713104D01*
G03X875900Y711689I1415J-1415D01*
G01Y709533D01*
G03X876486Y708118I2001J0D01*
G01X877196Y707407D01*
X879139Y705464D01*
G02X879193Y705357I-143J-139D01*
G02X879196Y705324I-197J-35D01*
G01Y702224D01*
G03X879782Y700809I2001J0D01*
G01X883387Y697204D01*
G02X883440Y697018I-142J-141D01*
G01Y697017D01*
G03X883401Y696678I1463J-340D01*
G03X884903Y695176I1502J0D01*
G03X885242Y695215I-1J1502D01*
G01X885293Y695227D01*
X885392Y695198D01*
X887163Y693427D01*
G02X887217Y693320I-143J-139D01*
G02X887220Y693287I-197J-35D01*
G01Y680643D01*
G02X887206Y680568I-200J-1D01*
G01X887191Y680532D01*
X881963Y675304D01*
G03X881825Y675152I1411J-1420D01*
G03X881821Y675148I139J-143D01*
G03X881810Y675133I1609J-1191D01*
G02X881805Y675127I-156J125D01*
G03X881459Y674558I1513J-1310D01*
G03X881445Y674522I1859J-743D01*
G01X881428Y674480D01*
G03X881422Y674464I184J-78D01*
G01X881399Y674386D01*
G03X881321Y673960I1918J-571D01*
G01Y673959D01*
X881320Y673941D01*
X881319Y673940D01*
G03X881308Y673722I1990J-210D01*
G01Y670167D01*
X881307Y666608D01*
G03X883308Y664606I2002J0D01*
G01X883309D01*
G03X883749Y664655I0J2000D01*
G03X884637Y665111I-441J1952D01*
G01X884651Y665124D01*
X884710Y665160D01*
X884761Y665161D01*
X884842Y665162D01*
X884844D01*
X884879Y665163D01*
X884910Y665164D01*
X884939Y665156D01*
G02X884991Y665133I-54J-193D01*
G01X885010Y665121D01*
X885022Y665111D01*
G03X886302Y664648I1281J1540D01*
G01X886304D01*
G03X888306Y666650I0J2002D01*
G01Y671222D01*
G02X888309Y671255I200J-2D01*
G02X888363Y671362I197J-32D01*
G01X889775Y672774D01*
G02X890458Y672492I283J-283D01*
G01Y666770D01*
G03X890459Y666715I2002J9D01*
G01Y666710D01*
X890460Y666708D01*
Y666686D01*
G03X892461Y664670I2001J-15D01*
G03X894462Y666671I0J2001D01*
G01Y673418D01*
G02X894465Y673451I200J-2D01*
G02X894519Y673558I197J-32D01*
G01X895777Y674816D01*
X896164Y675204D01*
X897047Y676086D01*
G02X897264Y676129I141J-142D01*
G02X897388Y675944I-76J-185D01*
G01Y658289D01*
G03X897974Y656874I2001J0D01*
G01X898769Y656078D01*
X898770Y656077D01*
G03X898795Y656052I1428J1403D01*
G01X899239Y655608D01*
X899338Y655510D01*
G03X900753Y654924I1415J1415D01*
G03X902754Y656925I0J2001D01*
G03X902655Y657549I-2001J2D01*
G01X902640Y657595D01*
X902624Y657636D01*
G03X902490Y657920I-1872J-709D01*
G03X902448Y657990I-1737J-994D01*
G03X902422Y658030I-1691J-1071D01*
G03X902412Y658045I-1670J-1103D01*
G03X902327Y658161I-1656J-1124D01*
G01X902298Y658198D01*
X902294Y658204D01*
X902282Y658219D01*
G02X902248Y658278I154J128D01*
G01X902226Y658338D01*
X902223Y658346D01*
G02X902212Y658411I189J65D01*
G01Y687639D01*
G02X902391Y687838I200J0D01*
G03Y690826I-155J1494D01*
G01X902314Y690834D01*
X902212Y690948D01*
Y692639D01*
G02X902391Y692838I200J0D01*
G03Y695826I-155J1494D01*
G01X902314Y695834D01*
X902212Y695948D01*
Y701777D01*
Y701788D01*
G02X902225Y701848I200J-12D01*
G01X902232Y701865D01*
G02X902276Y701924I180J-88D01*
G01X902349Y701989D01*
X902503Y702125D01*
G02X902578Y702167I133J-150D01*
G01X902619Y702179D01*
X902662Y702173D01*
G03X902841Y702163I173J1492D01*
G03Y705167I0J1502D01*
G03X902662Y705157I-6J-1502D01*
G01X902619Y705151D01*
X902578Y705163D01*
G02X902503Y705205I58J192D01*
G01X902280Y705402D01*
G02X902229Y705471I132J151D01*
G01X902212Y705509D01*
Y737840D01*
G03X901625Y739255I-2002J-1D01*
G01X892778Y748102D01*
G02X892734Y748169I142J141D01*
G01X892720Y748203D01*
Y768849D01*
G03X892134Y770264I-2001J0D01*
G01X885447Y776952D01*
X885417Y776982D01*
X885402Y777018D01*
G02X885388Y777093I186J74D01*
G01Y786169D01*
G03X884802Y787584I-2001J0D01*
G01X882752Y789634D01*
G03X881337Y790220I-1415J-1415D01*
G01X876754D01*
G02X876641Y790255I0J200D01*
G02X876612Y790279I112J165D01*
G01X874657Y792233D01*
X871628Y795263D01*
X869574Y797317D01*
G02X869530Y797384I142J141D01*
G01X869516Y797418D01*
Y799133D01*
G02X869579Y799279I200J0D01*
G01X869792Y799479D01*
G02X869941Y799533I137J-146D01*
G03X870035Y799530I95J1499D01*
G03Y802534I0J1502D01*
G03X869941Y802531I1J-1502D01*
G01X869899Y802529D01*
X869823Y802556D01*
X869579Y802785D01*
G02X869516Y802931I137J146D01*
G01Y809489D01*
G03X869457Y809970I-2002J-1D01*
G01X869454Y809982D01*
X869451Y810001D01*
G02X869492Y810153I198J28D01*
G01X869684Y810399D01*
X869702Y810417D01*
G02X869809Y810471I139J-143D01*
G02X869842Y810474I35J-197D01*
G01X878373D01*
G02X878389Y810473I-4J-200D01*
G02X878517Y810413I-15J-199D01*
G01X878539Y810390D01*
X878712Y810051D01*
G02X878733Y809938I-178J-91D01*
G01X878730Y809911D01*
X878711Y809862D01*
X878696Y809842D01*
G03X878414Y808966I1220J-876D01*
G01Y808965D01*
G03X878416Y808894I1502J7D01*
G01Y808886D01*
G03X879916Y807463I1500J79D01*
G03X881418Y808965I0J1502D01*
G01Y808966D01*
G03X881135Y809843I-1502J-1D01*
G01X881126Y809855D01*
G02X881099Y809990I171J104D01*
G02X881117Y810047I198J-31D01*
G01X881150Y810109D01*
Y810111D01*
X881281Y810365D01*
G02X881356Y810445I178J-91D01*
G02X881459Y810474I104J-171D01*
G01X882373D01*
G02X882389Y810473I-4J-200D01*
G02X882517Y810413I-15J-199D01*
G01X882539Y810390D01*
X882712Y810051D01*
G02X882733Y809938I-178J-91D01*
G01X882730Y809911D01*
X882711Y809862D01*
X882696Y809842D01*
G03X882414Y808966I1220J-876D01*
G01Y808965D01*
G03X882416Y808894I1502J7D01*
G01Y808886D01*
G03X883916Y807463I1500J79D01*
G03X885418Y808965I0J1502D01*
G01Y808966D01*
G03X885135Y809843I-1502J-1D01*
G01X885126Y809855D01*
G02X885099Y809990I171J104D01*
G02X885117Y810047I198J-31D01*
G01X885150Y810109D01*
Y810111D01*
X885281Y810365D01*
G02X885356Y810445I178J-91D01*
G02X885459Y810474I104J-171D01*
G01X886373D01*
G02X886389Y810473I-4J-200D01*
G02X886517Y810413I-15J-199D01*
G01X886539Y810390D01*
X886712Y810051D01*
G02X886733Y809938I-178J-91D01*
G01X886730Y809911D01*
X886711Y809862D01*
X886696Y809842D01*
G03X886414Y808966I1220J-876D01*
G01Y808965D01*
G03X886416Y808894I1502J7D01*
G01Y808886D01*
G03X887916Y807463I1500J79D01*
G03X889418Y808965I0J1502D01*
G01Y808966D01*
G03X889135Y809843I-1502J-1D01*
G01X889126Y809855D01*
G02X889099Y809990I171J104D01*
G02X889117Y810047I198J-31D01*
G01X889150Y810109D01*
Y810111D01*
X889281Y810365D01*
G02X889356Y810445I178J-91D01*
G02X889459Y810474I104J-171D01*
G01X894373D01*
G02X894389Y810473I-4J-200D01*
G02X894517Y810413I-15J-199D01*
G01X894539Y810390D01*
X894712Y810051D01*
G02X894733Y809938I-178J-91D01*
G01X894730Y809911D01*
X894711Y809862D01*
X894696Y809842D01*
G03X894414Y808966I1220J-876D01*
G01Y808965D01*
G03X894416Y808894I1502J7D01*
G01Y808886D01*
G03X895916Y807463I1500J79D01*
G03X897418Y808965I0J1502D01*
G01Y808966D01*
G03X897135Y809843I-1502J-1D01*
G01X897126Y809855D01*
G02X897099Y809990I171J104D01*
G02X897117Y810047I198J-31D01*
G01X897150Y810109D01*
Y810111D01*
X897281Y810365D01*
G02X897356Y810445I178J-91D01*
G02X897459Y810474I104J-171D01*
G01X898373D01*
G02X898389Y810473I-4J-200D01*
G02X898517Y810413I-15J-199D01*
G01X898539Y810390D01*
X898712Y810051D01*
G02X898733Y809938I-178J-91D01*
G01X898730Y809911D01*
X898711Y809862D01*
X898696Y809842D01*
G03X898414Y808966I1220J-876D01*
G01Y808965D01*
G03X898416Y808894I1502J7D01*
G01Y808886D01*
G03X899916Y807463I1500J79D01*
G03X901418Y808965I0J1502D01*
G01Y808966D01*
G03X901135Y809843I-1502J-1D01*
G01X901126Y809855D01*
G02X901099Y809990I171J104D01*
G02X901117Y810047I198J-31D01*
G01X901150Y810109D01*
Y810111D01*
X901281Y810365D01*
G02X901356Y810445I178J-91D01*
G02X901459Y810474I104J-171D01*
G01X902302D01*
G02X902420Y810436I1J-200D01*
G01X902443Y810419D01*
X902479Y810370D01*
X902490Y810337D01*
G03X903916Y809307I1426J472D01*
G03X904808Y809601I-1J1502D01*
G02X904911Y809640I120J-160D01*
G01X904966Y809644D01*
X905073Y809590D01*
X905345Y809452D01*
G02X905347Y809451I-88J-179D01*
G02X905446Y809279I-101J-173D01*
G01Y808432D01*
G02X905387Y808290I-200J0D01*
G01X903160Y806063D01*
G02X903018Y806004I-142J141D01*
G01X883198D01*
G03X882274Y805621I0J-1306D01*
G01X879116Y802463D01*
G03X878734Y801541I924J-923D01*
G01Y793594D01*
X878726Y793579D01*
G03X878538Y792851I1316J-728D01*
G03X881542I1502J0D01*
G03X881370Y793551I-1502J2D01*
G01X881358Y793573D01*
X881346Y793620D01*
Y800399D01*
G02X881363Y800419I161J-119D01*
G01X881753Y800809D01*
G02X881782Y800833I141J-141D01*
G02X881831Y800857I112J-166D01*
G01X881840Y800860D01*
G02X881957Y800858I55J-192D01*
G01X882296Y800747D01*
G02X882387Y800685I-63J-190D01*
G01X882404Y800664D01*
X882426Y800615D01*
X882431Y800587D01*
Y800586D01*
G03X882502Y800306I1485J228D01*
G03X883138Y799530I1413J510D01*
G01X883139D01*
X883140Y799529D01*
G02X883235Y799374I-104J-171D01*
G01X883239Y799197D01*
Y799195D01*
X883244Y799034D01*
Y799025D01*
G02X883185Y798886I-200J3D01*
G01X883157Y798858D01*
X883142Y798848D01*
G03X882500Y797616I861J-1232D01*
G03X885504I1502J0D01*
G03X884800Y798889I-1503J0D01*
G01X884799Y798890D01*
X884779Y798903D01*
G02X884688Y799028I104J171D01*
G02X884683Y799068I195J45D01*
G01X884678Y799234D01*
Y799236D01*
X884674Y799403D01*
G02X884680Y799455I200J3D01*
G01X884689Y799492D01*
X884729Y799551D01*
X884762Y799573D01*
G03X885418Y800815I-846J1241D01*
G03X885405Y801015I-1502J3D01*
G03X885375Y801173I-1489J-201D01*
G03X885319Y801353I-1460J-355D01*
G03X884160Y802298I-1403J-538D01*
G01X884158D01*
G03X884153Y802299I-42J-195D01*
G01X884102Y802304D01*
X884064Y802330D01*
G02X883996Y802408I111J166D01*
G01X883988Y802424D01*
G02X883987Y802426I177J90D01*
G01X883871Y802781D01*
G02X883865Y802862I192J55D01*
G02X883915Y802971I198J-25D01*
G01X884329Y803383D01*
G02X884338Y803390I127J-154D01*
G01X903642D01*
G03X904566Y803773I0J1306D01*
G01X907824Y807031D01*
G03X908206Y807953I-924J923D01*
G01Y809654D01*
X908270Y809748D01*
G03X909785Y808946I1515J1030D01*
G03X911560Y810324I0J1832D01*
G02X911754Y810474I194J-50D01*
G01X911828D01*
G03X911850Y810475I-44J1202D01*
G01X911857Y810476D01*
X911896D01*
G02X912062Y810387I0J-200D01*
G01X912090Y810347D01*
X912100Y810248D01*
X910700Y806870D01*
G02X910657Y806805I-185J76D01*
G01X905513Y801661D01*
G03X905230Y801237I924J-923D01*
G01X905224Y801223D01*
G02X905181Y801159I-184J77D01*
G01X905070Y801048D01*
G03X904796Y800637I897J-895D01*
G01X904035Y798805D01*
G02X903992Y798740I-185J76D01*
G01X899136Y793885D01*
G02X899071Y793842I-141J142D01*
G01X898923Y793780D01*
X898874Y793785D01*
G03X898738Y793791I-134J-1496D01*
G01X898737D01*
G03Y790787I0J-1502D01*
G03X899892Y791328I0J1503D01*
G01X899893Y791329D01*
G02X899969Y791385I153J-129D01*
G01X900348Y791542D01*
G03X900608Y791687I-502J1206D01*
G01X900627Y791700D01*
X900966Y791841D01*
X901050Y791876D01*
G03X901461Y792150I-484J1171D01*
G01X905655Y796344D01*
G03X905929Y796755I-897J895D01*
G01X906076Y797108D01*
G02X906119Y797173I185J-76D01*
G01X906371Y797424D01*
G03X906654Y797848I-924J923D01*
G01X907488Y799860D01*
G02X907531Y799925I185J-76D01*
G01X912873Y805267D01*
G03X913147Y805678I-897J895D01*
G01X914871Y809839D01*
X914872Y809841D01*
X914880Y809863D01*
X914883Y809869D01*
G03X914901Y809912I-1159J510D01*
G01X914916Y809953D01*
G03X914938Y810027I-1203J398D01*
G01Y810033D01*
X914945Y810058D01*
G03X914967Y810161I-1226J316D01*
G01Y810163D01*
X914969Y810177D01*
G03X914980Y810287I-1253J181D01*
G01X914982Y810326D01*
X915014Y810395D01*
X915042Y810422D01*
G02X915179Y810476I137J-146D01*
G01X915575D01*
X915582Y810475D01*
G03X915604Y810474I66J1201D01*
G01X916494D01*
X916533Y810457D01*
X916540Y810454D01*
X916637Y810408D01*
X916642Y810405D01*
G03X916668Y810375I1151J971D01*
G01X918090Y803225D01*
G02X918094Y803186I-196J-40D01*
G01Y800277D01*
G02X918079Y800200I-200J-1D01*
G01X917322Y798375D01*
G02X917279Y798310I-185J76D01*
G01X916313Y797344D01*
X916240Y797314D01*
X916208D01*
G02X916179Y797316I-1J200D01*
G01X916139Y797323D01*
G02X916107Y797332I38J196D01*
G01X916000Y797370D01*
X915998D01*
X915829Y797430D01*
G02X915738Y797495I66J189D01*
G01X915721Y797516D01*
X915700Y797570D01*
X915698Y797599D01*
G03X914202Y798962I-1496J-139D01*
G03X912751Y797848I0J-1502D01*
G01X912745Y797828D01*
G02X912615Y797708I-187J72D01*
G01X912608Y797706D01*
X912562Y797694D01*
X912558Y797693D01*
X912317Y797626D01*
X912315D01*
X912279Y797616D01*
G02X912174Y797615I-54J192D01*
G02X912085Y797665I50J194D01*
G01X912084Y797666D01*
G03X911028Y798100I-1056J-1068D01*
G03X910828Y798087I-3J-1502D01*
G03X909933Y797627I200J-1489D01*
G03X909554Y796888I1095J-1029D01*
G01Y796887D01*
G02X909506Y796792I-196J39D01*
G01X909488Y796772D01*
X909444Y796744D01*
X909390Y796727D01*
X909384Y796724D01*
X909087Y796628D01*
G02X908981Y796623I-62J190D01*
G02X908890Y796671I45J195D01*
G01X908889Y796672D01*
G03X907866Y797074I-1023J-1101D01*
G03Y794070I0J-1502D01*
G03X909179Y794842I0J1503D01*
G01X909194Y794869D01*
G03X909340Y795281I-1328J703D01*
G01Y795282D01*
G02X909389Y795378I196J-40D01*
G02X909476Y795434I148J-134D01*
G01X909504Y795443D01*
X909510Y795446D01*
X909807Y795542D01*
G02X909913Y795547I62J-190D01*
G02X910004Y795499I-45J-195D01*
G01X910005Y795498D01*
G03X911028Y795096I1023J1101D01*
G03X912485Y796231I0J1503D01*
G02X912575Y796354I194J-48D01*
G01X912637Y796391D01*
X912690Y796387D01*
G03X912768Y796392I26J198D01*
G01X912818Y796406D01*
X912952Y796443D01*
G02X913004Y796450I52J-193D01*
G01X913006D01*
G02X913145Y796393I-1J-200D01*
G01X913147Y796391D01*
G03X913151Y796387I1064J1060D01*
G03X913153Y796385I142J140D01*
G03X913485Y796140I1049J1075D01*
G01X913509Y796127D01*
X913529Y796108D01*
G02X913591Y795953I-138J-145D01*
G01X913581Y795752D01*
X913573Y795594D01*
G02X913450Y795419I-200J10D01*
G01X902536Y790898D01*
X900792Y790175D01*
G02X900715Y790160I-76J185D01*
G01X898479D01*
G02X898414Y790171I0J200D01*
G01X898372Y790187D01*
G02X898364Y790190I66J188D01*
G01X898210Y790254D01*
X897318Y790623D01*
X897026Y790744D01*
G02X897017Y790748I77J185D01*
G01X890791Y793693D01*
G02X890716Y793754I85J181D01*
G03X889516Y794353I-1200J-903D01*
G03X888014Y792851I0J-1502D01*
G03X889515Y791349I1502J0D01*
G01X889517D01*
G03X889580Y791350I8J1502D01*
G01X889629Y791352D01*
X896341Y788177D01*
G03X896400Y788151I556J1182D01*
G01X897748Y787593D01*
G03X898246Y787494I499J1207D01*
G01X900990D01*
G03X901488Y787593I-1J1306D01*
G01X916216Y793692D01*
G03X916640Y793975I-499J1207D01*
G01X919339Y796674D01*
G03X919622Y797098I-924J923D01*
G01X920607Y799477D01*
G03X920613Y799492I-1210J493D01*
G01X920647Y799575D01*
G02X920679Y799592I109J-167D01*
G01X920701Y799601D01*
X920860Y799635D01*
X921039Y799674D01*
G02X921069Y799676I28J-198D01*
G01X921116D01*
X921186Y799648D01*
X921215Y799620D01*
G03X921563Y799365I1138J1188D01*
G03X922221Y799169I788J1444D01*
G01X922264Y799165D01*
X922300Y799146D01*
G02X922364Y799090I-97J-175D01*
G01X922378Y799072D01*
X922384Y799062D01*
X922433Y798980D01*
X922440Y798968D01*
G02X922462Y798878I-178J-91D01*
G01Y798790D01*
X922451Y798758D01*
G03X922370Y798281I1421J-487D01*
G01Y798261D01*
G03X923872Y796769I1502J10D01*
G03X925374Y798271I0J1502D01*
G03X924089Y799757I-1502J0D01*
G01X924079Y799759D01*
X924049Y799766D01*
G02X923939Y799854I62J190D01*
G01X923846Y800010D01*
X923843Y800059D01*
X923840Y800105D01*
X923860Y800155D01*
X923861Y800158D01*
X923864Y800166D01*
X923866Y800170D01*
G03X923997Y800809I-1513J643D01*
G03X922352Y802454I-1645J0D01*
G01X922351D01*
G03X921365Y802126I0J-1645D01*
G01X921358Y802121D01*
X921338Y802106D01*
X921266Y802082D01*
G02X921186Y802072I-64J189D01*
G02X921110Y802094I17J199D01*
G01X920950Y802177D01*
G02X920842Y802354I92J178D01*
G01Y802450D01*
G03X920818Y802697I-1266J2D01*
G01X920710Y803243D01*
G02X920706Y803282I196J40D01*
G01Y803336D01*
G03X920681Y803590I-1306J0D01*
G01X919360Y810234D01*
Y810276D01*
G02X919532Y810474I200J0D01*
G01X920235D01*
G02X920410Y810370I0J-200D01*
G01X920417Y810355D01*
G03X920662Y809973I1373J611D01*
G03X923163Y810355I1128J991D01*
G01X923175Y810383D01*
X923212Y810426D01*
X923236Y810442D01*
G02X923345Y810474I109J-168D01*
G01X936899D01*
G02X936949Y810468I1J-200D01*
G02X937079Y810360I-51J-194D01*
G01X937117Y810280D01*
X937233Y810034D01*
G02X937213Y809829I-181J-86D01*
G01X937205Y809820D01*
G03X937202Y809817I1056J-1060D01*
G01X937199Y809813D01*
X937192Y809805D01*
X937184Y809795D01*
X937183Y809794D01*
X937180Y809790D01*
X937175Y809784D01*
G03X936855Y808857I1183J-927D01*
G01Y808856D01*
G03X938357Y807354I1502J0D01*
G03X939859Y808837I0J1502D01*
G01Y808859D01*
G03X939856Y808966I-1502J11D01*
G01X939853Y809016D01*
X939926Y809179D01*
X939928Y809216D01*
G03X939885Y809351I-200J11D01*
G01X939544Y809778D01*
G03X939533Y809791I-1152J-963D01*
G01X939531Y809793D01*
X939524Y809801D01*
G03X939516Y809812I-1219J-878D01*
G01X939502Y809828D01*
G02X939484Y809865I170J106D01*
G01X939470Y809904D01*
Y809966D01*
G02X939489Y810051I200J0D01*
G01X939597Y810280D01*
X939635Y810360D01*
G02X939765Y810468I181J-86D01*
G02X939815Y810474I49J-194D01*
G01X943373D01*
G02X943547Y810372I0J-200D01*
G01X943561Y810347D01*
X943716Y810046D01*
X943721Y810031D01*
X943723Y810024D01*
G02X943696Y809842I-189J-65D01*
G01X943691Y809836D01*
G03X943685Y809828I157J-124D01*
G01X943659Y809789D01*
X943637Y809753D01*
G03X943414Y808966I1279J-788D01*
G01Y808944D01*
G03X944916Y807463I1502J21D01*
G03X946361Y808554I0J1502D01*
G01X946364Y808563D01*
G02X946504Y808693I189J-64D01*
G01X946658Y808733D01*
X946848Y808782D01*
G02X947028Y808727I38J-196D01*
G01X949262Y806493D01*
G03X949305Y806460I142J141D01*
G01X949328Y806447D01*
X955134Y800641D01*
G03X955187Y800591I853J851D01*
G01X955197Y800582D01*
X955442Y800337D01*
X955448Y800332D01*
X955459Y800321D01*
X955495Y800306D01*
G03X955573Y800290I78J184D01*
G01X955945D01*
G03X955982Y800288I83J1200D01*
G01X956135D01*
G02X956183Y800282I-1J-200D01*
G02X956298Y800204I-48J-194D01*
G02X956319Y800165I-164J-114D01*
G01X956367Y800051D01*
X956388Y800001D01*
G02X956400Y799964I-183J-80D01*
G01X956405Y799938D01*
G02X956406Y799936I-172J-87D01*
G01Y799932D01*
G02X956397Y799829I-197J-35D01*
G01X956392Y799817D01*
X956358Y799739D01*
X956331Y799712D01*
G03X955850Y798553I1156J-1159D01*
G03X959124I1637J0D01*
G03X958660Y799694I-1637J-1D01*
G01X958658Y799696D01*
X958645Y799710D01*
X958601Y799774D01*
X958593Y799792D01*
X958581Y799815D01*
G02X958561Y799899I180J87D01*
G01X958560Y799940D01*
X958577Y799981D01*
X958654Y800165D01*
G02X958660Y800178I184J-77D01*
G02X958838Y800288I179J-90D01*
G01X966222D01*
G02X966339Y800228I-28J-198D01*
G01X966545Y800012D01*
G02X966594Y799888I-151J-131D01*
G01Y799863D01*
X966593Y799856D01*
Y799840D01*
X966592Y799832D01*
Y799790D01*
G03Y799788I1502J-1D01*
G03X969596Y799790I1502J4D01*
G01Y799793D01*
G03X969594Y799865I-1502J-6D01*
G01Y799880D01*
G02X969643Y800011I200J0D01*
G01X969778Y800153D01*
X969847Y800226D01*
X969851Y800230D01*
G02X969991Y800288I141J-142D01*
G01X975377D01*
G03X975425Y800290I-26J1203D01*
G01X979011D01*
G03X979059Y800288I74J1201D01*
G01X984349D01*
G03X984386Y800290I-46J1202D01*
G01X987019D01*
G03X987060Y800288I79J1201D01*
G01X987552D01*
X987558Y800290D01*
X987730D01*
G03X987808Y800306I0J200D01*
G01X987844Y800321D01*
X987855Y800332D01*
X987861Y800337D01*
X987989Y800465D01*
X988005Y800471D01*
X988174Y800646D01*
G02X988176Y800648I142J-140D01*
G01X994217Y806689D01*
G03X994267Y806742I-851J853D01*
G01X994276Y806752D01*
X994362Y806838D01*
G02X994392Y806863I142J-140D01*
G02X994407Y806872I110J-167D01*
G01X994427Y806882D01*
G02X994679Y806795I77J-185D01*
G02X994704Y806687I-175J-97D01*
G01X994701Y806632D01*
X994678Y806577D01*
Y806566D01*
X994680Y806564D01*
Y722987D01*
G03X994791Y722505I1240J32D01*
G03X995044Y722141I1129J515D01*
G01X1001253Y715933D01*
G03X1001667Y715659I878J876D01*
G03X1002127Y715570I461J1151D01*
G01X1016158D01*
G03X1016493Y715626I-35J1240D01*
G01X1016506Y715630D01*
X1016574Y715642D01*
X1016604D01*
G03X1016746Y715701I0J200D01*
G01X1016840Y715795D01*
X1016857Y715810D01*
X1016866Y715818D01*
X1016871Y715822D01*
X1016874Y715824D01*
G03X1016996Y715929I-746J991D01*
G01X1022877Y721811D01*
G03X1022982Y721931I-879J875D01*
G01X1022983Y721933D01*
X1022987Y721938D01*
X1023012Y721967D01*
X1023107Y722062D01*
G03X1023166Y722204I-141J142D01*
G01Y722235D01*
X1023177Y722299D01*
X1023181Y722312D01*
G03X1023238Y722683I-1183J372D01*
G01Y754943D01*
G02X1023344Y755119I200J-1D01*
G01X1023463Y755182D01*
X1023465D01*
X1023554Y755228D01*
X1023564Y755233D01*
G02X1023646Y755251I83J-182D01*
G01X1023764D01*
G02X1023853Y755230I0J-200D01*
G01X1023875Y755219D01*
X1023885Y755213D01*
X1023887Y755212D01*
X1023888Y755211D01*
G03X1024682Y754983I795J1273D01*
G01X1024684D01*
G03Y757987I0J1502D01*
G01X1024683D01*
G03X1023828Y757719I1J-1501D01*
G02X1023726Y757683I-115J164D01*
G01X1023671Y757680D01*
X1023464Y757788D01*
X1023322Y757862D01*
X1023296Y757888D01*
G02X1023283Y757903I144J138D01*
G02X1023238Y758029I155J126D01*
G01Y770076D01*
G03X1022895Y770931I-1240J-1D01*
G01X1022805Y771025D01*
X1022736Y771098D01*
X1022709Y771126D01*
X1022694Y771142D01*
G03X1022577Y771247I-885J-869D01*
G02X1022560Y771262I124J157D01*
G03X1022522Y771291I-139J-143D01*
G01X1022517Y771294D01*
X1022515Y771295D01*
X1022505Y771301D01*
X1022488Y771311D01*
X1022485Y771313D01*
X1022480Y771316D01*
X1022477Y771318D01*
G03X1022333Y771398I-673J-1042D01*
G01X1022150Y771484D01*
G03X1022074Y771503I-86J-181D01*
G01X1021871Y771513D01*
X1021869D01*
G02Y772435I26J461D01*
G01X1021871D01*
X1022074Y772445D01*
G03X1022150Y772464I-10J200D01*
G01X1022333Y772550D01*
G03X1022706Y772819I-526J1123D01*
G01X1022855Y772975D01*
X1022857Y772977D01*
X1022912Y773036D01*
G03X1023120Y773345I-913J839D01*
G03X1023238Y773871I-1122J528D01*
G01Y817077D01*
G03X1023207Y817340I-1239J-13D01*
G01X1023206Y817346D01*
Y817388D01*
G03X1023178Y817490I-200J0D01*
G01X1023153Y817532D01*
X1023137Y817564D01*
X1023135Y817569D01*
G03X1023123Y817595I-1131J-506D01*
G01X1023122Y817597D01*
X1023104Y817637D01*
G03X1023029Y817765I-1106J-562D01*
G02X1023012Y817797I167J109D01*
G02X1023002Y817927I184J80D01*
G02X1023043Y818005I193J-52D01*
G03X1023071Y819911I-1149J970D01*
G01X1023050Y819936D01*
X1023023Y820007D01*
G02X1023015Y820099I190J63D01*
G01X1023016Y820107D01*
G02X1023066Y820209I197J-33D01*
G01X1023114Y820261D01*
G03X1023168Y820397I-146J137D01*
G01Y820429D01*
X1023178Y820491D01*
X1023182Y820504D01*
Y820505D01*
G03X1023184Y820509I-176J90D01*
G03X1023238Y820871I-1186J362D01*
G01Y832105D01*
G03X1022571Y833204I-1240J-1D01*
G01X1022457Y833263D01*
X1022423Y833282D01*
X1022419Y833284D01*
X1022369Y833310D01*
X1022368D01*
X1022309Y833340D01*
G02X1022224Y833420I89J179D01*
G01X1022210Y833445D01*
X1022197Y833503D01*
X1022200Y833534D01*
G03X1022205Y833656I-1497J122D01*
G01Y833663D01*
G03X1022200Y833784I-1502J-1D01*
G02X1022309Y833979I199J17D01*
G01X1022439Y834045D01*
X1022457Y834055D01*
X1022571Y834114D01*
G03X1023238Y835213I-573J1100D01*
G01Y836105D01*
G03X1022571Y837204I-1240J-1D01*
G01X1022457Y837263D01*
X1022423Y837282D01*
X1022419Y837284D01*
X1022307Y837342D01*
G02X1022225Y837422I93J177D01*
G01X1022211Y837447D01*
X1022199Y837505D01*
X1022201Y837535D01*
G03X1022205Y837656I-1499J110D01*
G01Y837662D01*
G03X1022200Y837783I-1502J-1D01*
G01X1022198Y837811D01*
X1022209Y837867D01*
X1022224Y837894D01*
G02X1022301Y837973I176J-95D01*
G01X1022322Y837985D01*
G02X1022419Y838010I97J-175D01*
G01X1022431D01*
G03X1022573Y838069I0J200D01*
G01X1022672Y838169D01*
X1022701Y838193D01*
X1022708Y838198D01*
G03X1023238Y839213I-710J1017D01*
G01Y846923D01*
G03X1022746Y847890I-1240J-22D01*
G01X1022266Y848238D01*
G03X1022181Y848274I-118J-161D01*
G01X1021964Y848310D01*
X1021962D01*
X1021812Y848337D01*
X1021801Y848340D01*
X1021759Y848352D01*
G03X1021705Y848360I-56J-192D01*
G01X1021687D01*
X1021647Y848367D01*
X1021409Y848288D01*
X1021401Y848286D01*
X1021346Y848267D01*
G02X1021317Y848261I-108J449D01*
G01X1021306Y848259D01*
G02X1021240Y848250I-95J452D01*
G01X1021233D01*
G02Y849174I-12J462D01*
G01X1021244D01*
G02X1021306Y849165I-35J-460D01*
G01X1021315Y849163D01*
X1021321Y849162D01*
G02X1021346Y849157I-78J-455D01*
G01X1021401Y849138D01*
X1021409Y849136D01*
X1021599Y849073D01*
G03X1021697Y849066I63J190D01*
G01X1021962Y849114D01*
X1021964D01*
X1022181Y849150D01*
G03X1022266Y849186I-33J197D01*
G01X1022746Y849534D01*
G03X1023238Y850501I-748J989D01*
G01Y882641D01*
G02X1023269Y882748I200J0D01*
G01X1023285Y882772D01*
X1023325Y882808D01*
X1023352Y882821D01*
X1023356Y882823D01*
X1023426Y882853D01*
X1023641Y882945D01*
G02X1023644Y882946I65J-189D01*
G03X1023650Y882948I-60J191D01*
G02X1023794Y882947I71J-187D01*
G01X1023874Y882915D01*
X1023901Y882890D01*
G03X1024913Y882498I1012J1110D01*
G03Y885502I0J1502D01*
G03X1023901Y885110I0J-1502D01*
G01X1023874Y885085D01*
X1023797Y885053D01*
G02X1023762Y885043I-72J186D01*
G02X1023641Y885055I-42J196D01*
G01X1023426Y885147D01*
X1023320Y885193D01*
G02X1023214Y885301I79J183D01*
G02X1023203Y885417I185J76D01*
G01X1023234Y885567D01*
G03X1023238Y885607I-196J40D01*
G01Y901047D01*
G03X1022992Y901787I-1240J-1D01*
G03X1022875Y901922I-994J-743D01*
G01X1018829Y905967D01*
G03X1018415Y906241I-878J-876D01*
G03X1017955Y906330I-461J-1151D01*
G01X1006907D01*
G03X1006859Y906324I1J-200D01*
G01X1006846Y906320D01*
X1006803Y906304D01*
G02X1006734Y906292I-68J188D01*
G01X1006630D01*
X1006625D01*
G02X1006537Y906315I5J200D01*
G01X1006529Y906320D01*
X1006490Y906343D01*
X1006463Y906370D01*
G03X1005414Y906797I-1049J-1075D01*
G01X1005413D01*
G03X1005411I-1J-1502D01*
G03X1005349Y906796I-7J-1502D01*
G01X1005330Y906795D01*
X1005329D01*
G03X1004349Y906355I85J-1500D01*
G01X1004343Y906349D01*
X1004306Y906316D01*
X1004265Y906303D01*
X1004232Y906292D01*
X1004026D01*
X1004004Y906297D01*
G03X1003726Y906330I-284J-1207D01*
G01X981237D01*
G02X981070Y906421I1J200D01*
G01X980858Y906745D01*
X980850Y906845D01*
X980871Y906892D01*
G03X981000Y907500I-1373J609D01*
G03X977996I-1502J0D01*
G03X978191Y906760I1502J0D01*
G01X978210Y906727D01*
X978220Y906651D01*
X978135Y906309D01*
X978090Y906247D01*
X978068Y906233D01*
G03X978024Y906199I99J-174D01*
G01X978023Y906198D01*
X977929Y906104D01*
X977912Y906089D01*
X977903Y906081D01*
X977898Y906077D01*
X977895Y906075D01*
G03X977772Y905969I746J-990D01*
G01X974723Y902919D01*
G03X974618Y902799I879J-875D01*
G01X974617Y902797D01*
X974613Y902792D01*
X974588Y902763D01*
X974493Y902668D01*
G03X974434Y902526I141J-142D01*
G01Y902495D01*
X974423Y902431D01*
X974419Y902418D01*
G03X974362Y902047I1183J-372D01*
G01Y880807D01*
G02X973679Y880525I-400J1D01*
G01X973188Y881016D01*
G03X973140Y881061I-848J-856D01*
G01X973130Y881070D01*
X972885Y881315D01*
X972879Y881320D01*
X972868Y881331D01*
X972832Y881346D01*
G03X972754Y881362I-78J-184D01*
G01X972382D01*
G03X972345Y881364I-83J-1200D01*
G01X947749D01*
G02X947663Y881384I1J200D01*
G01X947586Y881424D01*
X947579Y881428D01*
X947540Y881452D01*
X947517Y881484D01*
G03X945111Y881507I-1212J-892D01*
G03X945102Y881495I1199J-909D01*
G01X945100Y881493D01*
X945090Y881480D01*
X945087Y881476D01*
G02X945017Y881420I-157J124D01*
G01X944975Y881399D01*
X944973D01*
X944950Y881387D01*
X944928Y881376D01*
X944881Y881364D01*
X930309D01*
G03X930272Y881362I46J-1202D01*
G01X927168D01*
G03X927127Y881364I-79J-1201D01*
G01X926947D01*
G03X926906Y881362I38J-1203D01*
G01X924018D01*
G03X923977Y881364I-79J-1201D01*
G01X923798D01*
G03X923757Y881362I38J-1203D01*
G01X920869D01*
G03X920828Y881364I-79J-1201D01*
G01X920648D01*
G03X920607Y881362I38J-1203D01*
G01X917719D01*
G03X917678Y881364I-79J-1201D01*
G01X917499D01*
G03X917458Y881362I38J-1203D01*
G01X914570D01*
G03X914529Y881364I-79J-1201D01*
G01X914349D01*
G03X914308Y881362I38J-1203D01*
G01X911420D01*
G03X911379Y881364I-79J-1201D01*
G01X911199D01*
G03X911158Y881362I38J-1203D01*
G01X908270D01*
G03X908229Y881364I-79J-1201D01*
G01X908050D01*
G03X908009Y881362I38J-1203D01*
G01X904905D01*
G03X904868Y881364I-83J-1200D01*
G01X901964D01*
G03X901927Y881362I46J-1202D01*
G01X898823D01*
G03X898782Y881364I-79J-1201D01*
G01X898603D01*
G03X898562Y881362I38J-1203D01*
G01X895674D01*
G03X895633Y881364I-79J-1201D01*
G01X895453D01*
G03X895412Y881362I38J-1203D01*
G01X892524D01*
G03X892483Y881364I-79J-1201D01*
G01X892303D01*
G03X892262Y881362I38J-1203D01*
G01X889374D01*
G03X889333Y881364I-79J-1201D01*
G01X889154D01*
G03X889113Y881362I38J-1203D01*
G01X886225D01*
G03X886184Y881364I-79J-1201D01*
G01X886004D01*
G03X885963Y881362I38J-1203D01*
G01X882859D01*
G03X882822Y881364I-83J-1200D01*
G01X872258D01*
G02X872114Y881426I1J200D01*
G01X872026Y881517D01*
X871913Y881634D01*
G02X871894Y881658I147J136D01*
G01X871899Y881741D01*
G03X871902Y881871I-2303J118D01*
G01Y897031D01*
X871923Y897092D01*
X871941Y897116D01*
X872043Y897147D01*
G03Y900021I-443J1437D01*
G01X871972Y900043D01*
X871922Y900077D01*
X871902Y900103D01*
Y906056D01*
G02X871942Y906176I200J0D01*
G02X872460Y906283I320J-241D01*
G02X872503Y906250I-99J-174D01*
G01X874535Y904217D01*
G02X874537Y904215I-140J-142D01*
G01X874676Y904071D01*
G03X874745Y904024I145J138D01*
G01X875125Y903871D01*
G03X875200Y903856I76J185D01*
G01X887309D01*
G03X888200Y904248I0J1209D01*
G01X888217Y904256D01*
X888242Y904269D01*
X888329Y904285D01*
G02X888332Y904286I64J-188D01*
G01X888342Y904288D01*
X888380Y904293D01*
G02X888489Y904277I27J-198D01*
G01X888502Y904270D01*
X888537Y904254D01*
G03X889176Y904112I639J1365D01*
G01X889179D01*
G03X889856Y904273I-1J1507D01*
G01X889877Y904283D01*
X889922Y904294D01*
X889969D01*
X890089Y904273D01*
G02X890156Y904248I-35J-197D01*
G03X891047Y903856I891J817D01*
G01X907054D01*
G03X907186Y903863I2J1209D01*
G02X907207Y903864I20J-199D01*
G01X907325D01*
X907356Y903879D01*
G03X907366Y903883I-69J187D01*
G01X907436Y903916D01*
G02X907455Y903924I87J-180D01*
G03X907682Y904032I-403J1140D01*
G02X907702Y904043I106J-169D01*
G01X907768Y904074D01*
G03X907778Y904079I-84J181D01*
G01X907809Y904093D01*
X907889Y904191D01*
X907891Y904193D01*
G03X907940Y904242I-830J879D01*
G01X907941Y904243D01*
G02X907949Y904249I124J-157D01*
G02X908030Y904282I114J-164D01*
G01X908156Y904304D01*
X908192Y904297D01*
X908214Y904293D01*
X908256Y904283D01*
X908276Y904273D01*
G03X908320Y904252I669J1345D01*
G01X908325Y904250D01*
X908336Y904246D01*
G03X908347Y904241I626J1363D01*
G01X908355Y904238D01*
X908365Y904233D01*
G03X908403Y904219I88J180D01*
G01X908410Y904217D01*
G03X908472Y904196I513J1412D01*
G01X908473D01*
X908491Y904190D01*
X908492D01*
X908518Y904183D01*
G03X908524Y904181I478J1424D01*
G01X908527Y904180D01*
X908538Y904177D01*
G03X908676Y904148I378J1454D01*
G03X909119Y904141I245J1482D01*
G01X909142Y904144D01*
G03X909568Y904274I-221J1486D01*
G01X909589Y904284D01*
X909639Y904295D01*
X909641D01*
X909676Y904303D01*
X909812Y904282D01*
X909818Y904281D01*
G02X909869Y904265I-34J-197D01*
G01X909887Y904256D01*
X909998Y904122D01*
G03X910066Y904068I155J126D01*
G01X910472Y903875D01*
G03X910558Y903856I85J181D01*
G01X919834D01*
X919948Y903750D01*
X919954Y903680D01*
G03X922948I1497J120D01*
G01X922954Y903750D01*
X923068Y903856D01*
X929494D01*
G03X929624Y903904I0J200D01*
G01X929625Y903905D01*
G03X930800Y903338I1175J934D01*
G03X931967Y903894I0J1503D01*
G02X932201Y903952I155J-126D01*
G03X932673Y903856I472J1113D01*
G01X952552D01*
G03X952684Y903863I2J1209D01*
G02X952705Y903864I20J-199D01*
G01X952747D01*
G03X952822Y903879I-1J200D01*
G01X952861Y903895D01*
G02X952882Y903902I74J-186D01*
G03X953123Y903998I-325J1165D01*
G02X953141Y904007I98J-174D01*
G01X953199Y904031D01*
G03X953206Y904034I-75J185D01*
G01X953238Y904047D01*
X953264Y904074D01*
G03X953267Y904077I-140J143D01*
G01X953313Y904124D01*
G02X953327Y904137I143J-140D01*
G03X953407Y904211I-780J924D01*
G01X974213Y925016D01*
G02X974215Y925018I142J-140D01*
G01X974359Y925157D01*
G03X974406Y925226I-138J145D01*
G01X974559Y925606D01*
G03X974574Y925681I-185J76D01*
G01Y932748D01*
G03X974567Y932880I-1209J2D01*
G02X974566Y932901I199J20D01*
G01Y938225D01*
G02X974567Y938246I200J1D01*
G03X974574Y938377I-1202J130D01*
G01Y991665D01*
X974566Y991685D01*
Y997989D01*
G02X974570Y998027I200J-2D01*
G02X974623Y998129I196J-37D01*
G01X975513Y999019D01*
G02X975615Y999072I139J-143D01*
G02X975653Y999076I40J-196D01*
G01X983620D01*
G03X983696Y999091I0J200D01*
G01X983771Y999123D01*
G02X983832Y999135I69J-188D01*
G01X997944D01*
G02X997981Y999131I-3J-200D01*
G01X998030Y999119D01*
X998053Y999114D01*
X998140Y999070D01*
X998167Y999039D01*
X998240Y998956D01*
X998343Y998839D01*
G02X998388Y998713I-155J-126D01*
G01Y998689D01*
X998387Y998677D01*
G03X998377Y998507I1492J-173D01*
G01Y998506D01*
G03X999879Y997005I1502J1D01*
G03X1001381Y998507I0J1502D01*
G03X1001370Y998687I-1502J-1D01*
G01X1001365Y998730D01*
X1001377Y998769D01*
G02X1001417Y998840I191J-61D01*
G01X1001518Y998955D01*
Y998957D01*
X1001616Y999067D01*
G02X1001766Y999135I150J-132D01*
G01X1068303D01*
G02X1068343Y999130I-5J-200D01*
G01X1068394Y999115D01*
G02X1068489Y999038I-72J-186D01*
G01X1068642Y998791D01*
X1068656Y998769D01*
X1068667Y998734D01*
G02X1068675Y998678I-192J-56D01*
G01Y998585D01*
X1068666Y998544D01*
X1068655Y998522D01*
G03X1068507Y997870I1356J-651D01*
G01Y997823D01*
G03X1070009Y996358I1502J37D01*
G03X1071511Y997824I0J1502D01*
G01Y997861D01*
G03X1071366Y998505I-1502J0D01*
G03X1071364Y998509I-180J-87D01*
G03X1071360Y998517I-1345J-668D01*
G01X1071358Y998521D01*
X1071353Y998533D01*
X1071338Y998573D01*
X1071332Y998596D01*
X1071321Y998636D01*
X1071326Y998675D01*
G02X1071354Y998751I198J-30D01*
G01X1071465Y998935D01*
X1071528Y999039D01*
G02X1071542Y999060I173J-100D01*
G02X1071699Y999135I156J-125D01*
G01X1122247D01*
G02X1122279Y999132I-3J-200D01*
G01X1122281D01*
G02X1122387Y999078I-34J-197D01*
G01X1124229Y997236D01*
G02X1124283Y997129I-143J-139D01*
G02X1124286Y997096I-197J-35D01*
G01Y993566D01*
G02X1124275Y993502I-200J1D01*
G01X1092461Y899506D01*
G02X1092341Y899464I-123J158D01*
G01X1092140Y899460D01*
X1091967Y899457D01*
G02X1091852Y899492I-2J200D01*
G01X1091827Y899509D01*
X1091790Y899555D01*
X1091778Y899585D01*
G03X1090375Y900549I-1403J-539D01*
G03X1088873Y899047I0J-1502D01*
G03X1090348Y897545I1502J0D01*
G01X1090377D01*
G03X1091140Y897754I-1J1502D01*
G02X1091188Y897774I100J-173D01*
G01X1091266Y897796D01*
G02X1091390Y897754I1J-200D01*
G01X1091400Y897746D01*
X1091665Y897535D01*
G02X1091682Y897520I-124J-157D01*
G01X1091699Y897503D01*
G02X1091751Y897411I-142J-141D01*
G01X1078459Y858141D01*
G02X1078430Y858122I-124J157D01*
G01X1078370Y858098D01*
G03X1077418Y856700I550J-1398D01*
G03X1077634Y855924I1502J0D01*
G01X1077649Y855900D01*
X1077655Y855889D01*
X1077657Y855882D01*
G02X1077654Y855763I-192J-55D01*
G01X1031500Y719401D01*
G02X1031406Y719360I-124J157D01*
G01X1031067Y719319D01*
X1031063D01*
X1031039Y719317D01*
G02X1030932Y719336I-20J199D01*
G01X1030907Y719348D01*
X1030867Y719384D01*
X1030851Y719408D01*
G03X1029582Y720105I-1269J-807D01*
G01X1029581D01*
G03X1028917Y719950I0J-1502D01*
G01X1028877Y719930D01*
X1028790Y719928D01*
X1028468Y720069D01*
G02X1028356Y720194I79J184D01*
G01Y720195D01*
G03X1026916Y721271I-1440J-426D01*
G03X1025414Y719769I0J-1502D01*
G03X1026017Y718566I1502J0D01*
G02X1026091Y718455I-120J-160D01*
G01X1026121Y718341D01*
G02X1026109Y718208I-194J-50D01*
G03X1025975Y717587I1370J-621D01*
G03X1027478Y716084I1503J0D01*
G03X1028855Y716985I0J1503D01*
G02X1028950Y717084I183J-81D01*
G01X1029059Y717137D01*
G02X1029198Y717151I88J-179D01*
G03X1029582Y717101I384J1452D01*
G01X1029585D01*
G03X1030101Y717193I-2J1502D01*
G02X1030211Y717201I69J-188D01*
G01X1030238Y717196D01*
X1030287Y717170D01*
X1030438Y717025D01*
G02X1030440Y717023I-140J-142D01*
G01X1030588Y716878D01*
X1030616Y716830D01*
X1030621Y716808D01*
X1029398Y713194D01*
G02X1029366Y713174I-122J159D01*
G02X1029348Y713166I-90J179D01*
G03X1028383Y711784I537J-1403D01*
G01Y711737D01*
G03X1028396Y711564I1502J26D01*
G03X1028511Y711156I1489J199D01*
G03X1028586Y711008I1375J604D01*
G01X1028590Y711002D01*
X1028591Y710999D01*
X1028596Y710990D01*
X1028603Y710977D01*
G03X1028610Y710964I1322J703D01*
G01X1028631Y710927D01*
Y710926D01*
X1024910Y699934D01*
G02X1024854Y699850I-189J65D01*
G01X1024837Y699835D01*
G02X1024797Y699806I-136J146D01*
G01X1024776Y699795D01*
X1024752Y699789D01*
X1024749Y699788D01*
G03X1024078Y699418I366J-1457D01*
G03X1023986Y699322I1037J-1086D01*
G02X1023899Y699264I-151J132D01*
G01X1023874Y699256D01*
X1023822Y699253D01*
X1023725Y699273D01*
X1023723D01*
X1023456Y699327D01*
G02X1023364Y699372I39J196D01*
G01X1023344Y699389D01*
X1023315Y699433D01*
X1023307Y699458D01*
G03X1021885Y700476I-1422J-484D01*
G03Y697472I0J-1502D01*
G03X1023015Y697984I0J1503D01*
G01X1023028Y697999D01*
G02X1023208Y698048I136J-146D01*
G01X1023229Y698043D01*
X1023554Y697978D01*
G02X1023691Y697858I-49J-194D01*
G03X1023693Y697850I1454J359D01*
G03X1023704Y697818I1426J472D01*
G01X1023743Y697706D01*
G03X1023762Y697666I189J65D01*
G01X1023822Y697568D01*
X1023823Y697567D01*
X1023836Y697546D01*
G03X1023949Y697385I1283J781D01*
G01X1023991Y697333D01*
X1024001Y697312D01*
G02X1024012Y697282I-182J-84D01*
G01X1022551Y692962D01*
X1022535Y692947D01*
X1022471Y692926D01*
X1022469D01*
G03X1021361Y691421I468J-1505D01*
G01Y691420D01*
G03X1021640Y690525I1575J0D01*
G01X1021650Y690510D01*
X1021666Y690481D01*
G02X1021678Y690452I-178J-91D01*
G01X1021684Y690435D01*
G02X1021689Y690418I-189J-65D01*
G01X1018264Y680299D01*
G02X1018198Y680205I-190J63D01*
G01X1018167Y680181D01*
G02X1018120Y680154I-122J158D01*
G01X1018094Y680143D01*
X1018066Y680140D01*
G03X1017812Y680088I173J-1492D01*
G03X1017810Y680087I87J-177D01*
G03X1017752Y680068I439J-1437D01*
G02X1017721Y680060I-65J189D01*
G01X1017669Y680051D01*
X1017614D01*
G02X1017501Y680086I0J200D01*
G01X1017462Y680160D01*
Y683054D01*
G03X1013856I-1803J0D01*
G01Y679654D01*
G03X1015659Y677852I1802J0D01*
G03X1016436Y678027I2J1803D01*
G01X1016469Y678043D01*
X1016543Y678049D01*
X1016911Y677939D01*
X1016928Y677911D01*
G03X1017149Y677612I1309J737D01*
G03X1017210Y677551I1092J1031D01*
G01X1017238Y677525D01*
X1017250Y677508D01*
X1017263Y677489D01*
G02X1017292Y677426I-165J-114D01*
G01X1005256Y641867D01*
G03X1005124Y641374I3719J-1260D01*
G01X1004534Y638409D01*
X1004516Y638379D01*
G03X1004298Y637600I1283J-779D01*
G03X1004315Y637371I1502J-4D01*
G01X1004321Y637337D01*
X1002901Y630198D01*
G03X1002846Y629832I3851J-766D01*
G02X1002795Y629717I-199J19D01*
G03X1002513Y629277I1104J-1018D01*
G01Y629275D01*
G02X1002415Y629172I-185J78D01*
G01X1002173Y629057D01*
G02X1002030Y629046I-86J181D01*
G03X1001608Y629107I-424J-1441D01*
G01X1001605D01*
G03Y626103I0J-1502D01*
G03X1002109Y626190I0J1503D01*
G01X1002155Y626207D01*
X1002255Y626192D01*
X1002561Y625964D01*
G02X1002642Y625793I-119J-161D01*
G01X1002558Y624071D01*
X1002482Y623972D01*
X1002422Y623953D01*
G03X1001379Y622521I462J-1432D01*
G03X1002301Y621133I1506J0D01*
G01X1002303D01*
X1002341Y621116D01*
X1002407Y621010D01*
X1002180Y616373D01*
G02X1002177Y616349I-200J13D01*
G01X1002046Y615599D01*
X1001162Y610535D01*
G03X1001105Y609941I3834J-668D01*
G01X1001057Y607440D01*
X1001051Y607141D01*
Y607139D01*
X1001049Y607010D01*
G02X1001024Y606918I-200J5D01*
G01X1001013Y606898D01*
X1000979Y606861D01*
X1000957Y606847D01*
G03X1000189Y605443I899J-1404D01*
G01Y605442D01*
G03X1000867Y604099I1669J0D01*
G01X1000900Y604074D01*
X1000927Y604028D01*
X1000942Y604001D01*
X1000989Y603908D01*
X1000988Y603859D01*
Y603858D01*
X1000856Y596969D01*
X1000616Y584535D01*
Y584529D01*
X1000511Y582388D01*
X1000491Y582349D01*
G03X1000323Y581659I1333J-690D01*
G03X1000430Y581103I1502J1D01*
G01X1000446Y581062D01*
X1000072Y573435D01*
G02X1000057Y573368I-200J10D01*
G01X994266Y559387D01*
G02X994100Y559265I-184J77D01*
G01X993693Y559226D01*
X993592Y559274D01*
X993562Y559321D01*
G03X993402Y559524I-1255J-825D01*
G01X993382Y559545D01*
X993357Y559595D01*
X993348Y559643D01*
Y559933D01*
G02X993359Y559998I200J0D01*
G01X993378Y560044D01*
X993403Y560071D01*
G03X993402Y562124I-1097J1026D01*
G01X993382Y562145D01*
X993357Y562195D01*
X993348Y562243D01*
Y562533D01*
G02X993351Y562566I200J-2D01*
G01Y562567D01*
G02X993398Y562665I197J-34D01*
G03X993660Y563045I-1091J1033D01*
G01X993673Y563073D01*
G03X993695Y563124I-1368J620D01*
G03X993798Y563520I-1389J573D01*
G01Y563521D01*
X993805Y563580D01*
G03X993809Y563697I-1499J110D01*
G03X993224Y564887I-1503J0D01*
G01X993213Y564895D01*
X993161Y564947D01*
X993146Y564981D01*
X993142Y564990D01*
G03X993130Y565010I-177J-93D01*
G01X993129Y565011D01*
X993115Y565031D01*
G02X993084Y565182I165J113D01*
G01X993089Y565210D01*
G03X993092Y565246I-197J35D01*
G01Y565337D01*
G02X993097Y565384I200J2D01*
G01X993108Y565428D01*
X993114Y565450D01*
X993146Y565517D01*
G02X993180Y565566I180J-88D01*
G02X993186Y565572I144J-138D01*
G01X993215Y565601D01*
X993225Y565608D01*
G03X993808Y566797I-921J1189D01*
G03X992306Y568299I-1502J0D01*
G03X990814Y566973I0J-1502D01*
G01X990807Y566914D01*
G03X990803Y566797I1499J-110D01*
G03X991388Y565607I1503J0D01*
G01X991399Y565599D01*
X991451Y565547D01*
X991466Y565513D01*
X991470Y565504D01*
G03X991482Y565484I177J93D01*
G01X991483Y565483D01*
X991497Y565463D01*
G02X991528Y565312I-165J-113D01*
G01X991523Y565284D01*
G03X991520Y565248I197J-35D01*
G01Y565160D01*
G02X991516Y565122I-200J2D01*
G01X991501Y565057D01*
G02X991495Y565039I-192J54D01*
G01X991457Y564958D01*
X991452Y564948D01*
X991397Y564893D01*
X991387Y564886D01*
G03X990804Y563697I921J-1189D01*
G03X991210Y562670I1502J0D01*
G01X991230Y562649D01*
X991255Y562599D01*
X991264Y562551D01*
Y562261D01*
G02X991253Y562196I-200J0D01*
G01X991234Y562150D01*
X991209Y562123D01*
G03X991210Y560070I1097J-1026D01*
G01X991230Y560049D01*
X991255Y559999D01*
X991264Y559951D01*
Y559661D01*
G02X991253Y559596I-200J0D01*
G01X991234Y559550D01*
X991209Y559523D01*
G03X991210Y557470I1097J-1026D01*
G01X991230Y557449D01*
X991255Y557399D01*
X991264Y557351D01*
Y557061D01*
G02X991253Y556996I-200J0D01*
G01X991234Y556950D01*
X991209Y556923D01*
G03X991210Y554870I1097J-1026D01*
G01X991230Y554849D01*
X991255Y554799D01*
X991264Y554751D01*
Y554462D01*
G02X991248Y554384I-200J0D01*
G01X991234Y554349D01*
X991209Y554323D01*
G03X990804Y553297I1097J-1026D01*
G03X990817Y553097I1502J-3D01*
G03X991198Y552282I1489J200D01*
G02X991235Y552070I-148J-135D01*
G01X990364Y549967D01*
G02X990146Y549846I-185J76D01*
G01X990145D01*
G03X989890Y549868I-256J-1480D01*
G01X989888D01*
G03X988901Y549498I0J-1501D01*
G01X988900D01*
Y549497D01*
G02X988770Y549449I-130J152D01*
G01X988506D01*
G02X988376Y549497I0J200D01*
G01X988375Y549498D01*
G03X986401I-987J-1131D01*
G01X986400D01*
Y549497D01*
G02X986270Y549449I-130J152D01*
G01X986006D01*
G02X985876Y549497I0J200D01*
G01X985875Y549498D01*
G03X983901I-987J-1131D01*
G01X983900D01*
Y549497D01*
G02X983770Y549449I-130J152D01*
G01X983506D01*
G02X983376Y549497I0J200D01*
G01X983375Y549498D01*
G03X982388Y549868I-987J-1131D01*
G03X980886Y548366I0J-1502D01*
G03X981454Y547190I1501J0D01*
G01X981455Y547189D01*
G02X981530Y547033I-125J-156D01*
G01X981528Y546718D01*
G02X981451Y546561I-200J1D01*
G03X980873Y545377I924J-1184D01*
G03X981243Y544390I1501J0D01*
G01Y544389D01*
X981244D01*
G02X981292Y544259I-152J-130D01*
G01Y543995D01*
G02X981244Y543865I-200J0D01*
G01X981243Y543864D01*
G03Y541890I1131J-987D01*
G01Y541889D01*
X981244D01*
G02X981292Y541759I-152J-130D01*
G01Y541495D01*
G02X981244Y541365I-200J0D01*
G01X981243Y541364D01*
G03Y539390I1131J-987D01*
G01Y539389D01*
X981244D01*
G02X981292Y539259I-152J-130D01*
G01Y538995D01*
G02X981244Y538865I-200J0D01*
G01X981243Y538864D01*
G03X980873Y537877I1131J-987D01*
G03X983877I1502J0D01*
G03X983507Y538864I-1501J0D01*
G01Y538865D01*
X983506D01*
G02X983458Y538995I152J130D01*
G01Y539259D01*
G02X983506Y539389I200J0D01*
G01X983507Y539390D01*
G03Y541364I-1131J987D01*
G01Y541365D01*
X983506D01*
G02X983458Y541495I152J130D01*
G01Y541759D01*
G02X983506Y541889I200J0D01*
G01X983507Y541890D01*
G03Y543864I-1131J987D01*
G01Y543865D01*
X983506D01*
G02X983458Y543995I152J130D01*
G01Y544259D01*
G02X983506Y544389I200J0D01*
G01X983507Y544390D01*
G03X983877Y545377I-1131J987D01*
G03X983309Y546553I-1501J0D01*
G01X983308Y546554D01*
G02X983233Y546710I125J156D01*
G01X983235Y547025D01*
G02X983312Y547182I200J-1D01*
G03X983375Y547234I-924J1184D01*
G01X983376D01*
Y547235D01*
G02X983506Y547283I130J-152D01*
G01X983770D01*
G02X983900Y547235I0J-200D01*
G01X983901Y547234D01*
G03X985875I987J1131D01*
G01X985876D01*
Y547235D01*
G02X986006Y547283I130J-152D01*
G01X986270D01*
G02X986400Y547235I0J-200D01*
G01X986401Y547234D01*
G03X988375I987J1131D01*
G01X988376D01*
Y547235D01*
G02X988506Y547283I130J-152D01*
G01X988770D01*
G02X988900Y547235I0J-200D01*
G01X988901Y547234D01*
G03X989629Y546886I988J1131D01*
G01X989700Y546874D01*
X989794Y546763D01*
Y521198D01*
G02X989634Y521002I-200J0D01*
G03Y518060I302J-1471D01*
G02X989794Y517864I-40J-196D01*
G01Y514625D01*
G03X989964Y513485I3927J3D01*
G01X1010930Y444372D01*
G02X1010909Y444210I-191J-58D01*
G01Y444209D01*
G03X1010686Y443421I1281J-788D01*
G03X1011582Y442047I1502J0D01*
G02X1011586Y442045I-87J-180D01*
G01X1011602Y442037D01*
X1011657Y441974D01*
X1013260Y436693D01*
G03X1013389Y436330I3760J1132D01*
G01X1021255Y417342D01*
X1021258Y417328D01*
G03X1022293Y415498I3810J947D01*
G01X1040581Y397209D01*
G02X1040640Y397067I-141J-142D01*
G01Y397066D01*
G03X1040699Y396924I200J0D01*
G01X1044301Y393322D01*
G03X1044972Y392787I2747J2757D01*
G03X1044974Y392785I139J137D01*
G03X1044993Y392774I1959J3362D01*
G03X1044995Y392772I142J140D01*
G03X1045001Y392769I1740J3473D01*
G03X1045145Y392683I2067J3297D01*
G01X1045146D01*
X1045190Y392659D01*
X1045202Y392653D01*
X1045205Y392652D01*
G03X1045560Y392483I1848J3424D01*
G01X1055019Y388566D01*
G03X1056221Y388281I1487J3595D01*
G02X1056241Y388278I-20J-199D01*
G03X1056912Y388220I672J3868D01*
G01X1060013D01*
G02X1060151Y388164I-1J-200D01*
G03X1062865Y387074I2715J2837D01*
G03X1066230Y388978I0J3926D01*
G02X1066279Y389033I171J-103D01*
G03X1066863Y390212I-920J1190D01*
G01Y390226D01*
G03Y390228I-1502J1D01*
G03X1066793Y390678I-1502J-3D01*
G02X1066784Y390751I190J61D01*
G03X1066792Y391001I-3919J251D01*
G03X1066443Y392619I-3927J0D01*
G02Y392783I182J82D01*
G03X1066792Y394401I-3578J1618D01*
G03X1066784Y394651I-3927J-1D01*
G02X1066792Y394724I199J15D01*
G01X1066793Y394725D01*
Y394727D01*
G03X1066851Y394984I-1430J458D01*
G01Y394988D01*
X1066858Y395043D01*
X1066859Y395050D01*
G03X1066860Y395062I-198J23D01*
G01X1066863Y395139D01*
Y395188D01*
G03X1066279Y396369I-1504J-9D01*
G02X1066230Y396424I122J158D01*
G03X1062865Y398328I-3365J-2022D01*
G03X1060150Y397238I0J-3926D01*
G01X1060121Y397210D01*
X1060051Y397182D01*
X1058982D01*
G02X1058956Y397210I133J149D01*
G01X1058948Y397220D01*
X1058921Y397254D01*
G02X1058900Y397288I159J122D01*
G01X1058862Y397374D01*
X1058860Y397411D01*
G03X1058848Y397538I-1501J-78D01*
G01X1058842Y397577D01*
G03X1058791Y397794I-1484J-234D01*
G02X1058782Y397867I190J61D01*
G03X1058790Y398113I-3919J251D01*
G03X1058441Y399731I-3927J0D01*
G02Y399895I182J82D01*
G03X1058790Y401513I-3578J1618D01*
G03X1058782Y401760I-3927J-4D01*
G02X1058791Y401833I199J12D01*
G03X1058852Y402123I-1433J453D01*
G03X1058855Y402152I-1493J169D01*
G01Y402153D01*
X1058858Y402183D01*
X1058890Y402263D01*
G02X1058919Y402312I185J-76D01*
G01X1058936Y402333D01*
X1058962Y402365D01*
X1058964Y402367D01*
X1058984Y402391D01*
X1058986Y402392D01*
X1060012D01*
G02X1060150Y402337I0J-200D01*
G03X1062863Y401248I2714J2837D01*
G01X1062865D01*
G03X1066231Y403152I0J3927D01*
G02X1066280Y403207I171J-103D01*
G03X1066863Y404380I-919J1188D01*
G01Y404416D01*
G03X1066793Y404854I-1503J-16D01*
G02X1066784Y404927I190J61D01*
G03X1066792Y405174I-3919J251D01*
G03X1066443Y406792I-3927J0D01*
G02Y406956I182J82D01*
G03X1066792Y408574I-3578J1618D01*
G03X1066784Y408824I-3927J-1D01*
G02X1066792Y408897I199J15D01*
G01X1066793Y408898D01*
Y408900D01*
G03X1066851Y409157I-1430J458D01*
G01Y409161D01*
X1066858Y409216D01*
X1066859Y409223D01*
G03X1066860Y409235I-198J23D01*
G01X1066863Y409312D01*
Y409361D01*
G03X1066279Y410542I-1504J-9D01*
G02X1066230Y410597I122J158D01*
G03X1062865Y412500I-3365J-2024D01*
G01X1062864D01*
G03X1060320Y411564I0J-3926D01*
G02X1060117Y411530I-130J152D01*
G03X1058674Y411806I-1446J-3650D01*
G01X1056774D01*
G03X1056753Y411805I176J-3919D01*
G01X1056734D01*
G02X1056610Y411865I20J199D01*
G01X1056520Y411958D01*
X1056405Y412077D01*
G02X1056386Y412101I147J136D01*
G01X1056388Y412179D01*
Y412181D01*
G03X1056390Y412286I-3925J127D01*
G01Y412288D01*
G03X1056041Y413905I-3927J-1D01*
G02Y414069I182J82D01*
G03X1056390Y415687I-3578J1618D01*
G03X1056382Y415933I-3927J-5D01*
G02X1056391Y416006I199J12D01*
G03X1056441Y416217I-1434J451D01*
G03X1056455Y416325I-1482J247D01*
G01Y416326D01*
X1056458Y416357D01*
X1056508Y416476D01*
X1056534Y416506D01*
X1056571Y416548D01*
G02X1056589Y416566I150J-132D01*
G01X1060013D01*
G02X1060151Y416510I-1J-200D01*
G03X1062865Y415420I2715J2837D01*
G03X1066230Y417324I0J3926D01*
G02X1066279Y417379I171J-103D01*
G03X1066863Y418558I-920J1190D01*
G01Y418572D01*
G03Y418574I-1502J1D01*
G03X1066793Y419024I-1502J-3D01*
G02X1066784Y419097I190J61D01*
G03X1066792Y419347I-3919J251D01*
G03X1066443Y420965I-3927J0D01*
G02Y421129I182J82D01*
G03X1066792Y422747I-3578J1618D01*
G03X1066784Y422997I-3927J-1D01*
G02X1066792Y423070I199J15D01*
G01X1066793Y423071D01*
Y423073D01*
G03X1066851Y423330I-1430J458D01*
G01Y423334D01*
X1066858Y423389D01*
X1066859Y423396D01*
G03X1066860Y423408I-198J23D01*
G01X1066863Y423485D01*
Y423534D01*
G03X1066279Y424715I-1504J-9D01*
G02X1066230Y424770I122J158D01*
G03X1062865Y426674I-3365J-2022D01*
G03X1060329Y425744I1J-3927D01*
G02X1060275Y425738I-49J194D01*
G01X1060243D01*
X1060224Y425744D01*
G03X1058896Y425978I-1329J-3658D01*
G01X1057152D01*
G03X1057145I-4J-3892D01*
G01X1056686D01*
X1056667Y425984D01*
X1056385Y426249D01*
X1056384Y426251D01*
G03X1056390Y426460I-3921J217D01*
G03X1056041Y428078I-3927J0D01*
G02Y428242I182J82D01*
G03X1056390Y429860I-3578J1618D01*
G03X1056382Y430106I-3927J-5D01*
G02X1056391Y430179I199J12D01*
G03X1056452Y430469I-1433J453D01*
G01Y430477D01*
X1056454Y430490D01*
G03X1056456Y430509I-1493J167D01*
G01Y430515D01*
X1056457Y430523D01*
Y430532D01*
X1056458Y430542D01*
Y430544D01*
G02X1056503Y430645I198J-28D01*
G01X1056523Y430668D01*
X1056525Y430670D01*
X1056570Y430721D01*
X1056575Y430726D01*
X1056587Y430740D01*
X1060013D01*
G02X1060151Y430684I-1J-200D01*
G03X1062865Y429594I2715J2837D01*
G03X1066230Y431498I0J3926D01*
G02X1066279Y431553I171J-103D01*
G03X1066863Y432732I-920J1190D01*
G01Y432746D01*
G03Y432748I-1502J1D01*
G03X1066793Y433198I-1502J-3D01*
G02X1066784Y433271I190J61D01*
G03X1066792Y433521I-3919J251D01*
G03X1066443Y435139I-3927J0D01*
G02Y435303I182J82D01*
G03X1066792Y436921I-3578J1618D01*
G03X1066784Y437171I-3927J-1D01*
G02X1066792Y437244I199J15D01*
G01X1066793Y437245D01*
Y437247D01*
G03X1066851Y437504I-1430J458D01*
G01Y437508D01*
X1066858Y437563D01*
X1066859Y437570D01*
G03X1066860Y437582I-198J23D01*
G01X1066863Y437659D01*
Y437708D01*
G03X1066279Y438889I-1504J-9D01*
G02X1066230Y438944I122J158D01*
G03X1062865Y440848I-3365J-2022D01*
G03X1060405Y439981I1J-3927D01*
G02X1060216Y439948I-125J156D01*
G03X1058968Y440152I-1249J-3723D01*
G01X1057063D01*
G03X1056441Y440103I-4J-3926D01*
G03X1056427Y440177I-1483J-242D01*
G01Y440179D01*
G03X1056391Y440313I-1468J-322D01*
G02X1056382Y440387I190J61D01*
G03X1056390Y440633I-3919J251D01*
G03X1056041Y442251I-3927J0D01*
G02Y442415I182J82D01*
G03X1056390Y444033I-3578J1618D01*
G03X1056382Y444283I-3927J-1D01*
G02X1056390Y444356I199J15D01*
G01X1056391Y444357D01*
Y444359D01*
G03X1056449Y444616I-1430J458D01*
G01Y444620D01*
X1056456Y444675D01*
X1056457Y444682D01*
G03X1056458Y444694I-198J23D01*
G01X1056461Y444771D01*
Y444820D01*
G03X1055877Y446001I-1504J-9D01*
G02X1055828Y446056I122J158D01*
G03X1052463Y447960I-3365J-2022D01*
G03X1051565Y447855I4J-3927D01*
G02X1051334Y447973I-46J195D01*
G01X1050620Y449699D01*
G03X1049877Y450861I-3628J-1501D01*
G02X1049825Y450989I148J135D01*
G03X1049529Y452331I-3923J-162D01*
G01X1048783Y454134D01*
G03X1048040Y455296I-3628J-1501D01*
G02X1047988Y455424I148J135D01*
G03X1047692Y456766I-3923J-162D01*
G01X1046946Y458569D01*
G03X1046203Y459731I-3628J-1501D01*
G02X1046151Y459859I148J135D01*
G03X1045855Y461201I-3923J-162D01*
G01X1045109Y463004D01*
G03X1044366Y464166I-3628J-1501D01*
G02X1044314Y464294I148J135D01*
G03X1044018Y465636I-3923J-162D01*
G01X1043272Y467439D01*
G03X1042529Y468601I-3628J-1501D01*
G02X1042477Y468729I148J135D01*
G03X1042181Y470071I-3923J-162D01*
G01X1041819Y470946D01*
G02X1041893Y471188I185J76D01*
G01X1041953Y471229D01*
X1042094Y471215D01*
X1045514Y467795D01*
G03X1046177Y467263I2752J2751D01*
G02X1046181Y467261I-87J-179D01*
G03X1048351Y466606I2171J3271D01*
G01X1049611D01*
G02X1049749Y466550I-1J-200D01*
G03X1052463Y465460I2715J2837D01*
G03X1055828Y467364I0J3926D01*
G02X1055877Y467419I171J-103D01*
G03X1056461Y468598I-920J1190D01*
G01Y468612D01*
G03Y468614I-1502J1D01*
G03X1056391Y469064I-1502J-3D01*
G02X1056382Y469137I190J61D01*
G03X1056390Y469387I-3919J251D01*
G03X1056041Y471005I-3927J0D01*
G02Y471169I182J82D01*
G03X1056390Y472787I-3578J1618D01*
G03X1056382Y473035I-3927J-3D01*
G02X1056391Y473108I199J12D01*
G03X1056447Y473358I-1433J452D01*
G03X1056460Y473510I-1488J204D01*
G01X1056461Y473545D01*
X1056473Y473576D01*
G02X1056508Y473634I186J-73D01*
G01X1056546Y473677D01*
X1056549Y473680D01*
X1056559Y473692D01*
X1056570Y473706D01*
G02X1056583Y473718I142J-141D01*
G01X1060013D01*
G02X1060151Y473662I-1J-200D01*
G03X1062865Y472572I2715J2837D01*
G03X1066230Y474476I0J3926D01*
G02X1066279Y474531I171J-103D01*
G03X1066863Y475710I-920J1190D01*
G01Y475724D01*
G03Y475726I-1502J1D01*
G03X1066793Y476176I-1502J-3D01*
G02X1066784Y476249I190J61D01*
G03X1066792Y476499I-3919J251D01*
G03X1066443Y478117I-3927J0D01*
G02Y478281I182J82D01*
G03X1066792Y479899I-3578J1618D01*
G03X1066784Y480149I-3927J-1D01*
G02X1066792Y480222I199J15D01*
G01X1066793Y480223D01*
Y480225D01*
G03X1066851Y480482I-1430J458D01*
G01Y480486D01*
X1066858Y480541D01*
X1066859Y480548D01*
G03X1066860Y480560I-198J23D01*
G01X1066863Y480637D01*
Y480686D01*
G03X1066279Y481867I-1504J-9D01*
G02X1066230Y481922I122J158D01*
G03X1062865Y483826I-3365J-2022D01*
G03X1060150Y482736I0J-3926D01*
G01X1060121Y482708D01*
X1060051Y482680D01*
X1059934D01*
X1059896Y482697D01*
G03X1059329Y482897I-1586J-3592D01*
G02X1059321Y482899I45J195D01*
G03X1058151Y483080I-1173J-3710D01*
G01X1056754D01*
G02X1056610Y483141I0J200D01*
G01X1056520Y483234D01*
X1056405Y483353D01*
G02X1056386Y483377I147J136D01*
G01X1056388Y483455D01*
Y483457D01*
G03X1056390Y483559I-3925J128D01*
G01Y483561D01*
G03X1056041Y485178I-3927J-1D01*
G02Y485342I182J82D01*
G03X1056390Y486960I-3578J1618D01*
G03X1056382Y487209I-3927J-2D01*
G01X1056379Y487246D01*
X1056387Y487271D01*
G03X1056390Y487281I-1437J437D01*
G01X1056435Y487425D01*
X1056438Y487436D01*
G03X1056442Y487460I-195J45D01*
G01X1056455Y487600D01*
G03X1056461Y487711I-1496J137D01*
G01Y487745D01*
G03X1056424Y488072I-1502J-4D01*
G01X1056418Y488100D01*
X1056421Y488155D01*
X1056431Y488183D01*
G02X1056495Y488273I189J-66D01*
G01X1056581Y488341D01*
X1056583D01*
X1056599Y488354D01*
X1056640Y488376D01*
X1056663Y488381D01*
G02X1056755I46J-195D01*
G01X1056806Y488369D01*
X1056827Y488358D01*
G03X1058350Y487949I1750J3476D01*
G02X1058372Y487946I-16J-199D01*
G03X1059025Y487892I649J3872D01*
G01X1060051D01*
X1060121Y487864D01*
X1060150Y487836D01*
G03X1062865Y486746I2715J2836D01*
G03X1066230Y488650I0J3926D01*
G02X1066279Y488705I171J-103D01*
G03X1066863Y489884I-920J1190D01*
G01Y489898D01*
G03Y489900I-1502J1D01*
G03X1066793Y490350I-1502J-3D01*
G02X1066784Y490423I190J61D01*
G03X1066792Y490673I-3919J251D01*
G03X1066443Y492291I-3927J0D01*
G02Y492455I182J82D01*
G03X1066792Y494073I-3578J1618D01*
G03X1066784Y494323I-3927J-1D01*
G02X1066792Y494396I199J15D01*
G01X1066793Y494397D01*
Y494399D01*
G03X1066851Y494656I-1430J458D01*
G01Y494660D01*
X1066858Y494715D01*
X1066859Y494722D01*
G03X1066860Y494734I-198J23D01*
G01X1066863Y494811D01*
Y494860D01*
G03X1066279Y496041I-1504J-9D01*
G02X1066230Y496096I122J158D01*
G03X1062865Y498000I-3365J-2022D01*
G03X1060873Y497457I0J-3927D01*
G01Y497456D01*
X1060842Y497438D01*
G02X1060691Y497417I-101J172D01*
G01X1060659Y497425D01*
X1060564Y497587D01*
G03X1060550Y497601I-2759J-2745D01*
G01X1059319Y498832D01*
G03X1059258Y498892I-2759J-2744D01*
G02X1059256Y498894I140J142D01*
G01X1058889Y499261D01*
G03X1058619Y499507I-2753J-2751D01*
G01X1058597Y499525D01*
X1057041Y501853D01*
X1057034Y501895D01*
G03X1056432Y503396I-3867J-680D01*
G01X1055487Y504810D01*
G03X1054635Y505726I-3265J-2182D01*
G02X1054565Y505830I122J158D01*
G03X1054043Y506970I-3785J-1044D01*
G01X1053097Y508385D01*
G03X1052647Y508941I-3264J-2182D01*
G02X1052602Y509148I143J140D01*
G01X1052724Y509487D01*
G02X1052890Y509618I188J-68D01*
G03X1055828Y511498I-427J3903D01*
G02X1055877Y511553I171J-103D01*
G03X1056461Y512732I-920J1190D01*
G01Y512746D01*
G03Y512748I-1502J1D01*
G03X1056391Y513198I-1502J-3D01*
G02X1056382Y513271I190J61D01*
G03X1056390Y513521I-3919J251D01*
G03X1056041Y515139I-3927J0D01*
G02Y515303I182J82D01*
G03X1056390Y516921I-3578J1618D01*
G03X1056382Y517168I-3927J-4D01*
G02X1056391Y517241I199J12D01*
G03X1056461Y517687I-1433J453D01*
G01Y517692D01*
X1056463Y517740D01*
X1056578Y517852D01*
X1060013D01*
G02X1060151Y517796I-1J-200D01*
G03X1062865Y516706I2715J2837D01*
G03X1066230Y518610I0J3926D01*
G02X1066279Y518665I171J-103D01*
G03X1066863Y519844I-920J1190D01*
G01Y519858D01*
G03Y519860I-1502J1D01*
G03X1066793Y520310I-1502J-3D01*
G02X1066784Y520383I190J61D01*
G03X1066792Y520633I-3919J251D01*
G03X1066443Y522251I-3927J0D01*
G02Y522415I182J82D01*
G03X1066792Y524032I-3578J1618D01*
G01Y524034D01*
G03X1066789Y524172I-3927J-16D01*
G02X1066800Y524247I200J9D01*
G03X1066791Y525273I-1415J501D01*
G01X1066787Y525285D01*
X1066771Y525334D01*
G03X1066759Y525360I-187J-70D01*
G01X1066758Y525362D01*
G03X1066743Y525399I-1400J-546D01*
G01X1066739Y525411D01*
X1066731Y525427D01*
G03X1066396Y525901I-1371J-614D01*
G03X1066280Y526001I-1038J-1087D01*
G02X1066230Y526056I120J160D01*
G03X1062865Y527960I-3365J-2022D01*
G03X1060150Y526870I0J-3926D01*
G01X1060121Y526842D01*
X1060051Y526814D01*
X1059537D01*
G02X1059446Y526836I0J200D01*
G03X1057760Y527263I-1783J-3498D01*
G01X1057724Y527264D01*
X1057093Y527525D01*
G03X1056565Y527701I-1492J-3596D01*
G01X1056534Y527709D01*
X1056508Y527725D01*
G02X1056460Y527767I106J170D01*
G01X1056431Y527802D01*
G02X1056429Y527804I140J142D01*
G01X1056427Y527806D01*
G02X1056383Y527920I156J126D01*
G01Y527921D01*
G03X1056040Y529312I-3920J-229D01*
G02Y529476I183J82D01*
G03X1056390Y531094I-3576J1621D01*
G03X1056382Y531344I-3927J-1D01*
G02X1056391Y531417I199J12D01*
G03X1056460Y531829I-1432J452D01*
G01Y531833D01*
G03X1056461Y531861I-1500J68D01*
G01Y531868D01*
G03Y531875I-1502J3D01*
G01Y531880D01*
G03X1056430Y532178I-1502J-6D01*
G01X1056427Y532191D01*
X1056429Y532221D01*
G02X1056510Y532369I200J-13D01*
G01X1056657Y532477D01*
X1056659D01*
X1056761Y532551D01*
G02X1056843Y532581I108J-168D01*
G01X1056932Y532531D01*
G03X1058861Y532024I1930J3420D01*
G01X1060013D01*
G02X1060151Y531969I0J-200D01*
G03X1062865Y530880I2714J2837D01*
G03X1066231Y532784I1J3926D01*
G02X1066280Y532839I171J-103D01*
G03X1066863Y534012I-919J1188D01*
G01Y534048D01*
G03X1066793Y534486I-1503J-16D01*
G02X1066784Y534559I190J61D01*
G03X1066792Y534806I-3919J251D01*
G03X1066443Y536424I-3927J0D01*
G02Y536588I182J82D01*
G03X1066792Y538206I-3578J1618D01*
G03X1066784Y538456I-3927J-1D01*
G02X1066792Y538529I199J15D01*
G03X1066811Y538593I-1430J459D01*
G01Y538595D01*
G03X1066853Y538808I-1449J396D01*
G01X1066858Y538849D01*
G03X1066864Y538982I-1497J134D01*
G01Y538984D01*
G03X1066280Y540174I-1504J0D01*
G02X1066230Y540229I120J160D01*
G03X1065674Y540949I-3365J-2024D01*
G02X1065617Y541089I143J140D01*
G01X1065619Y541372D01*
G02X1065677Y541512I200J-1D01*
G01X1065905Y541740D01*
G03X1066756Y543013I-2776J2777D01*
G01X1068551Y547345D01*
G03X1068775Y548084I-3627J1503D01*
G01X1068778Y548095D01*
X1068780Y548103D01*
G03X1068852Y548401I-3743J1062D01*
G03X1068904Y548729I-3814J773D01*
G02X1068907Y548745I198J-29D01*
G01X1068920Y548809D01*
X1068937Y548849D01*
X1068951Y548867D01*
G03X1069653Y550449I-3150J2344D01*
G01X1070023Y552314D01*
G03X1070098Y553078I-3851J764D01*
G03X1070059Y553638I-3927J8D01*
G02X1070085Y553768I198J28D01*
G03X1070561Y555012I-3377J2005D01*
G01X1070940Y556925D01*
G03X1071014Y557688I-3852J759D01*
G03X1070975Y558248I-3927J8D01*
G02X1071001Y558378I198J28D01*
G03X1071477Y559622I-3377J2005D01*
G01X1071648Y560490D01*
X1071718Y560570D01*
X1071751Y560582D01*
G03X1072323Y560939I-489J1421D01*
G03X1072327Y560943I-1060J1064D01*
G01X1072344Y560960D01*
G03X1072752Y561805I-1081J1043D01*
G03X1072764Y561943I-1489J199D01*
G01Y561946D01*
X1072765Y561961D01*
Y561993D01*
G03Y562003I-1502J5D01*
G03X1072196Y563181I-1504J0D01*
G02X1072137Y563418I124J157D01*
G03X1072393Y564232I-3596J1578D01*
G01X1072772Y566145D01*
G03X1072846Y566908I-3852J759D01*
G03X1072807Y567468I-3927J8D01*
G02X1072833Y567598I198J28D01*
G03X1073309Y568842I-3377J2005D01*
G01X1073688Y570755D01*
G03X1073762Y571518I-3852J759D01*
G03X1073723Y572078I-3927J8D01*
G02X1073749Y572208I198J28D01*
G03X1074225Y573452I-3377J2005D01*
G01X1074604Y575365D01*
G03X1074678Y576128I-3852J759D01*
G03X1074639Y576688I-3927J8D01*
G02X1074665Y576818I198J28D01*
G03X1075141Y578062I-3377J2005D01*
G01X1075520Y579975D01*
G03X1075594Y580738I-3852J759D01*
G03X1075560Y581254I-3951J-1D01*
G02X1075589Y581387I198J26D01*
G03X1076114Y582709I-3326J2086D01*
G01X1076494Y584623D01*
G03X1076570Y585388I-3851J769D01*
G03X1076421Y586456I-3902J0D01*
G01X1076408Y586502D01*
X1089908Y654478D01*
G02X1090123Y654639I196J-38D01*
G02X1090304Y654439I-19J-199D01*
G01Y607635D01*
G02X1090245Y607493I-200J0D01*
G01X1079459Y596708D01*
G03X1079076Y595784I923J-924D01*
G01Y480169D01*
G02X1079017Y480027I-200J0D01*
G01X1063477Y464486D01*
G02X1063323Y464428I-141J141D01*
G01X1062980Y464449D01*
X1062904Y464489D01*
X1062878Y464523D01*
G03X1061693Y465102I-1185J-923D01*
G03X1060191Y463600I0J-1502D01*
G03X1060770Y462415I1502J0D01*
G01X1060804Y462389D01*
X1060844Y462313D01*
X1060865Y461970D01*
G02X1060807Y461816I-199J-13D01*
G01X1059184Y460194D01*
G02X1059104Y460145I-142J141D01*
G01X1059103D01*
G03X1058047Y458711I446J-1434D01*
G03X1059549Y457209I1502J0D01*
G03X1060655Y457694I0J1504D01*
G02X1060802Y457759I148J-135D01*
G01X1061073D01*
G02X1061221Y457693I0J-200D01*
G03X1061714Y457332I1125J1020D01*
G02X1061824Y457202I-83J-182D01*
G01X1061898Y456929D01*
G02X1061871Y456765I-193J-52D01*
G03X1061611Y455921I1242J-845D01*
G03X1063027Y454421I1502J0D01*
G01X1063070Y454419D01*
X1063146Y454379D01*
X1063385Y454076D01*
X1063406Y453993D01*
X1063398Y453951D01*
G03X1063374Y453685I1478J-267D01*
G01Y453682D01*
G03X1066378I1502J0D01*
G03X1064962Y455182I-1502J0D01*
G01X1064919Y455184D01*
X1064843Y455224D01*
X1064604Y455527D01*
X1064583Y455610D01*
X1064591Y455652D01*
G03X1064615Y455921I-1478J267D01*
G01Y455937D01*
G02X1064737Y456123I200J2D01*
G01X1065079Y456267D01*
G02X1065298Y456224I78J-184D01*
G01X1067467Y454055D01*
G02X1067526Y453913I-141J-142D01*
G01Y385822D01*
G02X1067467Y385680I-200J0D01*
G01X1064396Y382610D01*
G02X1064192Y382561I-142J141D01*
G01X1063800Y382689D01*
X1063727Y382775D01*
X1063718Y382831D01*
G03X1062234Y384102I-1484J-231D01*
G03X1060732Y382600I0J-1502D01*
G03X1062003Y381116I1502J0D01*
G01X1062059Y381107D01*
X1062145Y381034D01*
X1062273Y380642D01*
G02X1062224Y380438I-190J-62D01*
G01X1061869Y380083D01*
G02X1061789Y380034I-142J141D01*
G01X1061788D01*
G03X1060732Y378600I446J-1434D01*
G03X1062234Y377098I1502J0D01*
G03X1063668Y378153I0J1502D01*
G01Y378155D01*
G02X1063717Y378235I190J-62D01*
G01X1069756Y384274D01*
G03X1070138Y385196I-924J923D01*
G01Y454539D01*
G03X1069756Y455461I-1306J-1D01*
G01X1065582Y459635D01*
G03X1064658Y460018I-924J-923D01*
G01X1063176D01*
G02X1063080Y460042I-1J200D01*
G03X1063031Y460068I-736J-1328D01*
G01X1063001Y460141D01*
G02X1063044Y460358I185J76D01*
G01X1081307Y478621D01*
G03X1081690Y479545I-923J924D01*
G01Y595160D01*
G02X1081749Y595302I200J0D01*
G01X1092534Y606087D01*
G03X1092916Y607009I-924J923D01*
G01Y658054D01*
G02X1092931Y658131I200J1D01*
G01X1097197Y668427D01*
G02X1097240Y668492I185J-76D01*
G01X1112110Y683363D01*
G02X1112252Y683422I142J-141D01*
G01X1116457D01*
G03X1117379Y683804I-1J1306D01*
G01X1138931Y705356D01*
G02X1139148Y705399I141J-142D01*
G01X1139205Y705376D01*
X1139272Y705275D01*
Y665835D01*
G02X1139213Y665693I-200J0D01*
G01X1127641Y654122D01*
G03X1127258Y653198I923J-924D01*
G01Y581634D01*
G02X1127199Y581492I-200J0D01*
G01X1125010Y579303D01*
G02X1124868Y579244I-142J141D01*
G01X1115458D01*
G02X1115369Y579265I0J200D01*
G01X1115367Y579266D01*
G03X1114668Y579439I-700J-1329D01*
G03Y576435I0J-1502D01*
G03X1115365Y576607I-1J1502D01*
G02X1115369Y576609I91J-178D01*
G01X1115390Y576620D01*
X1115434Y576630D01*
X1125492D01*
G03X1126416Y577013I0J1306D01*
G01X1129489Y580086D01*
G03X1129872Y581010I-923J924D01*
G01Y652574D01*
G02X1129931Y652716I200J0D01*
G01X1141502Y664287D01*
G03X1141884Y665209I-924J923D01*
G01Y705821D01*
G02X1141943Y705963I200J0D01*
G01X1165287Y729307D01*
G02X1165429Y729366I142J-141D01*
G01X1168751D01*
G03X1169673Y729748I-1J1306D01*
G01X1172299Y732374D01*
G02X1172379Y732423I142J-141D01*
G01X1172380D01*
G03X1173436Y733857I-446J1434D01*
G03X1171934Y735359I-1502J0D01*
G03X1170500Y734304I0J-1502D01*
G01Y734302D01*
G02X1170451Y734222I-190J62D01*
G01X1168267Y732037D01*
G02X1168125Y731978I-142J141D01*
G01X1166036D01*
G02X1165851Y732102I0J200D01*
G01X1165827Y732158D01*
X1165851Y732276D01*
X1180624Y747049D01*
G03X1181006Y747971I-924J923D01*
G01Y805688D01*
G03X1180907Y806186I-1306J-1D01*
G01X1173621Y823775D01*
G02X1173606Y823852I185J76D01*
G01Y912668D01*
G02X1173683Y912825I200J-1D01*
G01X1173968Y913049D01*
X1174058Y913068D01*
X1174102Y913057D01*
G03X1174461Y913013I361J1458D01*
G03Y916017I0J1502D01*
G03X1174313Y916010I-3J-1502D01*
G01X1174256Y916004D01*
X1174152Y916056D01*
X1173936Y916416D01*
G02X1173941Y916630I172J103D01*
G01X1183506Y930943D01*
G03X1183627Y931169I-1086J727D01*
G01X1187228Y939862D01*
G02X1187397Y939985I185J-76D01*
G01X1187808Y940018D01*
X1187908Y939967D01*
X1187938Y939918D01*
G03X1189219Y939201I1281J786D01*
G03Y942205I0J1502D01*
G03X1188869Y942163I3J-1502D01*
G01X1188867D01*
X1188812Y942150D01*
X1188707Y942184D01*
X1188439Y942499D01*
G02X1188406Y942705I152J130D01*
G01X1196915Y963250D01*
G03X1197014Y963748I-1207J499D01*
G01Y983838D01*
G02X1197130Y984020I200J0D01*
G01X1197513Y984197D01*
X1197628Y984181D01*
X1197673Y984143D01*
G03X1198644Y983787I971J1146D01*
G03Y986791I0J1502D01*
G03X1197673Y986435I0J-1502D01*
G01X1197628Y986397D01*
X1197513Y986381D01*
X1197130Y986558D01*
G02X1197014Y986740I84J182D01*
G01Y987280D01*
X1197029Y987332D01*
X1197043Y987355D01*
G03X1197259Y988131I-1286J776D01*
G03X1194255I-1502J0D01*
G01Y988129D01*
G03X1194384Y987521I1502J1D01*
G01X1194402Y987483D01*
Y964050D01*
G02X1194387Y963973I-200J-1D01*
G01X1183558Y937831D01*
G02X1183423Y937714I-185J77D01*
G01X1183113Y937635D01*
G02X1182939Y937672I-50J194D01*
G03X1182000Y938002I-939J-1171D01*
G03X1180498Y936500I0J-1502D01*
G03X1181835Y935007I1502J0D01*
G01X1181882Y935002D01*
X1181961Y934951D01*
X1182148Y934635D01*
G02X1182161Y934457I-172J-102D01*
G01X1181270Y932306D01*
G02X1181251Y932272I-183J80D01*
G01X1171214Y917251D01*
G03X1170994Y916526I1086J-725D01*
G01Y823550D01*
G03X1171093Y823052I1306J1D01*
G01X1178379Y805463D01*
G02X1178394Y805386I-185J-76D01*
G01Y786110D01*
G02X1178260Y785921I-200J0D01*
G01X1177902Y785797D01*
G02X1177680Y785862I-65J189D01*
G01X1177679Y785863D01*
G03X1176500Y786435I-1179J-929D01*
G03Y783431I0J-1502D01*
G03X1177679Y784003I0J1501D01*
G01X1177680Y784004D01*
G02X1177902Y784069I157J-124D01*
G01X1178260Y783945D01*
G02X1178394Y783756I-66J-189D01*
G01Y748597D01*
G02X1178335Y748455I-200J0D01*
G01X1155159Y725280D01*
G02X1154942Y725237I-141J142D01*
G01X1154885Y725260D01*
X1154818Y725361D01*
Y728543D01*
G03X1150206I-2306J0D01*
G01Y724849D01*
G02X1150147Y724707I-200J0D01*
G01X1118120Y692681D01*
G02X1117963Y692623I-141J142D01*
G01X1117616Y692651D01*
X1117540Y692694D01*
X1117514Y692730D01*
G03X1116296Y693353I-1218J-879D01*
G03X1114794Y691851I0J-1502D01*
G03X1115417Y690633I1502J0D01*
G01X1115453Y690607D01*
X1115496Y690531D01*
X1115524Y690184D01*
G02X1115466Y690027I-200J-16D01*
G01X1114776Y689337D01*
G02X1114634Y689278I-142J141D01*
G01X1111785D01*
G03X1109478Y686971I0J-2307D01*
G03X1110134Y685361I2307J1D01*
G01X1110135Y685360D01*
G02X1110133Y685080I-144J-139D01*
G01X1095180Y670128D01*
G03X1094897Y669704I924J-923D01*
G01X1091896Y662458D01*
G02X1091654Y662343I-185J77D01*
G02X1091515Y662574I57J192D01*
G01X1104572Y728329D01*
G02X1104579Y728354I196J-41D01*
G01X1191708Y985740D01*
X1191815Y985815D01*
X1191881Y985813D01*
G03X1191927Y985812I56J1501D01*
G01X1191929D01*
G03X1193430Y987314I-1J1502D01*
G03X1192802Y988535I-1501J0D01*
G01X1192749Y988574D01*
X1192709Y988698D01*
X1195540Y997061D01*
G02X1195793Y997186I189J-64D01*
G01X1195794D01*
X1195795Y997185D01*
G03X1196298Y997098I504J1415D01*
G01X1196300D01*
G03X1197802Y998600I0J1502D01*
G03X1197484Y999525I-1504J0D01*
G02X1197457Y999571I157J123D01*
G03X1196807Y1000297I-1384J-585D01*
G01X1196745Y1000331D01*
X1196693Y1000466D01*
X1199781Y1009587D01*
X1199889Y1009662D01*
X1199943Y1009660D01*
G03X1200006Y1009659I55J1503D01*
G01X1200008D01*
G03X1201510Y1011161I0J1502D01*
G03X1200915Y1012358I-1502J0D01*
G01X1200910Y1012362D01*
G02X1200841Y1012473I126J155D01*
G01X1200810Y1012600D01*
Y1012601D01*
X1200806Y1012617D01*
X1200820Y1012659D01*
X1200864Y1012712D01*
G03X1201202Y1013661I-1163J949D01*
G03X1201200Y1013740I-1502J1D01*
G01X1201198Y1013775D01*
X1202697Y1018205D01*
X1202731Y1018252D01*
X1202750Y1018267D01*
G03X1203302Y1019431I-951J1164D01*
G03X1203261Y1019778I-1502J-2D01*
G01Y1019780D01*
X1203255Y1019805D01*
X1203258Y1019859D01*
X1204277Y1022870D01*
G02X1204466Y1023006I189J-64D01*
G01X1205405D01*
G02X1205552Y1022941I-1J-200D01*
G01X1205553D01*
G02X1205604Y1022788I-148J-134D01*
G01X1204730Y1012795D01*
G02X1204626Y1012636I-199J17D01*
G01X1204330Y1012478D01*
G02X1204140Y1012479I-94J176D01*
G03X1203420Y1012663I-720J-1318D01*
G01X1203419D01*
G03Y1009659I0J-1502D01*
G01X1203420D01*
G03X1203900Y1009738I-1J1502D01*
G02X1204088Y1009706I65J-189D01*
G01X1204351Y1009499D01*
G02X1204427Y1009324I-123J-158D01*
G01X1203594Y999815D01*
G02X1203475Y999649I-199J17D01*
G01X1203103Y999487D01*
X1202994Y999501D01*
X1202951Y999534D01*
G03X1202028Y999851I-923J-1185D01*
G03Y996847I0J-1502D01*
G03X1202731Y997022I-1J1502D01*
G01X1202780Y997048D01*
X1202889Y997042D01*
X1203228Y996818D01*
G02X1203317Y996633I-110J-167D01*
G01X1201028Y970475D01*
G02X1201026Y970461I-199J21D01*
G01X1198127Y952262D01*
G02X1197999Y952118I-195J44D01*
G01X1197769Y952046D01*
X1197639Y952006D01*
G02X1197547Y952005I-48J194D01*
G01X1197534Y952008D01*
G02X1197449Y952059I57J192D01*
G01X1197445Y952063D01*
G03X1196352Y952535I-1093J-1030D01*
G03Y949531I0J-1502D01*
G01X1196354D01*
G03X1197049Y949702I-1J1503D01*
G01X1197072Y949714D01*
X1197127Y949727D01*
G02X1197214Y949729I48J-194D01*
G01X1197254Y949721D01*
X1197289Y949696D01*
X1197291D01*
X1197573Y949498D01*
G02X1197598Y949477I-116J-163D01*
G01X1197599Y949476D01*
G02X1197656Y949302I-141J-142D01*
G01X1197034Y945390D01*
X1196514Y942126D01*
X1196507Y942082D01*
X1196450Y941998D01*
G02X1196424Y941967I-165J112D01*
G01X1196378Y941922D01*
X1196361Y941911D01*
G03X1195670Y940645I814J-1266D01*
G03X1196023Y939677I1504J0D01*
G01X1196045Y939651D01*
X1196095Y939518D01*
G02X1196093Y939488I-200J-2D01*
G01X1193780Y924961D01*
X1192412Y916371D01*
G02X1192356Y916261I-198J31D01*
G01X1192327Y916232D01*
X1192286Y916201D01*
X1192268Y916191D01*
G03X1191488Y914873I724J-1318D01*
G01Y914872D01*
G03X1191899Y913840I1502J0D01*
G01X1191927Y913812D01*
X1191962Y913718D01*
X1191965Y913709D01*
G02X1191974Y913620I-190J-64D01*
G01X1191122Y908269D01*
G03X1191073Y907657I3844J-616D01*
G01Y907651D01*
G03X1191089Y907307I3893J9D01*
G01Y907300D01*
X1191093Y907245D01*
X1191120Y906821D01*
X1191162Y906173D01*
X1191168Y906084D01*
X1191244Y904901D01*
X1191247Y904859D01*
X1191202Y904734D01*
X1191182Y904708D01*
G03X1190865Y903785I1185J-923D01*
G01Y903784D01*
G03X1191311Y902716I1502J0D01*
G01X1191339Y902689D01*
X1191375Y902606D01*
X1191378Y902598D01*
G03X1191382Y902588I187J69D01*
G01X1191396Y902556D01*
X1191406Y902406D01*
X1191415Y902398D01*
X1191412Y902299D01*
Y902285D01*
G02X1191149Y902095I-200J0D01*
G01X1191120Y902105D01*
X1191108Y902113D01*
G03X1190210Y902411I-898J-1204D01*
G03X1188708Y900909I0J-1502D01*
G03X1190183Y899407I1502J0D01*
G01X1190212D01*
G03X1190997Y899629I-1J1502D01*
G02X1191177Y899645I106J-170D01*
G02X1191186Y899641I-77J-185D01*
G01X1191401Y899530D01*
X1191403D01*
X1191499Y899480D01*
G02X1191575Y899411I-92J-178D01*
G01X1191603Y899368D01*
X1191606Y899315D01*
X1191780Y896622D01*
X1192445Y886324D01*
G02X1192439Y886260I-200J-14D01*
G01X1192438Y886258D01*
G02X1192394Y886175I-194J50D01*
G01X1192216Y885975D01*
G02X1192153Y885928I-149J134D01*
G01X1192118Y885911D01*
X1192077Y885909D01*
G03X1190640Y884399I75J-1510D01*
G03X1192152Y882887I1512J0D01*
G03X1192273Y882892I-2J1512D01*
G01X1192314Y882895D01*
X1192349Y882884D01*
G02X1192420Y882844I-61J-191D01*
G01X1192633Y882657D01*
G02X1192692Y882528I-140J-142D01*
G01X1192923Y878957D01*
X1192964Y878328D01*
Y878298D01*
X1192255Y870199D01*
X1192169Y870100D01*
X1192136Y870093D01*
G03X1190929Y868620I295J-1473D01*
G03X1191968Y867191I1502J0D01*
G01X1191969D01*
G02X1192107Y867018I-61J-191D01*
G01X1197885Y800960D01*
X1197868Y800921D01*
G03X1197730Y800293I1363J-629D01*
G01Y800291D01*
G03X1197992Y799442I1507J0D01*
G01X1197993Y799441D01*
G02X1198027Y799346I-165J-113D01*
G01X1198216Y797180D01*
Y797176D01*
X1198231Y796951D01*
X1198279Y796200D01*
X1198298Y795903D01*
X1198316Y795627D01*
G02Y795617I-200J-5D01*
G01X1198317Y795563D01*
X1198249Y795441D01*
G02X1198228Y795412I-172J102D01*
G01X1198227Y795411D01*
X1198202Y795382D01*
X1198178Y795366D01*
G03X1197499Y794111I820J-1255D01*
G03X1198385Y792739I1505J0D01*
G01X1198396Y792734D01*
X1198418Y792721D01*
G02X1198514Y792564I-104J-171D01*
G01Y792563D01*
X1198524Y792411D01*
Y792409D01*
X1198532Y792293D01*
Y792291D01*
X1198534Y792252D01*
G02X1198524Y792180I-199J-9D01*
G01X1198510Y792135D01*
X1198486Y792100D01*
X1198446Y792042D01*
G02X1198371Y791976I-165J112D01*
G01X1198360Y791971D01*
X1198358Y791970D01*
G03X1197495Y790610I640J-1360D01*
G03X1198543Y789178I1502J0D01*
G01X1198566Y789170D01*
G02X1198638Y789114I-84J-182D01*
G01X1198705Y789032D01*
G02X1198735Y788983I-154J-128D01*
G01X1198748Y788951D01*
X1198755Y788843D01*
X1198784Y788391D01*
G02X1198752Y788269I-200J-13D01*
G01X1198735Y788243D01*
X1198684Y788202D01*
X1198654Y788191D01*
G03X1197675Y786783I523J-1408D01*
G03X1198840Y785319I1502J0D01*
G01X1198841D01*
G02X1198949Y785253I-45J-195D01*
G01X1198969Y785230D01*
X1198993Y785170D01*
X1199016Y784810D01*
X1199370Y779346D01*
X1199491Y777471D01*
X1199517Y777072D01*
X1199526Y776934D01*
X1199531Y776851D01*
X1200194Y766618D01*
X1200406Y763340D01*
X1200983Y754418D01*
X1204282Y703455D01*
G03X1204441Y702575I3884J247D01*
G01X1210981Y681038D01*
G02X1210983Y681032I-189J-66D01*
G01X1213181Y672827D01*
G03X1213573Y671880I3793J1015D01*
G01X1234679Y635322D01*
X1234681Y635222D01*
X1234658Y635177D01*
G03X1234498Y634535I1342J-675D01*
G01Y634477D01*
G03X1235032Y633351I1503J23D01*
G01X1235062Y633326D01*
X1235121Y633218D01*
X1235134Y633182D01*
X1235138Y633153D01*
X1235139Y633142D01*
X1235145Y633066D01*
G02X1235130Y632972I-199J-16D01*
G01X1235090Y632877D01*
X1235065Y632850D01*
X1235064Y632849D01*
G03X1234629Y631751I1168J-1098D01*
G03X1236232Y630148I1603J0D01*
G01X1236249D01*
G02X1236389Y630091I0J-200D01*
G01X1236476Y630004D01*
G02X1236534Y629874I-142J-141D01*
G03X1237099Y628785I1500J87D01*
G01X1237117Y628771D01*
X1237165Y628734D01*
G03X1237189Y628718I123J158D01*
G01X1237194Y628715D01*
X1237236Y628688D01*
G03X1237240Y628686I674J1342D01*
G01X1237248Y628681D01*
G02X1237304Y628630I-104J-171D01*
G01X1237350Y628568D01*
G02X1237382Y628503I-161J-119D01*
G02X1237384Y628495I-193J-53D01*
G01X1237414Y628370D01*
G02X1237419Y628324I-195J-44D01*
G01Y628162D01*
G02X1237398Y628073I-200J0D01*
G01X1237388Y628052D01*
X1237386Y628050D01*
G03X1237288Y627839I1309J-736D01*
G03X1237232Y627655I1406J-528D01*
G01X1237231Y627649D01*
X1237229Y627641D01*
G03X1237225Y627622I1468J-319D01*
G02X1237102Y627477I-196J41D01*
G01X1236986Y627432D01*
G02X1236798Y627455I-73J186D01*
G03X1235930Y627731I-868J-1227D01*
G03X1234428Y626229I0J-1502D01*
G03X1234999Y625050I1501J-1D01*
G01X1235001D01*
Y625049D01*
G02X1235072Y624855I-125J-156D01*
G01X1235005Y624506D01*
G02X1234866Y624352I-196J38D01*
G03X1233790Y622912I426J-1440D01*
G03X1236794I1502J0D01*
G03X1236223Y624091I-1501J1D01*
G01X1236221D01*
Y624092D01*
G02X1236150Y624286I125J156D01*
G01X1236217Y624635D01*
G02X1236356Y624789I196J-38D01*
G03X1237364Y625783I-426J1440D01*
G01Y625784D01*
G02X1237482Y625910I191J-60D01*
G01X1237773Y626024D01*
G02X1237945Y626011I72J-186D01*
G01X1237946D01*
G03X1238695Y625811I749J1303D01*
G01X1238730D01*
G03X1239599Y626113I-35J1502D01*
G03X1239682Y626180I-902J1202D01*
G01X1239696Y626192D01*
X1239713Y626202D01*
G02X1239986Y626129I100J-173D01*
G01X1240764Y624781D01*
X1240769Y624740D01*
G03X1241272Y623200I3903J423D01*
G01X1242248Y621510D01*
G03X1243058Y620522I3401J1962D01*
G02X1243123Y620411I-131J-151D01*
G03X1243573Y619215I3851J766D01*
G01X1243949Y618565D01*
G02X1243968Y618409I-173J-100D01*
G01X1243885Y618131D01*
G02X1243784Y618009I-192J56D01*
G03X1242202Y616532I1785J-3497D01*
G02X1242153Y616477I-171J103D01*
G03X1241570Y615289I919J-1188D01*
G01Y615287D01*
G03X1241640Y614833I1502J-1D01*
G02X1241649Y614760I-190J-61D01*
G03X1241642Y614511I3919J-235D01*
G03X1241991Y612893I3927J0D01*
G02Y612729I-183J-82D01*
G03X1241642Y611111I3578J-1618D01*
G03X1241643Y611004I3926J-17D01*
G01X1241645Y610928D01*
G02X1241621Y610895I-173J101D01*
G01X1241501Y610772D01*
X1241500Y610771D01*
X1241419Y610689D01*
G02X1241391Y610666I-140J142D01*
G02X1241277Y610630I-114J164D01*
G01X1240298D01*
G03X1239049Y610424I0J-3892D01*
G01X1239045Y610423D01*
X1239028Y610418D01*
X1239012Y610413D01*
X1239000Y610411D01*
G03X1238869Y610384I720J-3823D01*
G03X1238867Y610383I86J-174D01*
G03X1238845Y610378I852J-3798D01*
G01X1238805Y610368D01*
G03X1238789Y610364I936J-3778D01*
G03X1238712Y610344I940J-3776D01*
G03X1238651Y610327I1014J-3757D01*
G03X1238502Y610281I1073J-3741D01*
G01X1238501D01*
X1238497Y610280D01*
G03X1238267Y610195I1234J-3692D01*
G01X1238260Y610192D01*
G03X1238231Y610180I1474J-3602D01*
G01X1237980D01*
X1237910Y610208D01*
X1237881Y610236D01*
G03X1235166Y611326I-2715J-2836D01*
G03X1231802Y609423I1J-3927D01*
G02X1231752Y609368I-170J105D01*
G03X1231168Y608179I918J-1189D01*
G01Y608176D01*
G03X1231238Y607721I1502J-2D01*
G02X1231247Y607648I-190J-61D01*
G03X1231240Y607399I3919J-235D01*
G03X1231589Y605781I3927J0D01*
G02Y605617I-183J-82D01*
G03X1231240Y603999I3578J-1618D01*
G03X1231247Y603749I3926J-15D01*
G02X1231238Y603676I-199J-12D01*
G03X1231178Y603397I1432J-454D01*
G01X1231173Y603349D01*
G03X1231167Y603221I1497J-134D01*
G01Y603138D01*
X1231173Y603089D01*
G03X1231650Y602118I1496J132D01*
G03X1231751Y602032I1023J1100D01*
G02X1231799Y601977I-124J-157D01*
G03X1235166Y600072I3367J2023D01*
G03X1237880Y601162I-1J3927D01*
G02X1238018Y601218I139J-144D01*
G01X1241436D01*
G02X1241481Y601178I-109J-168D01*
G01X1241497Y601158D01*
X1241524Y601128D01*
X1241553Y601057D01*
Y601055D01*
X1241573Y601008D01*
X1241576Y600977D01*
G03X1241580Y600940I1495J143D01*
G03X1241600Y600815I1492J175D01*
G01X1241606Y600787D01*
X1241608Y600779D01*
X1241609Y600774D01*
G03X1241612Y600762I1457J358D01*
G01X1241613Y600759D01*
Y600757D01*
X1241616Y600746D01*
X1241617Y600741D01*
G03X1241633Y600683I1456J370D01*
G02X1241635Y600679I-175J-90D01*
G03X1241638Y600667I1459J358D01*
G03X1241639Y600664I1426J474D01*
G01X1241642Y600654D01*
X1241643Y600653D01*
X1241652Y600621D01*
X1241649Y600586D01*
G03X1241642Y600338I3919J-235D01*
G03X1241991Y598720I3927J0D01*
G02Y598556I-183J-82D01*
G03X1241642Y596938I3578J-1618D01*
G03X1241652Y596651I3926J-7D01*
G03X1241641Y596619I1415J-504D01*
G01Y596616D01*
X1241632Y596588D01*
G03X1241607Y596492I1440J-426D01*
G01Y596491D01*
G02X1241564Y596405I-195J44D01*
G01X1241534Y596370D01*
X1241530Y596367D01*
X1241496Y596329D01*
G02X1241431Y596281I-149J134D01*
G01X1241426Y596279D01*
X1241420Y596276D01*
G03X1241248Y596215I1215J-3699D01*
G01X1241247Y596214D01*
G03X1240824Y596028I1353J-3650D01*
G02X1240733Y596006I-91J178D01*
G01X1238018D01*
G02X1237880Y596062I1J200D01*
G03X1235166Y597152I-2715J-2837D01*
G03X1231802Y595249I1J-3927D01*
G02X1231752Y595194I-170J105D01*
G03X1231168Y594005I918J-1189D01*
G01Y594002D01*
G03X1231238Y593547I1502J-2D01*
G02X1231247Y593474I-190J-61D01*
G03X1231240Y593225I3919J-235D01*
G03X1231589Y591607I3927J0D01*
G02Y591443I-183J-82D01*
G03X1231240Y589825I3578J-1618D01*
G03X1231247Y589575I3926J-15D01*
G02X1231238Y589502I-199J-12D01*
G03X1231178Y589223I1432J-454D01*
G01X1231173Y589175D01*
G03X1231167Y589047I1497J-134D01*
G01Y588964D01*
X1231173Y588915D01*
G03X1231650Y587944I1496J132D01*
G03X1231751Y587858I1023J1100D01*
G02X1231799Y587803I-124J-157D01*
G03X1235166Y585898I3367J2023D01*
G03X1237880Y586988I-1J3927D01*
G02X1238018Y587044I139J-144D01*
G01X1241354D01*
G02X1241507Y586973I0J-200D01*
G01X1241526Y586951D01*
X1241539Y586914D01*
X1241573Y586837D01*
X1241576Y586804D01*
G03X1241615Y586577I1496J140D01*
G03X1241650Y586459I1456J368D01*
G03X1241651Y586454I1472J292D01*
G03X1241652Y586452I178J88D01*
G03X1241642Y586165I3916J-280D01*
G03X1241991Y584547I3927J0D01*
G02Y584383I-183J-82D01*
G03X1241642Y582766I3578J-1618D01*
G01Y582764D01*
G03X1241643Y582648I3926J-24D01*
G01X1241644Y582607D01*
X1241615Y582532D01*
X1241458Y582372D01*
X1241421Y582334D01*
G02X1241394Y582311I-143J140D01*
G02X1241278Y582274I-116J163D01*
G01X1239908D01*
G03X1239155Y582200I2J-3891D01*
G03X1239106Y582190I754J-3817D01*
G03X1238783Y582107I806J-3807D01*
G03X1238148Y581853I1122J-3726D01*
G01X1238109Y581834D01*
X1238019D01*
G02X1237881Y581889I0J200D01*
G03X1235168Y582978I-2714J-2837D01*
G01X1235166D01*
G03X1231800Y581073I0J-3926D01*
G02X1231751Y581018I-171J103D01*
G03X1231168Y579830I919J-1188D01*
G01Y579828D01*
G03X1231169Y579774I1501J1D01*
G01Y579766D01*
G03X1231202Y579513I1501J67D01*
G03X1231239Y579374I1468J316D01*
G02X1231247Y579301I-191J-58D01*
G03X1231240Y579052I3919J-235D01*
G03X1231589Y577434I3927J0D01*
G02Y577270I-183J-82D01*
G03X1231240Y575652I3578J-1618D01*
G03X1231247Y575402I3926J-15D01*
G02X1231238Y575329I-199J-12D01*
G03X1231178Y575050I1432J-454D01*
G01X1231173Y575002D01*
G03X1231167Y574874I1497J-134D01*
G01Y574791D01*
X1231173Y574742D01*
G03X1231650Y573771I1496J132D01*
G03X1231751Y573685I1023J1100D01*
G02X1231799Y573630I-124J-157D01*
G03X1235166Y571726I3366J2023D01*
G03X1237880Y572815I0J3926D01*
G02X1238018Y572870I138J-145D01*
G01X1241446D01*
X1241463Y572850D01*
X1241499Y572809D01*
X1241525Y572779D01*
X1241574Y572659D01*
X1241577Y572619D01*
Y572617D01*
G03X1241588Y572530I1495J145D01*
G03X1241589Y572528I171J84D01*
G03X1241604Y572447I1484J233D01*
G01X1241608Y572432D01*
X1241609Y572427D01*
G03X1241612Y572415I1457J358D01*
G01X1241613Y572412D01*
Y572410D01*
X1241616Y572399D01*
X1241617Y572394D01*
G03X1241633Y572336I1456J370D01*
G02X1241635Y572332I-175J-90D01*
G03X1241638Y572320I1459J358D01*
G03X1241639Y572317I1426J474D01*
G01X1241642Y572307D01*
X1241643Y572306D01*
X1241652Y572274D01*
X1241649Y572239D01*
G03X1241642Y571991I3919J-235D01*
G03X1241991Y570373I3927J0D01*
G02Y570209I-183J-82D01*
G03X1241642Y568591I3578J-1618D01*
G03X1241649Y568342I3926J-14D01*
G02X1241640Y568269I-199J-12D01*
G03X1241570Y567817I1432J-453D01*
G01Y567815D01*
G03Y567811I1502J-2D01*
G01Y567809D01*
G03X1241633Y567379I1502J0D01*
G01X1241637Y567366D01*
X1241648Y567300D01*
X1241642Y567266D01*
X1241626Y567174D01*
G02X1241585Y567082I-197J33D01*
G01X1241497Y566959D01*
Y566957D01*
X1241425Y566855D01*
G02X1241390Y566826I-144J139D01*
G01X1241017D01*
G02X1240940Y566841I-1J200D01*
G01X1239684Y567362D01*
G03X1238185Y567660I-1500J-3628D01*
G01X1237980D01*
X1237910Y567688D01*
X1237881Y567716D01*
G03X1235166Y568806I-2715J-2836D01*
G03X1231802Y566903I1J-3927D01*
G02X1231752Y566848I-170J105D01*
G03X1231168Y565659I918J-1189D01*
G01Y565656D01*
G03X1231238Y565201I1502J-2D01*
G02X1231247Y565128I-190J-61D01*
G03X1231240Y564879I3919J-235D01*
G03X1231589Y563261I3927J0D01*
G02Y563097I-183J-82D01*
G03X1231240Y561479I3578J-1618D01*
G03X1231247Y561229I3926J-15D01*
G02X1231238Y561156I-199J-12D01*
G03X1231178Y560877I1432J-454D01*
G01X1231173Y560829D01*
G03X1231167Y560701I1497J-134D01*
G01Y560618D01*
X1231173Y560569D01*
G03X1231650Y559598I1496J132D01*
G03X1231751Y559512I1023J1100D01*
G02X1231799Y559457I-124J-157D01*
G03X1235166Y557552I3367J2023D01*
G03X1237612Y558407I0J3926D01*
G01X1237655Y558442D01*
X1237762Y558457D01*
X1238474Y558162D01*
G03X1239973Y557864I1500J3628D01*
G01X1243481D01*
G03X1244979Y558162I-2J3927D01*
G01X1248417Y559586D01*
G02X1248432Y559591I71J-187D01*
G01X1250162Y560150D01*
G03X1251352Y560778I-1194J3705D01*
G01X1251398Y560813D01*
G02X1251444Y560840I123J-157D01*
G01X1251973Y561059D01*
G03X1253246Y561911I-1505J3626D01*
G01X1254844Y563509D01*
G02X1254863Y563526I143J-140D01*
G01X1255055Y563676D01*
X1257391Y565504D01*
G02X1257636Y565505I123J-158D01*
G01X1257690Y565464D01*
X1257725Y565333D01*
X1257257Y564203D01*
X1257233Y564168D01*
X1257216Y564153D01*
G03X1257012Y563951I2635J-2865D01*
G03X1256957Y563891I2841J-2660D01*
G02X1256953Y563887I-143J139D01*
G03X1256175Y562688I2850J-2701D01*
G01X1255486Y561024D01*
G03X1255196Y559788I3628J-1503D01*
G02X1255147Y559669I-200J13D01*
G03X1254475Y558586I2956J-2584D01*
G01X1253786Y556922D01*
G03X1253496Y555684I3628J-1503D01*
G02X1253447Y555565I-200J13D01*
G03X1252859Y554671I2956J-2585D01*
G01X1252838Y554627D01*
X1252762Y554569D01*
X1252351Y554497D01*
G03X1252204Y554384I34J-197D01*
G03X1252201Y554377I182J-82D01*
G01X1252196Y554366D01*
X1252195Y554364D01*
X1252183Y554334D01*
G02X1252139Y554269I-185J78D01*
G01X1252126Y554256D01*
X1252120Y554251D01*
G03X1251611Y553380I967J-1149D01*
G01Y553379D01*
X1251603Y553380D01*
X1251591Y553235D01*
Y553233D01*
G03X1251585Y553136I1495J-141D01*
G01Y553133D01*
X1251584Y553104D01*
G03X1251840Y552262I1503J-3D01*
G02X1251870Y552110I-166J-112D01*
G03X1251797Y551581I3844J-800D01*
G02X1251748Y551464I-199J15D01*
G03X1251351Y550922I2958J-2583D01*
G03X1251349Y550918I177J-91D01*
G03X1251346Y550913I3365J-2023D01*
G01X1251342Y550907D01*
X1251326Y550881D01*
X1251325Y550880D01*
G03X1251028Y550308I3294J-2073D01*
G01X1250813Y549794D01*
X1250356Y548703D01*
X1250355Y548701D01*
G03X1250342Y548671I3564J-1562D01*
G01Y548670D01*
X1250327Y548633D01*
G03X1250319Y548613I3609J-1455D01*
G03X1250294Y548548I3620J-1429D01*
G01Y548547D01*
X1250267Y548475D01*
G03X1250266Y548472I188J-64D01*
G01X1250265Y548466D01*
X1250235Y548376D01*
G03X1250084Y547688I3710J-1175D01*
G03X1250066Y547519I3860J-497D01*
G03X1250061Y547450I3879J-316D01*
G01X1250059Y547417D01*
X1250022Y547329D01*
X1250003Y547307D01*
G03X1249825Y547080I2999J-2535D01*
G02X1249821Y547074I-168J108D01*
G03X1249510Y546611I3067J-2396D01*
G03X1249299Y546182I3380J-1929D01*
G01X1249286Y546156D01*
X1248793Y544977D01*
X1248690Y544731D01*
X1248624Y544574D01*
Y544573D01*
X1248608Y544535D01*
G03X1248600Y544516I3582J-1520D01*
G01Y544515D01*
X1248584Y544477D01*
X1248578Y544459D01*
X1248576Y544454D01*
G03X1248544Y544367I3636J-1387D01*
G03X1248542Y544364I161J-109D01*
G03X1248529Y544325I3685J-1250D01*
G01Y544322D01*
X1248518Y544289D01*
G03X1248329Y543318I3694J-1223D01*
G01X1248327Y543283D01*
X1248282Y543179D01*
X1248260Y543149D01*
X1248231Y543112D01*
X1248226Y543106D01*
G03X1248069Y542918I2907J-2587D01*
G01X1248029Y542864D01*
G03X1248001Y542826I3119J-2327D01*
G01X1247999Y542823D01*
X1247989Y542809D01*
G03X1247877Y542644I3163J-2267D01*
G03X1247565Y542049I3278J-2098D01*
G01X1246892Y540444D01*
G03X1246781Y540147I3587J-1510D01*
G01X1246769Y540110D01*
X1246692Y540017D01*
G02X1246659Y539989I-145J137D01*
G01X1246626Y539970D01*
G02X1246523Y539941I-104J171D01*
G01X1246493D01*
X1246471Y539946D01*
G03X1245568Y540052I-906J-3821D01*
G03X1242204Y538149I1J-3927D01*
G02X1242154Y538094I-170J105D01*
G03X1241570Y536905I918J-1189D01*
G01Y536902D01*
G03X1241640Y536448I1502J-1D01*
G02X1241649Y536375I-190J-61D01*
G03X1241642Y536125I3919J-235D01*
G03X1241991Y534507I3927J0D01*
G02Y534343I-183J-82D01*
G03X1241642Y532725I3578J-1618D01*
G03X1241643Y532618I3926J-17D01*
G01X1241645Y532542D01*
G02X1241621Y532509I-173J101D01*
G01X1241501Y532386D01*
X1241500Y532385D01*
X1241419Y532303D01*
G02X1241391Y532280I-140J142D01*
G02X1241277Y532244I-114J164D01*
G01X1240242D01*
G03X1239762Y532214I2J-3892D01*
G01X1239760D01*
G03X1237993Y531794I0J-3927D01*
G01X1237937D01*
G03X1235166Y532940I-2772J-2780D01*
G03X1231802Y531037I1J-3927D01*
G02X1231752Y530982I-170J105D01*
G03X1231168Y529793I918J-1189D01*
G01Y529790D01*
G03X1231238Y529335I1502J-2D01*
G02X1231247Y529262I-190J-61D01*
G03X1231240Y529013I3919J-235D01*
G03X1231589Y527395I3927J0D01*
G02Y527231I-183J-82D01*
G03X1231240Y525613I3578J-1618D01*
G03X1231247Y525363I3926J-15D01*
G02X1231238Y525290I-199J-12D01*
G03X1231178Y525011I1432J-454D01*
G01X1231173Y524963D01*
G03X1231167Y524835I1497J-134D01*
G01Y524752D01*
X1231173Y524703D01*
G03X1231650Y523732I1496J132D01*
G03X1231751Y523646I1024J1100D01*
G02X1231799Y523591I-124J-157D01*
G03X1235166Y521686I3367J2023D01*
G03X1237880Y522776I-1J3927D01*
G02X1238018Y522832I139J-144D01*
G01X1241436D01*
G02X1241481Y522792I-109J-168D01*
G01X1241497Y522772D01*
X1241524Y522742D01*
X1241553Y522671D01*
Y522669D01*
X1241573Y522622D01*
X1241576Y522591D01*
G03X1241580Y522554I1495J143D01*
G03X1241600Y522429I1492J175D01*
G03X1241640Y522275I1472J300D01*
G02X1241649Y522202I-190J-61D01*
G03X1241642Y521952I3919J-235D01*
G03X1241991Y520334I3927J0D01*
G02Y520170I-183J-82D01*
G03X1241642Y518552I3578J-1618D01*
G03X1241643Y518445I3926J-17D01*
G01X1241645Y518368D01*
G02X1241621Y518335I-173J101D01*
G01X1241501Y518212D01*
X1241500Y518211D01*
X1241419Y518129D01*
G02X1241391Y518106I-140J142D01*
G02X1241277Y518070I-114J164D01*
G01X1240261D01*
G03X1238489Y517642I2J-3892D01*
G02X1238398Y517620I-91J178D01*
G01X1237980D01*
X1237910Y517648D01*
X1237881Y517676D01*
G03X1235166Y518766I-2715J-2836D01*
G03X1231802Y516863I1J-3927D01*
G02X1231752Y516808I-170J105D01*
G03X1231168Y515619I918J-1189D01*
G01Y515616D01*
G03X1231238Y515161I1502J-2D01*
G02X1231247Y515088I-190J-61D01*
G03X1231240Y514839I3919J-235D01*
G03X1231589Y513221I3927J0D01*
G02Y513057I-183J-82D01*
G03X1231240Y511439I3578J-1618D01*
G03X1231247Y511190I3926J-14D01*
G02X1231238Y511117I-199J-12D01*
G03X1231168Y510663I1432J-453D01*
G01Y510619D01*
G03X1231751Y509472I1502J42D01*
G02X1231801Y509417I-120J-160D01*
G03X1235166Y507512I3366J2021D01*
G03X1237880Y508602I-1J3927D01*
G02X1238018Y508658I139J-144D01*
G01X1245906D01*
G03X1247409Y508957I0J3927D01*
G01X1251463Y510636D01*
G02X1251680Y510593I76J-185D01*
G01X1251723Y510550D01*
X1251747Y510431D01*
X1251702Y510325D01*
G03X1251407Y509110I3619J-1522D01*
G02X1251358Y508994I-200J16D01*
G03X1250691Y507930I2950J-2591D01*
G01X1249992Y506270D01*
G03X1249697Y505055I3619J-1522D01*
G02X1249648Y504939I-200J16D01*
G03X1248981Y503875I2950J-2591D01*
G01X1248282Y502215D01*
G03X1248007Y501190I3620J-1521D01*
G02X1247997Y501151I-198J30D01*
G03X1247803Y500219I3684J-1253D01*
G03X1247793Y500058I3878J-322D01*
G02X1247779Y499991I-200J7D01*
G03X1247564Y499275I3636J-1482D01*
G01X1246903Y495949D01*
X1246902Y495948D01*
X1246666Y495799D01*
X1246642Y495784D01*
X1246614Y495776D01*
X1246542Y495795D01*
G03X1245568Y495918I-975J-3804D01*
G03X1242204Y494016I0J-3926D01*
G02X1242154Y493961I-170J105D01*
G03X1241570Y492771I918J-1189D01*
G01Y492768D01*
G03X1241640Y492313I1502J-2D01*
G02X1241649Y492240I-190J-61D01*
G03X1241642Y491991I3919J-235D01*
G03X1241991Y490373I3927J0D01*
G02Y490209I-183J-82D01*
G03X1241642Y488591I3578J-1618D01*
G03X1241649Y488342I3926J-14D01*
G02X1241640Y488269I-199J-12D01*
G03X1241583Y488014I1432J-454D01*
G02X1241450Y487852I-198J27D01*
G03X1241026Y487679I1269J-3716D01*
G02X1240940Y487660I-85J181D01*
G01X1238018D01*
G02X1237880Y487716I1J200D01*
G03X1235166Y488806I-2715J-2837D01*
G03X1231802Y486903I1J-3927D01*
G02X1231752Y486848I-170J105D01*
G03X1231168Y485659I918J-1189D01*
G01Y485656D01*
G03X1231238Y485201I1502J-2D01*
G02X1231247Y485128I-190J-61D01*
G03X1231240Y484879I3919J-235D01*
G03X1231589Y483261I3927J0D01*
G02Y483097I-183J-82D01*
G03X1231240Y481479I3578J-1618D01*
G03X1231247Y481229I3926J-15D01*
G02X1231238Y481156I-199J-12D01*
G03X1231178Y480877I1432J-454D01*
G01X1231173Y480829D01*
G03X1231167Y480701I1497J-134D01*
G01Y480618D01*
X1231173Y480569D01*
G03X1231650Y479598I1496J132D01*
G03X1231751Y479512I1024J1100D01*
G02X1231799Y479457I-124J-157D01*
G03X1235166Y477552I3367J2023D01*
G03X1237880Y478642I-1J3927D01*
G02X1238018Y478698I139J-144D01*
G01X1241436D01*
G02X1241481Y478658I-109J-168D01*
G01X1241497Y478638D01*
X1241524Y478608D01*
X1241553Y478537D01*
Y478535D01*
X1241573Y478488D01*
X1241576Y478457D01*
G03X1241580Y478420I1495J143D01*
G03X1241600Y478295I1492J175D01*
G03X1241640Y478141I1472J300D01*
G02X1241649Y478068I-190J-61D01*
G03X1241642Y477818I3919J-235D01*
G03X1241991Y476200I3927J0D01*
G02Y476036I-183J-82D01*
G03X1241642Y474419I3578J-1618D01*
G01Y474417D01*
G03X1241643Y474303I3926J-23D01*
G01X1241646Y474226D01*
G02X1241624Y474198I-168J109D01*
G01X1241467Y474028D01*
G02X1241410Y473985I-147J136D01*
G01X1241307Y473933D01*
X1241267Y473929D01*
X1241261Y473928D01*
X1241248Y473927D01*
G03X1240226Y473713I279J-3882D01*
G03X1240151Y473686I1281J-3675D01*
G03X1240149Y473684I140J-142D01*
G03X1240130Y473677I1336J-3655D01*
G01X1240129D01*
X1240118Y473672D01*
X1240109Y473669D01*
G03X1239939Y473599I1396J-3633D01*
G02X1239935Y473597I-91J178D01*
G03X1239732Y473507I1489J-3633D01*
G01X1239730D01*
X1239690Y473488D01*
X1238018D01*
G02X1237880Y473543I0J200D01*
G03X1235167Y474632I-2714J-2837D01*
G01X1235166D01*
G03X1231800Y472727I0J-3926D01*
G02X1231751Y472672I-171J103D01*
G03X1231168Y471484I919J-1188D01*
G01Y471482D01*
G03X1231169Y471428I1501J1D01*
G01Y471420D01*
G03X1231202Y471167I1500J67D01*
G03X1231239Y471028I1468J316D01*
G02X1231247Y470955I-191J-58D01*
G03X1231240Y470706I3919J-235D01*
G03X1231589Y469088I3927J0D01*
G02Y468924I-183J-82D01*
G03X1231240Y467306I3578J-1618D01*
G03X1231247Y467056I3926J-15D01*
G02X1231238Y466983I-199J-12D01*
G03X1231178Y466704I1432J-454D01*
G01X1231173Y466656D01*
G03X1231167Y466528I1497J-134D01*
G01Y466445D01*
X1231173Y466396D01*
G03X1231650Y465425I1496J132D01*
G03X1231751Y465339I1024J1100D01*
G02X1231799Y465284I-124J-157D01*
G03X1235166Y463380I3367J2025D01*
G01X1235167D01*
G03X1237880Y464469I-1J3926D01*
G02X1238018Y464524I138J-145D01*
G01X1245755D01*
G03X1247936Y465186I-1J3927D01*
G01X1259526Y472929D01*
G03X1260973Y474691I-2180J3266D01*
G01X1268189Y492114D01*
X1268253Y492173D01*
X1268276Y492180D01*
G03X1269345Y493604I-433J1438D01*
G01Y493642D01*
G03X1269334Y493804I-1502J-21D01*
G03X1269158Y494345I-1490J-186D01*
G02X1269154Y494351I164J113D01*
G01X1269151Y494437D01*
X1276666Y512578D01*
G02X1276709Y512643I185J-76D01*
G01X1277370Y513305D01*
G03X1278222Y514578I-2774J2778D01*
G01X1299076Y564923D01*
G02X1299260Y565047I185J-76D01*
G01X1299689Y565049D01*
X1299789Y564983D01*
X1299813Y564927D01*
G03X1301194Y564016I1381J591D01*
G03X1302686Y565342I0J1502D01*
G01X1302692Y565396D01*
G03X1302697Y565518I-1498J122D01*
G01Y565598D01*
X1302692Y565645D01*
G03X1301942Y566821I-1497J-127D01*
G01X1301919Y566835D01*
X1301905Y566843D01*
X1301880Y566862D01*
X1301868Y566871D01*
X1301835Y566904D01*
G02X1301796Y566958I140J143D01*
G01X1301782Y566988D01*
X1301778Y567022D01*
X1301764Y567140D01*
Y567142D01*
X1301747Y567282D01*
G02X1301745Y567306I198J29D01*
G01Y567365D01*
X1301782Y567448D01*
X1301784Y567452D01*
X1301792Y567470D01*
X1301835Y567529D01*
X1301849Y567542D01*
G03X1302320Y568633I-1030J1092D01*
G01Y568635D01*
G03X1301377Y570031I-1505J0D01*
G02X1301373Y570033I87J179D01*
G01X1301326Y570053D01*
X1301263Y570205D01*
X1311736Y595487D01*
G02X1311921Y595610I185J-77D01*
G01X1314654D01*
G02X1314683Y595608I1J-200D01*
G01X1316814Y593476D01*
G03X1317050Y593289I924J924D01*
G01X1317070Y593277D01*
X1318086Y592261D01*
G02X1318144Y592115I-142J-141D01*
G01Y592112D01*
X1318128Y591811D01*
G02X1318107Y591731I-200J10D01*
G01X1318089Y591696D01*
X1318054Y591668D01*
G03X1317497Y590500I946J-1168D01*
G03X1317501Y590391I1503J1D01*
G01X1317504Y590366D01*
G03X1318979Y588998I1496J134D01*
G01X1319000D01*
G03X1320168Y589554I1J1503D01*
G01X1320169Y589555D01*
G02X1320235Y589609I157J-124D01*
G01X1320269Y589626D01*
X1320609Y589644D01*
G02X1320612I1J-200D01*
G01X1320616D01*
G02X1320759Y589587I3J-200D01*
G01X1323077Y587269D01*
G02X1323094Y587249I-144J-139D01*
G01Y582999D01*
G03X1323477Y582075I1306J0D01*
G01X1325294Y580258D01*
G03X1325683Y579990I924J924D01*
G01X1325725Y579971D01*
X1325785Y579899D01*
X1325803Y579823D01*
Y579822D01*
X1325856Y579597D01*
G02X1325857Y579509I-194J-46D01*
G01X1325848Y579465D01*
X1325819Y579429D01*
G03X1325498Y578519I1181J-928D01*
G01Y578476D01*
G03X1327000Y576998I1502J24D01*
G01X1327019D01*
G03X1327573Y577111I-18J1502D01*
G01X1327589Y577118D01*
X1327625Y577126D01*
G02X1327759Y577110I45J-195D01*
G01X1327782Y577098D01*
X1327826Y577068D01*
X1327828D01*
X1328056Y576917D01*
G02X1328106Y576870I-110J-167D01*
G01Y574987D01*
X1328100Y574976D01*
X1328059Y574948D01*
X1328057D01*
X1327916Y574852D01*
X1327775Y574756D01*
X1327757Y574747D01*
G02X1327695Y574729I-86J181D01*
G01X1327643Y574723D01*
G03X1327044Y574848I-600J-1377D01*
G01X1326990D01*
X1326963Y574846D01*
X1326961D01*
G03Y571846I82J-1500D01*
G01X1326963D01*
X1326990Y571844D01*
X1327044D01*
G03X1327582Y571944I-1J1502D01*
G02X1327616Y571953I68J-188D01*
G01X1327673Y571964D01*
G02X1327776Y571935I-1J-200D01*
G01X1327887Y571860D01*
X1328058Y571744D01*
G02X1328060Y571742I-140J-142D01*
G03X1328066Y571738I114J164D01*
G02X1328106Y571698I-120J-160D01*
G01Y569855D01*
G02X1328047Y569713I-200J0D01*
G01X1327618Y569284D01*
X1327601Y569279D01*
X1327517Y569296D01*
X1327478Y569311D01*
G03X1326946Y569408I-531J-1405D01*
G01X1326937D01*
G03X1325444Y567906I9J-1502D01*
G03X1326946Y566404I1502J0D01*
G03X1327657Y566584I-2J1502D01*
G01X1327689Y566600D01*
X1328089D01*
G03X1329011Y566982I-1J1306D01*
G01X1329298Y567269D01*
G02X1329313Y567274I134J-377D01*
G01X1329315D01*
G02X1329750Y567132I116J-383D01*
G02X1329790Y567012I-160J-120D01*
G01Y550674D01*
X1329782Y550659D01*
G03X1329594Y549931I1316J-728D01*
G03X1332598I1502J0D01*
G03X1332426Y550631I-1502J2D01*
G01X1332414Y550653D01*
X1332402Y550700D01*
Y587217D01*
G03X1332020Y588139I-1306J-1D01*
G01X1327524Y592635D01*
Y592694D01*
X1327538Y592784D01*
X1327574Y593013D01*
G02X1327610Y593100I197J-31D01*
G01Y593101D01*
G02X1327618Y593112I166J-112D01*
G03X1328520Y594500I-617J1388D01*
G03X1328379Y595139I-1520J0D01*
G02X1328380Y595155I200J-4D01*
G01X1328385Y595206D01*
X1328605Y595531D01*
G02X1328752Y595610I160J-121D01*
G01X1333231D01*
G02X1333269Y595606I-2J-200D01*
G02X1333371Y595553I-37J-196D01*
G01X1333399Y595525D01*
X1333587Y595249D01*
G02X1333622Y595150I-165J-114D01*
G01Y595140D01*
G03X1333480Y594500I1378J-641D01*
G03X1336520I1520J0D01*
G03X1336379Y595139I-1520J0D01*
G02X1336380Y595155I200J-4D01*
G01X1336385Y595206D01*
X1336605Y595531D01*
G02X1336752Y595610I160J-121D01*
G01X1349373D01*
G02X1349405Y595607I-3J-200D01*
G01X1349407D01*
G02X1349513Y595553I-34J-197D01*
G01X1351059Y594007D01*
G02X1351113Y593900I-143J-139D01*
G02X1351116Y593867I-197J-35D01*
G01Y560257D01*
G03X1351175Y560115I200J0D01*
G01X1354335Y556955D01*
G02X1354394Y556813I-141J-142D01*
G01Y548299D01*
G03X1354776Y547377I1306J1D01*
G01X1358835Y543319D01*
G02X1358894Y543177I-141J-142D01*
G01Y482197D01*
G03X1359276Y481275I1306J1D01*
G01X1364335Y476217D01*
G02X1364394Y476075I-141J-142D01*
G01Y395445D01*
G02X1364335Y395303I-200J0D01*
G01X1343032Y374000D01*
G02X1342965Y373956I-141J142D01*
G01X1342931Y373942D01*
X1339379D01*
G02X1339228Y374012I1J200D01*
G01X1339184Y374065D01*
X1339173Y374093D01*
G03X1337508Y375204I-1665J-692D01*
G01X1334107D01*
G03X1333815Y375180I1J-1803D01*
G01X1333813D01*
X1333756Y375171D01*
X1333739D01*
X1333544Y375367D01*
G02X1333545Y375398I200J9D01*
G01X1353817Y395670D01*
G03X1354200Y396594I-923J924D01*
G01Y416681D01*
G02X1354259Y416823I200J0D01*
G01X1358806Y421370D01*
G03X1359188Y422292I-924J923D01*
G01Y423226D01*
X1359191Y423232D01*
X1359221Y423257D01*
G02X1359258Y423281I127J-155D01*
G01X1359376Y423338D01*
X1359498Y423397D01*
G02X1359585Y423417I87J-180D01*
G01X1359724D01*
G02X1359818Y423393I-1J-200D01*
G01X1359839Y423382D01*
X1359858Y423370D01*
G03X1360717Y423099I860J1231D01*
G01X1360719D01*
G03Y426103I0J1502D01*
G03X1359795Y425785I0J-1501D01*
G01X1359773Y425768D01*
X1359721Y425747D01*
X1359694Y425744D01*
G02X1359586Y425763I-21J199D01*
G01X1359261Y425920D01*
G02X1359188Y425980I87J180D01*
G01Y453892D01*
G03X1358806Y454814I-1306J-1D01*
G01X1353539Y460081D01*
G03X1352615Y460464I-924J-923D01*
G01X1349460D01*
G02X1349420Y460503I118J161D01*
G01X1349291Y460700D01*
X1349229Y460795D01*
G02X1349219Y460812I167J110D01*
G02X1349208Y460970I178J92D01*
G01X1349215Y460986D01*
G03X1349348Y461589I-1369J618D01*
G01Y461627D01*
G03X1347846Y463109I-1502J-20D01*
G03X1346363Y461850I0J-1503D01*
G01X1346358Y461823D01*
X1346348Y461800D01*
G02X1346320Y461756I-181J84D01*
G01X1346259Y461680D01*
G02X1346169Y461617I-155J126D01*
G01X1345883Y461519D01*
G02X1345791Y461510I-65J189D01*
G01X1345313Y461987D01*
X1345288Y462030D01*
X1345281Y462053D01*
G03X1343846Y463109I-1435J-447D01*
G03X1342344Y461607I0J-1502D01*
G03X1343421Y460166I1503J0D01*
G01X1343447Y460158D01*
X1345372Y458233D01*
G03X1346296Y457850I924J923D01*
G01X1351991D01*
G02X1352133Y457791I0J-200D01*
G01X1356517Y453408D01*
G02X1356576Y453266I-141J-142D01*
G01Y422918D01*
G02X1356517Y422776I-200J0D01*
G01X1351969Y418229D01*
G03X1351586Y417305I923J-924D01*
G01Y397218D01*
G02X1351527Y397076I-200J0D01*
G01X1331714Y377263D01*
G02X1331572Y377204I-142J141D01*
G01X1313496D01*
G03X1312572Y376821I0J-1306D01*
G01X1311745Y375993D01*
G02X1311603Y375934I-142J141D01*
G01X1307220D01*
X1307165Y375950D01*
X1307153Y375958D01*
X1307146Y375974D01*
X1307129Y376013D01*
X1306980Y376343D01*
G02X1306973Y376362I184J79D01*
G02X1306971Y376483I190J64D01*
G01X1306973Y376488D01*
X1306992Y376538D01*
X1307017Y376566D01*
G03X1307412Y377578I-1107J1015D01*
G01Y377583D01*
G03X1307403Y377746I-1502J-1D01*
G01X1307397Y377798D01*
X1307416Y377844D01*
G02X1307476Y377923I184J-78D01*
G01X1307736Y378132D01*
G02X1307892Y378174I126J-156D01*
G01X1307926Y378169D01*
X1307944Y378163D01*
G03X1308409Y378089I466J1428D01*
G01X1308417D01*
G03X1309912Y379591I-7J1502D01*
G03X1308410Y381093I-1502J0D01*
G03X1306908Y379595I0J-1502D01*
G01Y379589D01*
G03X1306917Y379426I1502J1D01*
G01X1306923Y379374D01*
X1306904Y379328D01*
G02X1306844Y379249I-184J78D01*
G01X1306584Y379040D01*
G02X1306428Y378998I-126J156D01*
G01X1306394Y379003D01*
X1306376Y379009D01*
G03X1305911Y379083I-466J-1428D01*
G01X1305903D01*
G03X1304408Y377581I7J-1502D01*
G01Y377580D01*
G03X1304780Y376591I1502J0D01*
G01X1304803Y376565D01*
X1304834Y376486D01*
G02X1304835Y376340I-186J-74D01*
G01X1304832Y376333D01*
X1304831Y376332D01*
X1304733Y376110D01*
X1304685Y376001D01*
G02X1304627Y375934I-176J94D01*
G01X1298960D01*
G03X1298038Y375552I1J-1306D01*
G01X1295045Y372559D01*
G02X1294965Y372510I-142J141D01*
G01X1294964D01*
G03X1294948Y372505I440J-1436D01*
G01X1294944Y372504D01*
G03X1294423Y372208I466J-1427D01*
G03X1293976Y371523I987J-1132D01*
G01Y371521D01*
G02X1293927Y371441I-190J62D01*
G01X1293466Y370979D01*
G02X1293372Y370987I-31J198D01*
G01X1293088Y371083D01*
G02X1293057Y371096I62J190D01*
G02X1293010Y371131I95J176D01*
G01X1292996Y371145D01*
X1292934Y371219D01*
G02X1292905Y371267I155J126D01*
G01X1292895Y371289D01*
X1292890Y371314D01*
G03X1291410Y372562I-1480J-254D01*
G03X1289908Y371060I0J-1502D01*
G03X1291156Y369580I1502J0D01*
G01X1291181Y369575D01*
X1291203Y369565D01*
G02X1291251Y369536I-78J-184D01*
G01X1291328Y369472D01*
G02X1291381Y369399I-131J-151D01*
G01X1291385Y369387D01*
X1291449Y369201D01*
X1291484Y369099D01*
G02X1291493Y369007I-189J-65D01*
G01X1290332Y367846D01*
G03X1289950Y366924I924J-923D01*
G01Y361673D01*
G02X1289891Y361531I-200J0D01*
G01X1284765Y356405D01*
G02X1284623Y356346I-142J141D01*
G01X1256374D01*
G03X1255452Y355964I1J-1306D01*
G01X1231614Y332126D01*
G02X1231388Y332087I-141J142D01*
G01X1231048Y332246D01*
G02X1230934Y332446I85J181D01*
G03X1230940Y332584I-1496J134D01*
G03X1229438Y331082I-1502J0D01*
G03X1229576Y331088I4J1502D01*
G02X1229776Y330974I19J-199D01*
G01X1229935Y330634D01*
G02X1229896Y330408I-181J-85D01*
G01X1227860Y328371D01*
G02X1227718Y328312I-142J141D01*
G01X1225911D01*
G03X1224989Y327930I1J-1306D01*
G01X1222891Y325831D01*
G02X1222749Y325772I-142J141D01*
G01X1221466D01*
X1221451Y325780D01*
G03X1220723Y325968I-728J-1316D01*
G03Y322964I0J-1502D01*
G03X1221423Y323136I2J1502D01*
G01X1221445Y323148D01*
X1221492Y323160D01*
X1222299D01*
G02X1222419Y323120I0J-200D01*
G02X1222549Y322650I-241J-320D01*
G02X1222493Y322572I-186J74D01*
G03X1222414Y322500I840J-1001D01*
G01X1214713Y314799D01*
X1214691Y314790D01*
X1203009D01*
G02X1202874Y314843I1J200D01*
G01X1202689Y315013D01*
X1202687Y315015D01*
X1202676Y315025D01*
G02X1202631Y315084I134J149D01*
G01X1202614Y315118D01*
X1202611Y315157D01*
G03X1199615I-1498J-118D01*
G01X1199612Y315118D01*
X1199595Y315084D01*
G02X1199550Y315025I-179J90D01*
G01X1199539Y315015D01*
X1199537Y315013D01*
X1199352Y314843D01*
G02X1199254Y314793I-136J146D01*
G01X1199124Y314924D01*
G03X1198202Y315306I-923J-924D01*
G01X1183250D01*
G02X1183096Y315378I0J200D01*
G01X1182871Y315649D01*
X1182848Y315733D01*
X1182855Y315772D01*
G03X1182881Y316048I-1476J278D01*
G01Y316066D01*
G03X1181379Y317551I-1502J-17D01*
G03X1180014Y316678I0J-1504D01*
G01X1180013Y316674D01*
X1180005Y316656D01*
X1180004Y316654D01*
X1179988Y316617D01*
X1179962Y316592D01*
G02X1179860Y316539I-139J143D01*
G01X1179535Y316476D01*
G02X1179470Y316474I-39J196D01*
G01X1176396Y319547D01*
X1176371Y319590D01*
X1176364Y319613D01*
G03X1174929Y320669I-1435J-447D01*
G03X1173427Y319167I0J-1502D01*
G03X1174504Y317726I1503J0D01*
G01X1174530Y317718D01*
X1178018Y314230D01*
G02X1178012Y314147I-198J-27D01*
G01X1177915Y313831D01*
X1177902Y313809D01*
G02X1177879Y313780I-167J109D01*
G01X1177799Y313707D01*
X1177795Y313703D01*
G02X1177752Y313673I-135J148D01*
G01X1177730Y313662D01*
X1177724Y313661D01*
X1177686Y313652D01*
X1177685D01*
G03X1176543Y312193I361J-1459D01*
G03X1178045Y310691I1502J0D01*
G01X1178051D01*
G03X1178765Y310871I1J1503D01*
G01X1178795Y310886D01*
X1179187D01*
G02X1179213Y310864I-116J-163D01*
G01X1179221Y310856D01*
X1179423Y310622D01*
G02X1179444Y310589I-157J-123D01*
G01X1179430Y310505D01*
G03X1179400Y310131I2276J-371D01*
G03X1179562Y309282I2306J0D01*
G01X1179595Y309199D01*
G02X1179565Y309131I-195J45D01*
G01X1179451Y308964D01*
X1179382Y308863D01*
G02X1179257Y308780I-165J113D01*
G02X1179217Y308776I-40J196D01*
G01X1095009D01*
G02X1094904Y308806I0J200D01*
G01X1094881Y308820D01*
X1094844Y308860D01*
X1094831Y308886D01*
X1094691Y309163D01*
X1094688Y309166D01*
X1094670Y309202D01*
G02X1094649Y309291I179J89D01*
G01Y309327D01*
X1094669Y309387D01*
X1094688Y309413D01*
G03X1094980Y310303I-1210J890D01*
G01Y310336D01*
X1094979Y310362D01*
G03X1091977I-1501J-57D01*
G01X1091976Y310336D01*
Y310304D01*
G03X1092269Y309413I1502J0D01*
G02X1092308Y309310I-160J-120D01*
G01X1092312Y309255D01*
X1092265Y309162D01*
X1092125Y308886D01*
X1092124Y308885D01*
G02X1092052Y308806I-178J90D01*
G01X1092029Y308791D01*
X1091975Y308776D01*
X1077861D01*
G02X1077748Y308811I0J200D01*
G01X1077724Y308828D01*
X1077687Y308874D01*
X1077675Y308903D01*
X1077572Y309164D01*
Y309166D01*
X1077542Y309244D01*
G02X1077548Y309378I191J59D01*
G01X1077588Y309468D01*
X1077617Y309496D01*
G03X1078073Y310574I-1046J1078D01*
G03X1075069I-1502J0D01*
G03X1075525Y309496I1502J0D01*
G01X1075554Y309468D01*
X1075591Y309386D01*
G02X1075595Y309230I-182J-83D01*
G01X1075570Y309166D01*
Y309164D01*
X1075467Y308903D01*
Y308902D01*
G02X1075393Y308810I-186J74D01*
G01X1075369Y308793D01*
X1075312Y308776D01*
X1055290D01*
G02X1054904Y309072I0J400D01*
G02X1054956Y309266I193J52D01*
G01X1063793Y318103D01*
G02X1063935Y318162I142J-141D01*
G01X1075647D01*
G02X1075765Y318124I1J-200D01*
G01X1075804Y318095D01*
X1075822Y318072D01*
X1075842Y318047D01*
X1075853Y318018D01*
G03X1077252Y317063I1399J547D01*
G03X1078205Y317404I0J1502D01*
G01X1078216Y317413D01*
G02X1078260Y317436I114J-164D01*
G01X1078293Y317449D01*
G02X1078344Y317461I71J-187D01*
G01X1078346D01*
G02X1078378Y317462I22J-199D01*
G01X1078445Y317416D01*
G03X1079748Y317016I1304J1927D01*
G03X1082074Y319343I0J2326D01*
G03X1081592Y320762I-2326J1D01*
G01X1081551Y320814D01*
G02X1081550Y320831I199J20D01*
G01Y321236D01*
X1081572Y321298D01*
X1081592Y321324D01*
G03X1082074Y322741I-1844J1418D01*
G01Y322743D01*
G03X1079748Y325070I-2327J0D01*
G03X1078445Y324670I1J-2327D01*
G01X1078377Y324624D01*
G02X1078348Y324625I-8J200D01*
G01X1078346D01*
G02X1078295Y324637I20J199D01*
G01X1078262Y324650D01*
G02X1078211Y324678I70J187D01*
G01X1078188Y324696D01*
X1078154Y324722D01*
G03X1077262Y325023I-902J-1201D01*
G01X1077252D01*
G03X1077246I-3J-1502D01*
G01X1077243D01*
G03X1077052Y325010I6J-1502D01*
G03X1076146Y324538I200J-1489D01*
G01X1076129Y324520D01*
Y324519D01*
G03X1075852Y324066I1123J-998D01*
G01X1075841Y324038D01*
X1075822Y324014D01*
X1075821Y324012D01*
G02X1075782Y323975I-156J125D01*
G01X1075765Y323962D01*
G02X1075647Y323924I-117J162D01*
G01X1062428D01*
G03X1060783Y323243I0J-2327D01*
G01X1050635Y313095D01*
G02X1050493Y313036I-142J141D01*
G01X1032035D01*
G02X1031886Y313102I0J200D01*
G01X1031763Y313239D01*
G02X1031721Y313312I148J134D01*
G01X1031708Y313351D01*
G03X1031722Y313554I-1488J205D01*
G03X1030220Y315056I-1502J0D01*
G03X1028728Y313730I0J-1502D01*
G01X1028722Y313676D01*
G03X1029403Y312293I1498J-122D01*
G01X1029409Y312289D01*
X1029423Y312280D01*
X1029459Y312244D01*
G02X1029516Y312126I-142J-141D01*
G01X1029541Y311909D01*
Y311907D01*
X1029542Y311902D01*
X1025235Y307595D01*
G02X1025093Y307536I-142J141D01*
G01X1013486D01*
G02X1013480Y307550I181J86D01*
G01X1013394Y307774D01*
Y307776D01*
X1013352Y307883D01*
G02X1013359Y308029I190J64D01*
G01X1013360Y308032D01*
X1013416Y308081D01*
G03X1013477Y308138I-861J983D01*
G01X1021418Y316079D01*
G02X1021560Y316138I142J-141D01*
G01X1049536D01*
G03X1050460Y316521I0J1306D01*
G01X1068226Y334287D01*
G02X1068368Y334346I142J-141D01*
G01X1100207D01*
G02X1100349Y334287I0J-200D01*
G01X1107312Y327325D01*
X1107337Y327282D01*
X1107344Y327259D01*
G03X1108779Y326203I1435J447D01*
G03X1110281Y327705I0J1502D01*
G03X1109204Y329146I-1503J0D01*
G01X1109178Y329154D01*
X1101755Y336577D01*
G03X1100831Y336960I-924J-923D01*
G01X1067744D01*
G03X1066820Y336577I0J-1306D01*
G01X1049054Y318811D01*
G02X1048912Y318752I-142J141D01*
G01X1020936D01*
G03X1020012Y318369I0J-1306D01*
G01X1012071Y310427D01*
G02X1011929Y310368I-142J141D01*
G01X1011242D01*
X1011210Y310384D01*
G03X1010499Y310564I-713J-1322D01*
G03X1008997Y309062I0J-1502D01*
G01Y309060D01*
G03X1009344Y308100I1503J0D01*
G01X1009359Y308082D01*
X1009380Y308042D01*
G02X1009400Y307954I-180J-87D01*
G01Y307936D01*
G02X1009394Y307887I-200J0D01*
G02X1009382Y307853I-194J49D01*
G01X1009238Y307539D01*
Y307538D01*
X1009237Y307536D01*
X991686D01*
G03X990796Y307359I0J-2326D01*
G01X987227Y305881D01*
G02X987150Y305866I-76J185D01*
G01X961802D01*
Y305836D01*
X954840D01*
G03X953195Y305155I0J-2327D01*
G01X944735Y296695D01*
G02X944593Y296636I-142J141D01*
G01X884240D01*
G03X882595Y295955I0J-2327D01*
G01X880035Y293395D01*
G02X879893Y293336I-142J141D01*
G01X878524D01*
G02X878383Y293394I0J200D01*
G01X878183Y293593D01*
G02X878124Y293733I141J142D01*
G03X875120I-1502J-12D01*
G01Y293693D01*
X875089Y293621D01*
X874861Y293394D01*
G02X874720Y293336I-141J142D01*
G01X873407D01*
G02X873265Y293395I0J200D01*
G01X867705Y298955D01*
G03X866060Y299636I-1645J-1646D01*
G01X775407D01*
G02X775265Y299695I0J200D01*
G01X751205Y323755D01*
G03X749560Y324436I-1645J-1646D01*
G01X465279D01*
G03X464389Y324259I0J-2326D01*
G01X463745Y323993D01*
X463694D01*
X462839Y323639D01*
X462782Y323615D01*
X462662Y323640D01*
X462619Y323684D01*
X462617Y323686D01*
X462537Y323768D01*
X462519Y323895D01*
X462549Y323953D01*
G03X462752Y324783I-1599J831D01*
G01Y328185D01*
G03X459148I-1802J0D01*
G01Y324785D01*
G03X460408Y323066I1803J0D01*
G01X460471Y323046D01*
X460547Y322943D01*
X460548Y322827D01*
Y322825D01*
X460549Y322764D01*
X460482Y322662D01*
X458259Y321741D01*
G02X458182Y321726I-76J185D01*
G01X438487D01*
G02X438329Y321804I0J200D01*
G01X438125Y322068D01*
X438107Y322157D01*
X438119Y322203D01*
G03X438168Y322583I-1453J381D01*
G03X435164I-1502J0D01*
G03X435213Y322203I1502J1D01*
G01X435225Y322157D01*
X435207Y322068D01*
X435003Y321804D01*
G02X434845Y321726I-158J122D01*
G01X431910D01*
G02X431733Y321833I0J200D01*
G01X431617Y322054D01*
G02X431594Y322147I177J93D01*
G01Y322266D01*
G02X431626Y322374I200J0D01*
G01Y322375D01*
G03X431863Y323186I-1266J810D01*
G01Y323187D01*
G03X430361Y324689I-1502J0D01*
G03X428911Y323578I0J-1502D01*
G01Y323577D01*
G02X428801Y323448I-193J53D01*
G01X428570Y323341D01*
G02X428486Y323323I-83J182D01*
G01X428357D01*
X428318Y323340D01*
X428317D01*
G03X427713Y323467I-604J-1375D01*
G03X426270Y322383I0J-1502D01*
G01X426260Y322347D01*
X426237Y322317D01*
G02X426184Y322269I-159J122D01*
G01X425952Y322125D01*
X425950D01*
X425943Y322121D01*
X425872Y322109D01*
X424578Y322365D01*
G02X424436Y322476I39J196D01*
G01X424379Y322596D01*
Y322598D01*
X424290Y322787D01*
X424292Y322880D01*
X424315Y322922D01*
G03X424490Y323626I-1327J704D01*
G01Y323627D01*
G03X421486I-1502J0D01*
G03X421493Y323483I1502J1D01*
G01X421498Y323436D01*
X421464Y323347D01*
X421210Y323118D01*
G02X421037Y323071I-133J149D01*
G01X416724Y323927D01*
G02X416583Y324037I40J196D01*
G01X416435Y324346D01*
X416437Y324439D01*
X416459Y324481D01*
G03X416631Y325171I-1330J698D01*
G01Y325203D01*
G03X416190Y326244I-1502J-22D01*
G03X414118Y326292I-1061J-1064D01*
G01X414101Y326276D01*
X414058Y326252D01*
G02X413957Y326227I-97J175D01*
G01X413737Y326232D01*
G02X413600Y326291I5J200D01*
G01X410204Y329686D01*
G02X410161Y329751I142J141D01*
G01X410088Y329927D01*
G02X410195Y330188I185J77D01*
G01X410198Y330189D01*
X410200D01*
G03X410656Y330469I-545J1400D01*
G01X410683Y330493D01*
X410735Y330513D01*
G02X410808Y330527I73J-186D01*
G01X410888D01*
G02X410947Y330518I0J-200D01*
G01X411209Y330436D01*
X411212D01*
G02X411346Y330290I-61J-191D01*
G01Y330289D01*
G03X412812Y329114I1466J327D01*
G01X412814D01*
G03X412947Y329120I-1J1503D01*
G01X412988Y329125D01*
G03X414314Y330617I-176J1492D01*
G03X413788Y331759I-1503J0D01*
G01X413782Y331764D01*
X413781Y331765D01*
X413768Y331776D01*
G02X413697Y331918I129J153D01*
G01X413682Y332207D01*
X413679Y332258D01*
X413718Y332340D01*
X413742Y332364D01*
G03X414173Y333416I-1071J1053D01*
G01Y333418D01*
G03X411169I-1502J0D01*
G03X411706Y332267I1502J0D01*
G01X411707Y332266D01*
X411747Y332232D01*
X411783Y332158D01*
X411785Y332117D01*
X411801Y331835D01*
Y331813D01*
G02X411743Y331673I-200J1D01*
G01X411735Y331664D01*
G03X411557Y331442I1078J-1046D01*
G01X411551Y331433D01*
X411513Y331385D01*
X411479Y331366D01*
X411461Y331355D01*
G02X411287Y331337I-106J170D01*
G01X411245Y331353D01*
X411182Y331417D01*
X411155Y331496D01*
X411156Y331533D01*
Y331538D01*
G03X411157Y331589I-1501J55D01*
G03X409667Y333091I-1502J0D01*
G01X409652D01*
G03X409154Y333006I0J-1502D01*
G01X409118Y332993D01*
X409042Y332997D01*
X408837Y333088D01*
G02X408735Y333194I83J182D01*
G01X406605Y338334D01*
G03X406169Y339018I-2150J-889D01*
G02X406159Y339030I149J134D01*
G03X405977Y339235I-1801J-1416D01*
G01X402981Y342231D01*
G03X402628Y342520I-1621J-1619D01*
G02X402622Y342524I108J168D01*
G03X401270Y342958I-1353J-1892D01*
G01X397075D01*
G02X396933Y343017I0J200D01*
G01X396528Y343422D01*
G03X394883Y344104I-1646J-1645D01*
G03X392556Y341777I0J-2327D01*
G03X393039Y340358I2326J0D01*
G01X393059Y340333D01*
X393080Y340270D01*
Y339884D01*
X393059Y339821D01*
X393039Y339796D01*
G03X392556Y338377I1843J-1419D01*
G03X394883Y336050I2327J0D01*
G03X396528Y336732I-1J2327D01*
G01X396933Y337137D01*
G02X397075Y337196I142J-141D01*
G01X399761D01*
G02X399903Y337137I0J-200D01*
G01X400022Y337018D01*
G02Y336736I-142J-141D01*
G01X400016Y336730D01*
X400011Y336726D01*
G03X399491Y335589I983J-1137D01*
G03X400781Y334102I1502J0D01*
G01X400876Y334089D01*
G03X400904Y334087I28J198D01*
G01X400996D01*
G03X401631Y334228I0J1502D01*
G01X401648Y334236D01*
X401736Y334259D01*
X401779Y334251D01*
X401798Y334248D01*
X402028Y334161D01*
G02X402142Y334050I-71J-187D01*
G01X405114Y326877D01*
G03X405618Y326122I2150J889D01*
G01X412435Y319305D01*
G03X413626Y318668I1646J1645D01*
G01X426999Y316008D01*
G03X427453Y315964I450J2282D01*
G01X458957D01*
G03X459847Y316141I0J2326D01*
G01X465926Y318659D01*
G02X466003Y318674I76J-185D01*
G01X748053D01*
G02X748195Y318615I0J-200D01*
G01X772255Y294555D01*
G03X773900Y293874I1645J1646D01*
G01X784612D01*
G02X784769Y293798I0J-200D01*
G01X784992Y293514D01*
X785012Y293424D01*
X785001Y293380D01*
G03X784959Y293028I1460J-353D01*
G03X787963I1502J0D01*
G03X787921Y293380I-1502J-1D01*
G01X787910Y293424D01*
X787930Y293514D01*
X788153Y293798D01*
G02X788310Y293874I157J-124D01*
G01X864553D01*
G02X864695Y293815I0J-200D01*
G01X870255Y288255D01*
G03X871900Y287574I1645J1646D01*
G01X881400D01*
G03X883045Y288255I0J2327D01*
G01X883869Y289079D01*
G02X884051Y289133I141J-142D01*
G01X884378Y289066D01*
G02X884523Y288944I-41J-196D01*
G03X885918Y287998I1395J556D01*
G03X887420Y289500I0J1502D01*
G03X887208Y290269I-1501J0D01*
G01X887181Y290316D01*
X887180Y290423D01*
X887378Y290773D01*
G02X887552Y290874I174J-99D01*
G01X946100D01*
G03X947745Y291555I0J2327D01*
G01X947802Y291612D01*
G02X948009Y291660I142J-141D01*
G01X948404Y291523D01*
X948476Y291433D01*
X948482Y291377D01*
G03X949974Y290052I1492J178D01*
G03X951476Y291554I0J1502D01*
G03X950151Y293046I-1503J0D01*
G01X950095Y293052D01*
X950005Y293124D01*
X949868Y293519D01*
G02X949916Y293726I189J65D01*
G01X956205Y300015D01*
G02X956347Y300074I142J-141D01*
G01X987802D01*
G03X988692Y300251I0J2326D01*
G01X992300Y301745D01*
G02X992377Y301760I76J-185D01*
G01X994336D01*
G02X994374Y301756I-2J-200D01*
G02X994476Y301703I-37J-196D01*
G01X994939Y301240D01*
G02X994992Y301138I-143J-139D01*
G02X994996Y301100I-196J-40D01*
G01Y280507D01*
G02X994974Y280416I-200J0D01*
G02X994938Y280366I-178J90D01*
G01X992624Y278052D01*
G02X992557Y278008I-141J142D01*
G01X992523Y277994D01*
X921784D01*
G03X921642Y277935I0J-200D01*
G01X921023Y277316D01*
X920997Y277300D01*
X920964Y277282D01*
X920932Y277276D01*
G03X920508Y277110I218J-1182D01*
G01X920486Y277105D01*
X920397Y277031D01*
G02X920395Y277029I-142J140D01*
G03X920273Y276916I754J-936D01*
G03X920111Y276699I876J-823D01*
G03X920110Y276697I178J-90D01*
G01X920107Y276692D01*
Y276691D01*
G03X920081Y276644I1038J-605D01*
G03X920078Y276641I133J-136D01*
G01X920074Y276632D01*
X920055Y276592D01*
Y276591D01*
G03X920052Y276585I177J-92D01*
G01Y276584D01*
X919962Y276373D01*
X919953Y276352D01*
X919946Y276335D01*
X919945Y276333D01*
X919891Y276205D01*
G02X919848Y276141I-184J77D01*
G01X919821Y276114D01*
X919751Y276083D01*
X919739Y276082D01*
X919709D01*
G03X918227Y274600I20J-1502D01*
G01X918226Y274520D01*
G02X918215Y274508I-153J129D01*
G01X918144Y274437D01*
G03X918085Y274295I141J-142D01*
G01Y271859D01*
X918083Y271846D01*
G03X918071Y271654I1490J-190D01*
G03X918083Y271462I1502J-2D01*
G01X918085Y271449D01*
Y267241D01*
G02X918064Y267152I-200J0D01*
G01X918060Y267144D01*
X918055Y267132D01*
X918052Y267126D01*
G03X917926Y266592I1076J-536D01*
G01Y266445D01*
G03X918062Y265890I1203J1D01*
G01X918075Y265866D01*
X918085Y265824D01*
Y264772D01*
X918083Y264759D01*
G03X918071Y264567I1490J-190D01*
G03X918083Y264375I1502J-2D01*
G01X918085Y264362D01*
Y263343D01*
G02X918083Y263318I-200J3D01*
G01X918076Y263282D01*
G02X918058Y263229I-196J37D01*
G01X918039Y263190D01*
G03X917926Y262682I1089J-509D01*
G01Y261721D01*
G03X918062Y261166I1203J1D01*
G01X918075Y261142D01*
X918085Y261100D01*
Y260048D01*
X918083Y260035D01*
G03X918071Y259843I1490J-190D01*
G03X918083Y259651I1502J-2D01*
G01X918085Y259638D01*
Y258619D01*
G02X918083Y258594I-200J3D01*
G01X918071Y258530D01*
X918068Y258525D01*
Y258524D01*
X918048Y258483D01*
G03X917937Y258113I1080J-526D01*
G03X917926Y257957I1190J-162D01*
G01Y256996D01*
G03X918062Y256441I1203J1D01*
G01X918075Y256417D01*
X918085Y256375D01*
Y255323D01*
X918083Y255310D01*
G03X918071Y255118I1490J-190D01*
G03X918083Y254926I1502J-2D01*
G01X918085Y254913D01*
Y253894D01*
G02X918083Y253869I-200J3D01*
G01X918071Y253805D01*
X918068Y253800D01*
Y253799D01*
X918048Y253758D01*
G03X917937Y253388I1080J-526D01*
G03X917926Y253232I1190J-162D01*
G01Y252272D01*
G03X918062Y251717I1203J1D01*
G01X918075Y251693D01*
X918085Y251651D01*
Y250599D01*
X918083Y250586D01*
G03X918071Y250394I1490J-190D01*
G03X918083Y250202I1502J-2D01*
G01X918085Y250189D01*
Y249170D01*
G02X918083Y249145I-200J3D01*
G01X918071Y249081D01*
X918068Y249076D01*
Y249075D01*
X918048Y249034D01*
G03X917937Y248664I1080J-526D01*
G03X917926Y248508I1190J-162D01*
G01Y247547D01*
G03X918062Y246992I1203J1D01*
G01X918075Y246968D01*
X918085Y246926D01*
Y245874D01*
X918083Y245861D01*
G03X918071Y245669I1490J-190D01*
G03X918083Y245477I1502J-2D01*
G01X918085Y245464D01*
Y241150D01*
X918083Y241137D01*
G03X918071Y240945I1490J-190D01*
G03X918083Y240753I1502J-2D01*
G01X918085Y240740D01*
Y234063D01*
X918083Y234050D01*
G03X918071Y233858I1490J-190D01*
G03X918083Y233666I1502J-2D01*
G01X918085Y233653D01*
Y169423D01*
G02X917969Y169242I-200J1D01*
G01X917804Y169166D01*
X917627Y169085D01*
G02X917446Y169102I-74J186D01*
G01X917426Y169119D01*
G03X916453Y169477I-973J-1143D01*
G03Y166473I0J-1502D01*
G03X917426Y166831I0J1501D01*
G01X917427Y166832D01*
G02X917528Y166877I129J-153D01*
G01X917557Y166881D01*
X917612Y166873D01*
X917788Y166792D01*
X917977Y166704D01*
G02X918085Y166527I-92J-178D01*
G01Y163081D01*
G02X918071Y163007I-200J0D01*
G01X918058Y162975D01*
X917952Y162859D01*
X917920Y162843D01*
X917833Y162798D01*
X917799Y162793D01*
G03Y159819I218J-1487D01*
G01X917833Y159814D01*
X917920Y159769D01*
X917953Y159752D01*
X918037Y159660D01*
G02X918085Y159531I-152J-130D01*
G01Y151308D01*
G02X917885Y151108I-200J0D01*
G01X911378D01*
G02X911333Y151113I-1J200D01*
G01X911298Y151121D01*
G02X911179Y151211I52J193D01*
G01X911067Y151421D01*
Y151423D01*
X911013Y151526D01*
G02X910990Y151630I177J94D01*
G01X910993Y151684D01*
X911024Y151730D01*
X911026Y151733D01*
X911053Y151777D01*
G03X911096Y151852I-1281J784D01*
G03X911134Y151928I-1325J710D01*
G01X911143Y151946D01*
G03X911171Y152012I-1369J620D01*
G01X911178Y152033D01*
X911179Y152037D01*
X911180Y152038D01*
G03X911274Y152560I-1408J523D01*
G03Y152562I-1502J1D01*
G01Y152584D01*
G03X909772Y154064I-1502J-22D01*
G03X908514Y153384I0J-1504D01*
G01X908491Y153348D01*
X908461Y153317D01*
X908441Y153305D01*
X908361Y153255D01*
G02X908267Y153224I-108J168D01*
G01X907990Y153206D01*
G02X907894Y153224I-12J200D01*
G02X907820Y153282I83J182D01*
G01X907808Y153297D01*
X907807Y153298D01*
X907796Y153312D01*
G03X906623Y153875I-1173J-941D01*
G01X906622D01*
G03X905120Y152373I0J-1502D01*
G01Y152372D01*
G03X905284Y151690I1502J0D01*
G01X905285Y151688D01*
G02X905307Y151589I-178J-91D01*
G01X905305Y151541D01*
X905095Y151197D01*
X905082Y151183D01*
G02X904926Y151108I-156J125D01*
G01X895613D01*
G02X895472Y151166I0J200D01*
G01X894351Y152287D01*
X894345Y152292D01*
X894339Y152298D01*
G03X892930Y152878I-1409J-1421D01*
G01X886570D01*
G03X885155Y152292I0J-2001D01*
G01X881818Y148955D01*
G03X881232Y147541I1415J-1415D01*
G01Y147535D01*
G03Y147503I2001J-16D01*
G01Y147487D01*
G03X881233Y147467I1999J90D01*
G01Y147447D01*
G03X881236Y147399I1999J101D01*
G01Y147398D01*
G03X883203Y145538I1997J142D01*
G01X883239D01*
G03X883735Y145602I-6J2002D01*
G03X884030Y145704I-505J1937D01*
G03X884278Y145833I-797J1836D01*
G03X884369Y145892I-1043J1708D01*
G03X884520Y146007I-1136J1648D01*
G03X884649Y146125I-1285J1534D01*
G01X886534Y148010D01*
X887344Y148821D01*
G02X887459Y148875I138J-145D01*
G02X887482Y148876I20J-199D01*
G01X889960D01*
G02X890108Y148810I0J-200D01*
G01X890307Y148589D01*
G02X890349Y148515I-149J-133D01*
G01X890362Y148473D01*
X890359Y148439D01*
G03X890351Y148340I1492J-170D01*
G01Y148338D01*
G03X890350Y148299I1501J-58D01*
G01Y148268D01*
G03X891852Y146775I1502J9D01*
G03X893033Y147349I0J1502D01*
G01X893040Y147358D01*
X893059Y147377D01*
G02X893169Y147433I141J-142D01*
G01X893248Y147446D01*
G02X893266Y147447I20J-199D01*
G01X893519D01*
G02X893534Y147446I-6J-200D01*
G02X893597Y147431I-14J-200D01*
G01X893619Y147421D01*
X893634Y147412D01*
X893636Y147411D01*
G03X893876Y147282I1066J1695D01*
G03X894050Y147213I824J1824D01*
G01X894057Y147211D01*
X894075Y147203D01*
X894095Y147197D01*
X894124Y147188D01*
G03X894740Y147104I575J1917D01*
G01X917885D01*
G02X918085Y146904I0J-200D01*
G01Y120719D01*
G02X918084Y120696I-200J-3D01*
G01X918079Y120668D01*
G02X918064Y120617I-198J30D01*
G01X918053Y120593D01*
X918034Y120571D01*
G03X917673Y119594I1142J-977D01*
G03X918046Y118604I1500J0D01*
G02X918084Y118503I-161J-118D01*
G02X918085Y118485I-199J-20D01*
G01Y117719D01*
G02X918084Y117696I-200J-3D01*
G01X918079Y117668D01*
G02X918064Y117617I-198J30D01*
G01X918053Y117593D01*
X918034Y117571D01*
G03X917673Y116594I1142J-977D01*
G03X918046Y115604I1500J0D01*
G02X918084Y115503I-161J-118D01*
G02X918085Y115485I-199J-20D01*
G01Y114519D01*
G02X918084Y114496I-200J-3D01*
G01X918079Y114468D01*
G02X918064Y114417I-198J30D01*
G01X918053Y114393D01*
X918034Y114371D01*
G03X917673Y113394I1142J-977D01*
G03X918046Y112404I1500J0D01*
G02X918084Y112303I-161J-118D01*
G02X918085Y112285I-199J-20D01*
G01Y52324D01*
G02X918071Y52249I-200J-1D01*
G01X918056Y52213D01*
X914604Y48761D01*
G02X914537Y48717I-141J142D01*
G01X914503Y48703D01*
X880773D01*
G02X880698Y48717I-1J200D01*
G01X880662Y48732D01*
X873208Y56186D01*
G02X873164Y56253I142J141D01*
G01X873150Y56287D01*
Y92898D01*
G02X873165Y92974I200J0D01*
G01X873172Y92990D01*
X873197Y93041D01*
X873209Y93064D01*
X873257Y93125D01*
X873272Y93138D01*
G03X873282Y95411I-980J1141D01*
G01X873276Y95417D01*
X873252Y95441D01*
G02X873240Y95455I146J137D01*
G01X873209Y95494D01*
X873197Y95517D01*
X873170Y95574D01*
G02X873150Y95660I180J87D01*
G01Y168198D01*
X873158Y168249D01*
X873161Y168260D01*
G03X873207Y168505I-1449J399D01*
G03X873202Y168864I-1494J159D01*
G03X873194Y168916I-1488J-202D01*
G03X873158Y169076I-1481J-249D01*
G01X873150Y169103D01*
Y172198D01*
X873158Y172249D01*
X873161Y172260D01*
G03X873207Y172505I-1449J399D01*
G03X873202Y172864I-1494J159D01*
G03X873194Y172916I-1488J-202D01*
G03X873158Y173076I-1481J-249D01*
G01X873150Y173103D01*
Y176198D01*
X873158Y176249D01*
X873161Y176260D01*
G03X873207Y176505I-1449J399D01*
G03X873202Y176864I-1494J159D01*
G03X873194Y176916I-1488J-202D01*
G03X873158Y177076I-1481J-249D01*
G01X873150Y177103D01*
Y180198D01*
X873158Y180249D01*
X873161Y180260D01*
G03X873207Y180505I-1449J399D01*
G03X873202Y180864I-1494J159D01*
G03X873194Y180916I-1488J-202D01*
G03X873158Y181076I-1481J-249D01*
G01X873150Y181103D01*
Y186014D01*
G02X873160Y186075I200J-1D01*
G01X873169Y186102D01*
X873187Y186140D01*
G03X873328Y186757I-1361J636D01*
G01Y186773D01*
G03X873172Y187446I-1502J6D01*
G03X873171Y187448I-1344J-671D01*
G01X873160Y187471D01*
X873150Y187513D01*
Y192198D01*
X873158Y192249D01*
X873161Y192260D01*
G03X873207Y192505I-1449J399D01*
G03X873202Y192864I-1494J159D01*
G03X873194Y192916I-1488J-202D01*
G03X873158Y193076I-1481J-249D01*
G01X873150Y193103D01*
Y196198D01*
X873158Y196249D01*
X873161Y196260D01*
G03X873207Y196505I-1449J399D01*
G03X873202Y196864I-1494J159D01*
G03X873194Y196916I-1488J-202D01*
G03X873158Y197076I-1481J-249D01*
G01X873150Y197103D01*
Y200332D01*
X873161Y200364D01*
G03X873247Y200863I-1416J501D01*
G01Y200865D01*
G03X873161Y201364I-1502J-2D01*
G01X873150Y201396D01*
Y204332D01*
X873161Y204364D01*
G03X873247Y204863I-1416J501D01*
G01Y204865D01*
G03X873161Y205364I-1502J-2D01*
G01X873150Y205396D01*
Y208332D01*
X873161Y208364D01*
G03X873247Y208863I-1416J501D01*
G01Y208865D01*
G03X873161Y209364I-1502J-2D01*
G01X873150Y209396D01*
Y212332D01*
X873161Y212364D01*
G03X873247Y212863I-1416J501D01*
G01Y212865D01*
G03X873161Y213364I-1502J-2D01*
G01X873150Y213396D01*
Y216332D01*
X873161Y216364D01*
G03X873247Y216863I-1416J501D01*
G01Y216865D01*
G03X873161Y217364I-1502J-2D01*
G01X873150Y217396D01*
Y221332D01*
X873161Y221364D01*
G03X873247Y221863I-1416J501D01*
G01Y221865D01*
G03X873161Y222364I-1502J-2D01*
G01X873150Y222396D01*
Y275831D01*
G03X873091Y275973I-200J0D01*
G01X867206Y281858D01*
G03X867064Y281917I-142J-141D01*
G01X855570D01*
X855557D01*
G02X855394Y282022I13J200D01*
G03X855335Y282122I-1322J-713D01*
G03X855283Y282197I-1260J-818D01*
G03X852747Y282013I-1210J-890D01*
G02X852585Y281917I-171J104D01*
G01X848960D01*
G02X848889Y281930I0J200D01*
G01X848855Y281943D01*
X848766Y282026D01*
X848739Y282050D01*
X848693Y282138D01*
X848688Y282156D01*
X848674Y282200D01*
X848671Y282215D01*
X848670Y282219D01*
X848669Y282227D01*
Y282229D01*
G03X848434Y282820I-1482J-247D01*
G03X845705Y282227I-1247J-838D01*
G01Y282225D01*
X845704Y282222D01*
X845700Y282200D01*
X845686Y282156D01*
X845681Y282138D01*
X845635Y282050D01*
X845608Y282026D01*
X845548Y281970D01*
G02X845483Y281929I-137J146D01*
G01X845451Y281917D01*
X842971D01*
G02X842849Y281959I1J200D01*
G01X842758Y282031D01*
G02X842717Y282076I126J156D01*
G01X842701Y282099D01*
X842691Y282132D01*
G03X842058Y282980I-1444J-418D01*
G03X839778Y282042I-813J-1264D01*
G01X839769Y282003D01*
X839714Y281960D01*
G02X839591Y281917I-124J157D01*
G01X753208D01*
X753195D01*
G02X753032Y282022I13J200D01*
G03X752973Y282122I-1322J-713D01*
G03X752921Y282197I-1260J-818D01*
G03X750385Y282013I-1210J-890D01*
G02X750223Y281917I-171J104D01*
G01X746598D01*
G02X746527Y281930I0J200D01*
G01X746493Y281943D01*
X746404Y282026D01*
X746377Y282050D01*
X746331Y282138D01*
X746326Y282156D01*
X746312Y282200D01*
X746309Y282215D01*
X746308Y282219D01*
X746307Y282227D01*
Y282229D01*
G03X746072Y282820I-1482J-247D01*
G03X743343Y282227I-1247J-838D01*
G01Y282225D01*
X743342Y282222D01*
X743338Y282200D01*
X743324Y282156D01*
X743319Y282138D01*
X743273Y282050D01*
X743246Y282026D01*
X743186Y281970D01*
G02X743121Y281929I-137J146D01*
G01X743089Y281917D01*
X740609D01*
G02X740487Y281959I1J200D01*
G01X740396Y282031D01*
G02X740355Y282076I125J155D01*
G01X740339Y282099D01*
X740329Y282132D01*
G03X739696Y282980I-1444J-418D01*
G03X737416Y282042I-813J-1264D01*
G01X737407Y282003D01*
X737352Y281960D01*
G02X737229Y281917I-124J157D01*
G01X650846D01*
X650833D01*
G02X650670Y282022I13J200D01*
G03X650611Y282122I-1322J-713D01*
G03X650559Y282197I-1260J-818D01*
G03X648023Y282013I-1210J-890D01*
G02X647861Y281917I-171J104D01*
G01X644236D01*
G02X644165Y281930I0J200D01*
G01X644131Y281943D01*
X644042Y282026D01*
X644015Y282050D01*
X643954Y282169D01*
X643949Y282202D01*
G03X640977I-1486J-220D01*
G01X640972Y282169D01*
X640911Y282050D01*
X640884Y282026D01*
X640824Y281970D01*
G02X640759Y281929I-137J146D01*
G01X640727Y281917D01*
X638247D01*
G02X638125Y281959I1J200D01*
G01X638034Y282031D01*
G02X637993Y282076I125J155D01*
G01X637977Y282099D01*
X637967Y282132D01*
G03X637334Y282980I-1444J-418D01*
G03X635054Y282042I-813J-1264D01*
G01X635045Y282003D01*
X634990Y281960D01*
G02X634867Y281917I-124J157D01*
G01X548484D01*
X548471D01*
G02X548308Y282022I13J200D01*
G03X548249Y282122I-1322J-713D01*
G03X548197Y282197I-1260J-818D01*
G03X545661Y282013I-1210J-890D01*
G02X545499Y281917I-171J104D01*
G01X541874D01*
G02X541803Y281930I0J200D01*
G01X541769Y281943D01*
X541680Y282026D01*
X541653Y282050D01*
X541592Y282169D01*
X541587Y282202D01*
G03X538615I-1486J-220D01*
G01X538610Y282169D01*
X538549Y282050D01*
X538522Y282026D01*
X538462Y281970D01*
G02X538397Y281929I-137J146D01*
G01X538365Y281917D01*
X535885D01*
G02X535763Y281959I1J200D01*
G01X535672Y282031D01*
G02X535631Y282076I126J156D01*
G01X535615Y282099D01*
X535605Y282132D01*
G03X534972Y282980I-1444J-418D01*
G03X532692Y282042I-813J-1264D01*
G01X532683Y282003D01*
X532628Y281960D01*
G02X532505Y281917I-124J157D01*
G01X484127D01*
G02X484036Y281939I0J200D01*
G02X483986Y281975I90J178D01*
G01X483971Y281990D01*
X483774Y282231D01*
G02X483731Y282354I157J124D01*
G01Y282385D01*
G03X483861Y283151I-20342J3846D01*
G03X483868Y283199I-20481J3011D01*
G03X484090Y286275I-20481J3024D01*
G01Y286297D01*
G03X484089Y286438I-20703J-76D01*
G01Y286445D01*
G03X477722Y301158I-20701J-224D01*
G01Y301159D01*
G03X477033Y301790I-14323J-14948D01*
G01X477025Y301797D01*
X477016Y301805D01*
X477015Y301806D01*
X477004Y301815D01*
G03X476978Y301838I-13730J-15494D01*
G01X476940Y301923D01*
X476942Y301962D01*
X476959Y302249D01*
G02X476977Y302310I198J-25D01*
G01X477049Y302442D01*
X477080Y302463D01*
X477081Y302464D01*
X477093Y302473D01*
G03X477641Y303584I-853J1112D01*
G03X476239Y304986I-1402J0D01*
G03X474906Y304022I0J-1404D01*
G01X474898Y303997D01*
X474884Y303975D01*
G02X474854Y303938I-170J107D01*
G01X474815Y303902D01*
G02X474754Y303862I-138J144D01*
G01X474723Y303849D01*
X474685Y303847D01*
G03X474624Y303835I8J-200D01*
G01X474569Y303815D01*
G02X474504Y303804I-65J189D01*
G01X474375D01*
G02X474286Y303825I0J200D01*
G01X474268Y303834D01*
X474260Y303839D01*
G03X471943Y305073I-10871J-17619D01*
G03X468702Y306230I-8557J-18852D01*
G03X463387Y306924I-5315J-20009D01*
G03X447222Y299156I0J-20703D01*
G01X447213Y299144D01*
X447212Y299143D01*
X447211Y299141D01*
X447198Y299125D01*
G03X447150Y299065I16142J-12963D01*
G03X446925Y298775I16244J-12835D01*
G03X446906Y298750I16473J-12539D01*
G03X446779Y298581I16487J-12522D01*
G03X444711Y295155I16607J-12361D01*
G03X442684Y286221I18676J-8934D01*
G03X460398Y265735I20703J0D01*
G01X460426Y265731D01*
X460484Y265705D01*
G02X460597Y265525I-87J-180D01*
G01Y162923D01*
G02X460586Y162858I-200J0D01*
G02X460480Y162741I-189J65D01*
G01X460462Y162733D01*
X460456Y162731D01*
G03X459823Y162321I474J-1425D01*
G03X460459Y159880I1106J-1015D01*
G01X460460D01*
X460471Y159876D01*
G02X460558Y159809I-74J-186D01*
G02X460597Y159690I-161J-119D01*
G01Y151308D01*
G02X460397Y151108I-200J0D01*
G01X454292D01*
G02X454247Y151113I-1J200D01*
G01X454212Y151121D01*
G02X454093Y151211I52J193D01*
G01X453981Y151421D01*
Y151423D01*
X453927Y151526D01*
G02X453904Y151630I177J94D01*
G01X453907Y151684D01*
X453938Y151730D01*
X453940Y151733D01*
X453967Y151777D01*
G03X454010Y151852I-1281J784D01*
G03X454169Y152324I-1325J709D01*
G03X454188Y152560I-1483J238D01*
G01Y152562D01*
G03X452686Y154064I-1502J0D01*
G03X451416Y153365I0J-1503D01*
G01X451409Y153353D01*
G02X451352Y153301I-161J119D01*
G01X451272Y153252D01*
G02X451241Y153238I-97J174D01*
G03X451237Y153236I87J-179D01*
G02X451181Y153224I-69J188D01*
G01X450904Y153206D01*
G02X450808Y153224I-12J200D01*
G02X450734Y153282I83J182D01*
G01X450722Y153297D01*
X450721Y153298D01*
X450710Y153312D01*
G03X449537Y153875I-1173J-941D01*
G01X449536D01*
G03X448034Y152373I0J-1502D01*
G01Y152372D01*
G03X448198Y151690I1502J0D01*
G01X448199Y151688D01*
G02X448221Y151589I-178J-91D01*
G01X448219Y151541D01*
X448009Y151197D01*
X447996Y151183D01*
G02X447840Y151108I-156J125D01*
G01X438527D01*
G02X438386Y151166I0J200D01*
G01X437265Y152287D01*
X437259Y152292D01*
X437253Y152298D01*
G03X435844Y152878I-1409J-1421D01*
G01X429484D01*
G03X428069Y152292I0J-2001D01*
G01X424732Y148955D01*
G03X424146Y147541I1415J-1415D01*
G01Y147535D01*
G03Y147503I2001J-16D01*
G01Y147487D01*
G03X424147Y147467I1999J90D01*
G01Y147447D01*
G03X424150Y147399I1999J101D01*
G01Y147398D01*
G03X426117Y145538I1997J142D01*
G01X426153D01*
G03X426649Y145602I-6J2002D01*
G03X426944Y145704I-505J1937D01*
G03X427192Y145833I-797J1836D01*
G03X427235Y145860I-1043J1708D01*
G01X427252Y145871D01*
G03X427434Y146007I-1105J1669D01*
G03X427563Y146125I-1285J1534D01*
G01X429448Y148010D01*
X430258Y148821D01*
G02X430373Y148875I138J-145D01*
G02X430396Y148876I20J-199D01*
G01X432853D01*
G02X432902Y148870I0J-200D01*
G01X432926Y148864D01*
G02X433021Y148811I-46J-194D01*
G01X433157Y148660D01*
X433221Y148589D01*
G02X433263Y148515I-149J-133D01*
G01X433276Y148473D01*
X433273Y148439D01*
G03X433265Y148340I1492J-170D01*
G01Y148338D01*
G03X433264Y148299I1501J-58D01*
G01Y148268D01*
G03X434766Y146775I1502J9D01*
G03X435947Y147349I0J1502D01*
G01X435954Y147358D01*
X435973Y147377D01*
G02X436083Y147433I141J-142D01*
G01X436162Y147446D01*
G02X436180Y147447I20J-199D01*
G01X436411D01*
G02X436437Y147445I-2J-200D01*
G01X436522Y147429D01*
X436554Y147409D01*
G03X436610Y147375I1067J1694D01*
G03X436725Y147313I1007J1730D01*
G03X436906Y147234I890J1793D01*
G03X436980Y147208I700J1875D01*
G03X436984Y147205I120J156D01*
G01X437001Y147200D01*
X437005Y147199D01*
X437011Y147197D01*
G03X437654Y147104I604J1908D01*
G01X460397D01*
G02X460597Y146904I0J-200D01*
G01Y119767D01*
X460596Y119757D01*
G03X460587Y119595I1493J-164D01*
G01Y119593D01*
G03X460596Y119431I1502J2D01*
G01X460597Y119421D01*
Y116767D01*
X460596Y116757D01*
G03X460587Y116595I1493J-164D01*
G01Y116593D01*
G03X460596Y116431I1502J2D01*
G01X460597Y116421D01*
Y113567D01*
X460596Y113557D01*
G03X460587Y113395I1493J-164D01*
G01Y113393D01*
G03X460596Y113231I1502J2D01*
G01X460597Y113221D01*
Y103114D01*
G02X460583Y103039I-200J-1D01*
G01X460568Y103003D01*
X452721Y95156D01*
G02X452654Y95112I-141J142D01*
G01X452620Y95098D01*
X419916D01*
G02X419841Y95112I-1J200D01*
G01X419805Y95127D01*
X415472Y99460D01*
G02X415428Y99527I142J141D01*
G01X415414Y99561D01*
Y167267D01*
X415426Y167314D01*
X415437Y167336D01*
X415484Y167428D01*
X415517Y167454D01*
X415518Y167455D01*
X415532Y167466D01*
X415534Y167467D01*
G03X416129Y168665I-909J1198D01*
G03X415668Y169748I-1503J0D01*
G03X415529Y169866I-1041J-1085D01*
G01X415528D01*
X415526Y169868D01*
X415508Y169882D01*
X415493Y169900D01*
X415477Y169919D01*
X415437Y169996D01*
G02X415414Y170088I177J93D01*
G01Y171267D01*
X415426Y171314D01*
X415437Y171336D01*
X415484Y171428D01*
X415517Y171454D01*
X415518Y171455D01*
X415532Y171466D01*
X415534Y171467D01*
G03X416129Y172665I-909J1198D01*
G03X415668Y173748I-1503J0D01*
G03X415529Y173866I-1041J-1085D01*
G01X415528D01*
X415526Y173868D01*
X415508Y173882D01*
X415493Y173900D01*
X415477Y173919D01*
X415437Y173996D01*
G02X415414Y174088I177J93D01*
G01Y175267D01*
X415426Y175314D01*
X415437Y175336D01*
X415484Y175428D01*
X415517Y175454D01*
X415518Y175455D01*
X415532Y175466D01*
X415534Y175467D01*
G03X416129Y176665I-909J1198D01*
G03X415668Y177748I-1503J0D01*
G03X415529Y177866I-1041J-1085D01*
G01X415528D01*
X415526Y177868D01*
X415508Y177882D01*
X415493Y177900D01*
X415477Y177919D01*
X415437Y177996D01*
G02X415414Y178088I177J93D01*
G01Y179267D01*
X415426Y179314D01*
X415437Y179336D01*
X415484Y179428D01*
X415517Y179454D01*
X415518Y179455D01*
X415532Y179466D01*
X415534Y179467D01*
G03X416129Y180665I-909J1198D01*
G03X415668Y181748I-1503J0D01*
G03X415529Y181866I-1041J-1085D01*
G01X415528D01*
X415526Y181868D01*
X415508Y181882D01*
X415493Y181900D01*
X415477Y181919D01*
X415437Y181996D01*
G02X415414Y182088I177J93D01*
G01Y185256D01*
G02X415416Y185284I200J0D01*
G01X415420Y185305D01*
G02X415443Y185367I196J-38D01*
G01X415498Y185465D01*
X415515Y185483D01*
X415531Y185500D01*
X415552Y185514D01*
X415553Y185515D01*
G03X415554Y188041I-815J1263D01*
G01X415532Y188055D01*
X415497Y188093D01*
X415479Y188126D01*
X415440Y188196D01*
G02X415420Y188243I172J101D01*
G01X415414Y188267D01*
Y191267D01*
X415426Y191314D01*
X415437Y191336D01*
X415484Y191428D01*
X415517Y191454D01*
X415518Y191455D01*
X415532Y191466D01*
X415534Y191467D01*
G03X416129Y192665I-909J1198D01*
G03X415668Y193748I-1503J0D01*
G03X415529Y193866I-1041J-1085D01*
G01X415528D01*
X415526Y193868D01*
X415508Y193882D01*
X415493Y193900D01*
X415477Y193919D01*
X415437Y193996D01*
G02X415414Y194088I177J93D01*
G01Y195267D01*
X415426Y195314D01*
X415437Y195336D01*
X415484Y195428D01*
X415517Y195454D01*
X415518Y195455D01*
X415532Y195466D01*
X415534Y195467D01*
G03X416129Y196665I-909J1198D01*
G03X415668Y197748I-1503J0D01*
G03X415529Y197866I-1041J-1085D01*
G01X415528D01*
X415526Y197868D01*
X415508Y197882D01*
X415493Y197900D01*
X415477Y197919D01*
X415437Y197996D01*
G02X415414Y198088I177J93D01*
G01Y199409D01*
G02X415441Y199509I200J0D01*
G01X415494Y199602D01*
X415521Y199632D01*
X415539Y199645D01*
G03X415537Y202084I-881J1219D01*
G01X415518Y202098D01*
X415504Y202114D01*
G02X415478Y202151I150J133D01*
G01X415438Y202227D01*
G02X415418Y202284I176J94D01*
G02X415414Y202320I196J40D01*
G01Y203409D01*
G02X415441Y203509I200J0D01*
G01X415494Y203602D01*
X415521Y203632D01*
X415539Y203645D01*
G03X415537Y206084I-881J1219D01*
G01X415518Y206098D01*
X415504Y206114D01*
G02X415478Y206151I150J133D01*
G01X415438Y206227D01*
G02X415418Y206284I176J94D01*
G02X415414Y206320I196J40D01*
G01Y207409D01*
G02X415441Y207509I200J0D01*
G01X415494Y207602D01*
X415521Y207632D01*
X415539Y207645D01*
G03X415537Y210084I-881J1219D01*
G01X415518Y210098D01*
X415504Y210114D01*
G02X415478Y210151I150J133D01*
G01X415438Y210227D01*
G02X415418Y210284I176J94D01*
G02X415414Y210320I196J40D01*
G01Y211409D01*
G02X415441Y211509I200J0D01*
G01X415494Y211602D01*
X415521Y211632D01*
X415539Y211645D01*
G03X415537Y214084I-881J1219D01*
G01X415518Y214098D01*
X415504Y214114D01*
G02X415478Y214151I150J133D01*
G01X415438Y214227D01*
G02X415418Y214284I176J94D01*
G02X415414Y214320I196J40D01*
G01Y215409D01*
G02X415441Y215509I200J0D01*
G01X415494Y215602D01*
X415521Y215632D01*
X415539Y215645D01*
G03X415537Y218084I-881J1219D01*
G01X415518Y218098D01*
X415504Y218114D01*
G02X415478Y218151I150J133D01*
G01X415438Y218227D01*
G02X415418Y218284I176J94D01*
G02X415414Y218320I196J40D01*
G01Y220409D01*
G02X415441Y220509I200J0D01*
G01X415494Y220602D01*
X415521Y220632D01*
X415539Y220645D01*
G03X415537Y223084I-881J1219D01*
G01X415518Y223098D01*
X415504Y223114D01*
G02X415478Y223151I150J133D01*
G01X415438Y223227D01*
G02X415418Y223284I176J94D01*
G02X415414Y223320I196J40D01*
G01Y278449D01*
G03X415355Y278591I-200J0D01*
G01X412088Y281858D01*
G03X411946Y281917I-142J-141D01*
G01X398483D01*
X398470D01*
G02X398307Y282022I13J200D01*
G03X398248Y282122I-1322J-713D01*
G03X398196Y282197I-1260J-818D01*
G03X396986Y282809I-1210J-890D01*
G03X395660Y282013I0J-1502D01*
G02X395498Y281917I-171J104D01*
G01X391873D01*
G02X391802Y281930I0J200D01*
G01X391768Y281943D01*
X391679Y282026D01*
X391652Y282050D01*
X391591Y282169D01*
X391586Y282202D01*
G03X388614I-1486J-220D01*
G01X388609Y282169D01*
X388548Y282050D01*
X388521Y282026D01*
X388461Y281970D01*
G02X388396Y281929I-137J146D01*
G01X388364Y281917D01*
X385814D01*
G02X385691Y281960I1J200D01*
G01X385636Y282003D01*
X385627Y282042D01*
G03X382691I-1468J-326D01*
G01X382682Y282003D01*
X382627Y281960D01*
G02X382504Y281917I-124J157D01*
G01X296121D01*
X296108D01*
G02X295945Y282022I13J200D01*
G03X295886Y282122I-1322J-713D01*
G03X295834Y282197I-1260J-818D01*
G03X294624Y282809I-1210J-890D01*
G03X293298Y282013I0J-1502D01*
G02X293136Y281917I-171J104D01*
G01X289511D01*
G02X289440Y281930I0J200D01*
G01X289406Y281943D01*
X289317Y282026D01*
X289290Y282050D01*
X289229Y282169D01*
X289224Y282202D01*
G03X286252I-1486J-220D01*
G01X286247Y282169D01*
X286186Y282050D01*
X286159Y282026D01*
X286099Y281970D01*
G02X286034Y281929I-137J146D01*
G01X286002Y281917D01*
X283452D01*
G02X283329Y281960I1J200D01*
G01X283274Y282003D01*
X283265Y282042D01*
G03X280329I-1468J-326D01*
G01X280320Y282003D01*
X280265Y281960D01*
G02X280142Y281917I-124J157D01*
G01X193804D01*
G02X193714Y281939I1J200D01*
G01X193638Y281983D01*
G02X193596Y282015I99J174D01*
G01X193580Y282031D01*
X193566Y282055D01*
G03X192424Y282801I-1303J-748D01*
G01X192421D01*
X192406Y282803D01*
G03X192309Y282809I-141J-1496D01*
G01X192273D01*
G03X192262I-6J-1502D01*
G01X192261D01*
G03X191799Y282736I1J-1502D01*
G03X190936Y282013I463J-1429D01*
G02X190774Y281917I-171J104D01*
G01X187149D01*
G02X187078Y281930I0J200D01*
G01X187044Y281943D01*
X186955Y282026D01*
X186928Y282050D01*
X186867Y282169D01*
X186862Y282202D01*
G03X183890I-1486J-220D01*
G01X183885Y282169D01*
X183824Y282050D01*
X183797Y282026D01*
X183737Y281970D01*
G02X183672Y281929I-137J146D01*
G01X183640Y281917D01*
X181090D01*
G02X180967Y281960I1J200D01*
G01X180912Y282003D01*
X180903Y282042D01*
G03X177967I-1468J-326D01*
G01X177958Y282003D01*
X177903Y281960D01*
G02X177780Y281917I-124J157D01*
G01X91442D01*
G02X91352Y281939I1J200D01*
G01X91276Y281983D01*
G02X91234Y282015I99J174D01*
G01X91218Y282031D01*
X91204Y282055D01*
G03X90062Y282801I-1303J-748D01*
G01X90059D01*
X90044Y282803D01*
G03X89947Y282809I-141J-1496D01*
G01X89911D01*
G03X89900I-6J-1502D01*
G01X89899D01*
G03X89437Y282736I1J-1502D01*
G03X88574Y282013I463J-1429D01*
G02X88412Y281917I-171J104D01*
G01X84787D01*
G02X84716Y281930I0J200D01*
G01X84682Y281943D01*
X84593Y282026D01*
X84566Y282050D01*
X84505Y282169D01*
X84500Y282202D01*
G03X81528I-1486J-220D01*
G01X81523Y282169D01*
X81462Y282050D01*
X81435Y282026D01*
X81375Y281970D01*
G02X81310Y281929I-137J146D01*
G01X81278Y281917D01*
X78728D01*
G02X78605Y281960I1J200D01*
G01X78550Y282003D01*
X78541Y282042D01*
G03X75605I-1468J-326D01*
G01X75596Y282003D01*
X75541Y281960D01*
G02X75418Y281917I-124J157D01*
G01X59387D01*
G02X59312Y281931I-1J200D01*
G01X59276Y281946D01*
X47059Y294163D01*
G03X46917Y294222I-142J-141D01*
G01X28255D01*
G02X28241Y294223I7J199D01*
G01X28230D01*
G02X28079Y294317I19J199D01*
G01X27926Y294589D01*
Y294591D01*
X27907Y294623D01*
G02X27886Y294740I178J92D01*
G01Y294741D01*
X27888Y294759D01*
X27908Y294831D01*
X27922Y294854D01*
G03X28131Y295618I-1292J764D01*
G01Y295619D01*
G03X25127I-1502J0D01*
G01Y295618D01*
G03X25335Y294856I1502J1D01*
G01X25341Y294846D01*
X25349Y294832D01*
X25364Y294778D01*
X25369Y294757D01*
G02X25372Y294744I-193J-51D01*
G01Y294741D01*
G02X25351Y294623I-199J-26D01*
G01X25332Y294591D01*
Y294589D01*
X25183Y294322D01*
G02X25026Y294223I-173J100D01*
G02X25010Y294222I-20J199D01*
G01X3590D01*
G02X3515Y294236I-1J200D01*
G01X3479Y294251D01*
X2667Y295063D01*
G02X2623Y295130I142J141D01*
G01X2609Y295164D01*
Y325590D01*
G02X2612Y325623I200J-2D01*
G02X2666Y325730I197J-32D01*
G01X17350Y340414D01*
G03X17409Y340556I-141J142D01*
G01Y953148D01*
G03X17350Y953290I-200J0D01*
G01X4054Y966586D01*
G02X4010Y966653I142J141D01*
G01X3996Y966687D01*
Y968649D01*
G03X3937Y968791I-200J0D01*
G01X2488Y970240D01*
G02X2444Y970307I142J141D01*
G01X2430Y970341D01*
Y990232D01*
G02X2433Y990265I200J-2D01*
G02X2487Y990372I197J-32D01*
G01X5573Y993458D01*
G02X5680Y993512I139J-143D01*
G02X5713Y993515I35J-197D01*
G01X35207D01*
G03X35285Y993531I0J200D01*
G01X35286D01*
X35350Y993558D01*
X35387Y993574D01*
X209605D01*
G02X209991Y993278I0J-400D01*
G02X209987Y993162I-193J-51D01*
G01X97157Y659810D01*
G02X97106Y659782I-121J160D01*
G01X96965Y659728D01*
X96960Y659726D01*
X96922Y659712D01*
G02X96854Y659700I-68J188D01*
G01X96733D01*
X96707Y659703D01*
G02X96641Y659724I27J198D01*
G01X96630Y659730D01*
X96589Y659750D01*
X96559Y659764D01*
G03X95917Y659906I-644J-1390D01*
G03X94693Y659294I0J-1531D01*
G01X94685Y659283D01*
X94662Y659260D01*
G02X94532Y659202I-141J142D01*
G01X94402Y659201D01*
X94400D01*
X94245Y659200D01*
G02X94086Y659277I-1J200D01*
G01X94085Y659278D01*
X94078Y659287D01*
G03X92897Y659861I-1181J-928D01*
G03Y656857I0J-1502D01*
G01X92898D01*
G03X94067Y657416I0J1502D01*
G01Y657417D01*
X94094Y657449D01*
X94211Y657509D01*
G02X94300Y657531I91J-178D01*
G01X94412Y657532D01*
X94414D01*
X94531Y657533D01*
G02X94576Y657528I1J-200D01*
G02X94692Y657454I-43J-195D01*
G01X94694Y657452D01*
X94702Y657441D01*
G03X94872Y657254I1215J933D01*
G01X94875Y657252D01*
X94897Y657230D01*
G02X94950Y657109I-146J-136D01*
G01X94955Y656890D01*
Y656888D01*
X94956Y656857D01*
X94957Y656816D01*
X94942Y656777D01*
G02X94902Y656713I-187J72D01*
G01X94899Y656710D01*
X94897Y656708D01*
G03X94869Y656679I1066J-1058D01*
G03X94867Y656677I140J-142D01*
G03X94471Y655661I1106J-1016D01*
G01Y655660D01*
G03X94937Y654572I1503J0D01*
G03X95163Y654394I1039J1087D01*
G01X95191Y654376D01*
X95223Y654344D01*
G02X95275Y654253I-142J-141D01*
G01X91083Y641867D01*
G03X90951Y641374I3719J-1260D01*
G01X88728Y630198D01*
G03X88657Y629625I3851J-768D01*
G01X88007Y616373D01*
G02X88004Y616349I-200J13D01*
G01X86989Y610535D01*
G03X86932Y609941I3834J-668D01*
G01X86884Y607440D01*
X86878Y607141D01*
Y607139D01*
X86876Y607010D01*
G02X86851Y606918I-200J5D01*
G01X86840Y606898D01*
X86806Y606861D01*
X86784Y606847D01*
G03X86016Y605443I899J-1404D01*
G01Y605442D01*
G03X86694Y604100I1669J1D01*
G01X86695Y604099D01*
X86732Y604071D01*
X86745Y604047D01*
X86769Y604019D01*
X86818Y603923D01*
X86815Y603870D01*
Y603858D01*
X86683Y596969D01*
X86442Y584506D01*
Y584500D01*
X86381Y583263D01*
G02X86342Y583155I-200J11D01*
G01X86320Y583124D01*
X86319Y583123D01*
G02X86234Y583056I-162J118D01*
G01X86232Y583055D01*
X86199Y583042D01*
G03X85296Y581835I589J-1382D01*
G01X85290Y581779D01*
G03X85285Y581659I1498J-123D01*
G01Y581579D01*
X85290Y581532D01*
G03X86139Y580304I1497J127D01*
G02X86143Y580302I-87J-180D01*
G01X86169Y580289D01*
X86230Y580186D01*
X85899Y573435D01*
G02X85884Y573368I-200J10D01*
G01X80093Y559387D01*
G02X79927Y559265I-184J77D01*
G01X79520Y559226D01*
X79419Y559274D01*
X79389Y559321D01*
G03X79229Y559524I-1255J-825D01*
G01X79209Y559545D01*
X79184Y559595D01*
X79175Y559643D01*
Y559932D01*
G02X79186Y559998I200J1D01*
G01X79205Y560044D01*
X79230Y560071D01*
G03X79229Y562124I-1097J1026D01*
G01X79209Y562145D01*
X79184Y562195D01*
X79175Y562243D01*
Y562532D01*
G02X79188Y562602I200J-1D01*
G01X79205Y562645D01*
X79233Y562674D01*
G03X79635Y563697I-1101J1023D01*
G03Y563705I-1502J4D01*
G01Y563734D01*
G03X79578Y564111I-1502J-34D01*
G01X79564Y564156D01*
G03X79212Y564743I-1431J-459D01*
G01X79122Y564835D01*
X79101Y564857D01*
X79087Y564884D01*
X79055Y564947D01*
X79051Y564961D01*
X79034Y565003D01*
Y565255D01*
G02X79053Y565339I200J-1D01*
G01X79104Y565450D01*
X79135Y565478D01*
G03X79635Y566597I-1002J1119D01*
G03X78133Y568099I-1502J0D01*
G03X76631Y566634I0J-1502D01*
G01Y566595D01*
G03X77134Y565474I1502J1D01*
G01X77150Y565459D01*
X77174Y565426D01*
X77214Y565337D01*
X77232Y565297D01*
Y565039D01*
G02X77213Y564955I-200J1D01*
G01X77162Y564844D01*
X77131Y564816D01*
G03X76631Y563697I1002J-1119D01*
G03X77037Y562670I1502J0D01*
G01X77057Y562649D01*
X77082Y562599D01*
X77091Y562551D01*
Y562262D01*
G02X77080Y562196I-200J-1D01*
G01X77061Y562150D01*
X77036Y562123D01*
G03X77037Y560070I1097J-1026D01*
G01X77057Y560049D01*
X77082Y559999D01*
X77091Y559951D01*
Y559662D01*
G02X77080Y559596I-200J-1D01*
G01X77061Y559550D01*
X77036Y559523D01*
G03X77037Y557470I1097J-1026D01*
G01X77057Y557449D01*
X77082Y557399D01*
X77091Y557351D01*
Y557062D01*
G02X77080Y556996I-200J-1D01*
G01X77061Y556950D01*
X77036Y556923D01*
G03X77037Y554870I1097J-1026D01*
G01X77057Y554849D01*
X77082Y554799D01*
X77091Y554751D01*
Y554462D01*
G02X77078Y554392I-200J1D01*
G01X77061Y554349D01*
X77033Y554320D01*
G03X76631Y553297I1101J-1023D01*
G03X76644Y553097I1502J-3D01*
G03X77025Y552282I1489J200D01*
G02X77062Y552070I-148J-135D01*
G01X76186Y549954D01*
G02X75965Y549834I-185J77D01*
G01X75964D01*
G03X75688Y549860I-278J-1476D01*
G03X74701Y549490I0J-1501D01*
G01X74700D01*
Y549489D01*
G02X74570Y549441I-130J152D01*
G01X74306D01*
G02X74176Y549489I0J200D01*
G01X74175Y549490D01*
G03X72201I-987J-1131D01*
G01X72200D01*
Y549489D01*
G02X72070Y549441I-130J152D01*
G01X71806D01*
G02X71676Y549489I0J200D01*
G01X71675Y549490D01*
G03X69701I-987J-1131D01*
G01X69700D01*
Y549489D01*
G02X69570Y549441I-130J152D01*
G01X69306D01*
G02X69176Y549489I0J200D01*
G01X69175Y549490D01*
G03X68188Y549860I-987J-1131D01*
G03X66686Y548358I0J-1502D01*
G03X67261Y547177I1502J1D01*
G02X67337Y547021I-124J-157D01*
G01X67339Y546661D01*
X67299Y546578D01*
X67263Y546550D01*
G03X66700Y545378I939J-1172D01*
G01Y545377D01*
G03X67070Y544390I1501J0D01*
G01Y544389D01*
X67071D01*
G02X67119Y544259I-152J-130D01*
G01Y543995D01*
G02X67071Y543865I-200J0D01*
G01X67070Y543864D01*
G03Y541890I1131J-987D01*
G01Y541889D01*
X67071D01*
G02X67119Y541759I-152J-130D01*
G01Y541495D01*
G02X67071Y541365I-200J0D01*
G01X67070Y541364D01*
G03Y539390I1131J-987D01*
G01Y539389D01*
X67071D01*
G02X67119Y539259I-152J-130D01*
G01Y538995D01*
G02X67071Y538865I-200J0D01*
G01X67070Y538864D01*
G03X66700Y537877I1131J-987D01*
G03X69704I1502J0D01*
G03X69334Y538864I-1501J0D01*
G01Y538865D01*
X69333D01*
G02X69285Y538995I152J130D01*
G01Y539259D01*
G02X69333Y539389I200J0D01*
G01X69334Y539390D01*
G03Y541364I-1131J987D01*
G01Y541365D01*
X69333D01*
G02X69285Y541495I152J130D01*
G01Y541759D01*
G02X69333Y541889I200J0D01*
G01X69334Y541890D01*
G03Y543864I-1131J987D01*
G01Y543865D01*
X69333D01*
G02X69285Y543995I152J130D01*
G01Y544259D01*
G02X69333Y544389I200J0D01*
G01X69334Y544390D01*
G03X69704Y545377I-1131J987D01*
G03X69129Y546558I-1502J-1D01*
G02X69053Y546714I124J157D01*
G01X69051Y547074D01*
X69091Y547157D01*
X69127Y547185D01*
G03X69174Y547225I-950J1164D01*
G02X69176Y547227I142J-140D01*
G01X69203Y547250D01*
X69270Y547275D01*
X69570D01*
G02X69700Y547227I0J-200D01*
G01X69701Y547226D01*
G03X71675I987J1131D01*
G01X71676D01*
Y547227D01*
G02X71806Y547275I130J-152D01*
G01X72070D01*
G02X72200Y547227I0J-200D01*
G01X72201Y547226D01*
G03X74175I987J1131D01*
G01X74176D01*
Y547227D01*
G02X74306Y547275I130J-152D01*
G01X74570D01*
G02X74700Y547227I0J-200D01*
G01X74701Y547226D01*
G03X75453Y546875I986J1132D01*
G01X75454D01*
G02X75622Y546677I-32J-197D01*
G01Y521131D01*
G02X75459Y520935I-200J0D01*
G03Y517981I277J-1477D01*
G02X75622Y517785I-37J-196D01*
G01Y514624D01*
G03X75791Y513485I3926J0D01*
G01X99087Y436693D01*
G03X99216Y436330I3760J1132D01*
G01X107353Y416686D01*
G03X108205Y415413I3626J1505D01*
G01X110121Y413496D01*
X110133Y413476D01*
G03X110709Y412741I3329J2016D01*
G01X130128Y393322D01*
G03X130799Y392787I2747J2757D01*
G03X130801Y392785I139J137D01*
G03X130820Y392774I1959J3362D01*
G03X130822Y392772I139J137D01*
G03X130828Y392769I1740J3473D01*
G03X130972Y392683I2067J3297D01*
G01X130973D01*
X131017Y392659D01*
X131029Y392653D01*
X131032Y392652D01*
G03X131387Y392483I1848J3424D01*
G01X140846Y388566D01*
G03X142048Y388281I1487J3595D01*
G02X142068Y388278I-20J-199D01*
G03X142739Y388220I672J3868D01*
G01X145840D01*
G02X145978Y388164I-1J-200D01*
G03X148692Y387074I2715J2837D01*
G03X152056Y388977I-1J3927D01*
G02X152106Y389032I170J-105D01*
G03X152690Y390221I-918J1189D01*
G01Y390224D01*
G03X152620Y390679I-1502J2D01*
G02X152611Y390752I190J61D01*
G03X152618Y391001I-3919J235D01*
G03X152269Y392619I-3927J0D01*
G02Y392783I183J82D01*
G03X152618Y394401I-3578J1618D01*
G03X152611Y394650I-3926J14D01*
G01X152608Y394689D01*
X152609Y394693D01*
G03X152618Y394719I-1415J504D01*
G01X152649Y394814D01*
X152653Y394837D01*
X152654Y394842D01*
X152667Y394915D01*
G03X152680Y395002I-1479J265D01*
G01X152685Y395051D01*
G03X152691Y395179I-1497J134D01*
G03X152107Y396369I-1504J0D01*
G02X152057Y396424I120J160D01*
G03X148692Y398328I-3365J-2022D01*
G03X145977Y397238I0J-3926D01*
G01X145948Y397210D01*
X145878Y397182D01*
X144809D01*
G02X144783Y397210I133J149D01*
G01X144775Y397220D01*
X144752Y397247D01*
G02X144728Y397281I151J132D01*
G01X144693Y397351D01*
X144687Y397400D01*
X144686Y397408D01*
G03X144676Y397522I-1500J-74D01*
G01Y397525D01*
X144675Y397537D01*
X144673Y397553D01*
X144667Y397594D01*
X144665Y397605D01*
X144664Y397609D01*
G03X144660Y397629I-197J-29D01*
G02X144657Y397640I191J58D01*
G03X144636Y397727I-1470J-309D01*
G01X144633Y397741D01*
X144629Y397753D01*
G03X144617Y397791I-1438J-433D01*
G02X144609Y397864I191J58D01*
G03X144616Y398113I-3919J235D01*
G03X144267Y399731I-3927J0D01*
G02Y399895I183J82D01*
G03X144616Y401513I-3578J1618D01*
G03X144609Y401759I-3926J11D01*
G02X144618Y401833I199J13D01*
G03X144631Y401876I-1432J457D01*
G03X144683Y402150I-1445J416D01*
G01Y402151D01*
X144686Y402179D01*
X144737Y402309D01*
G02X144808Y402392I182J-84D01*
G01X145839D01*
G02X145977Y402337I0J-200D01*
G03X148690Y401248I2714J2837D01*
G01X148692D01*
G03X152058Y403153I0J3926D01*
G02X152107Y403208I171J-103D01*
G03X152690Y404384I-919J1188D01*
G01Y404398D01*
G03X152611Y404878I-1502J-1D01*
G01X152608Y404887D01*
G03X152618Y405174I-3916J280D01*
G03X152269Y406792I-3927J0D01*
G02Y406956I183J82D01*
G03X152618Y408574I-3578J1618D01*
G03X152608Y408862I-3926J8D01*
G03X152610Y408867I-1393J560D01*
G03X152611Y408869I-174J88D01*
G01X152619Y408894D01*
Y408895D01*
G02X152623Y408909I194J-48D01*
G03X152630Y408930I-1421J485D01*
G01Y408932D01*
X152638Y408959D01*
G03X152645Y408986I-1451J390D01*
G01X152657Y409033D01*
G03X152680Y409176I-1470J310D01*
G01X152685Y409224D01*
G03X152691Y409352I-1497J134D01*
G03X152107Y410542I-1504J0D01*
G02X152057Y410597I120J160D01*
G03X148692Y412500I-3365J-2024D01*
G01X148691D01*
G03X146147Y411564I0J-3926D01*
G02X145944Y411530I-130J152D01*
G03X144501Y411806I-1446J-3650D01*
G01X142601D01*
G03X142580Y411805I176J-3919D01*
G01X142558D01*
G02X142503Y411820I25J199D01*
G02X142439Y411863I77J184D01*
G01X142272Y412033D01*
G02X142215Y412178I143J140D01*
G03X142216Y412287I-3925J91D01*
G03X141867Y413905I-3927J0D01*
G02Y414069I183J82D01*
G03X142216Y415687I-3578J1618D01*
G03X142209Y415936I-3926J14D01*
G01X142206Y415973D01*
X142213Y415994D01*
X142214Y415998D01*
X142232Y416056D01*
G03X142234Y416063I-1443J416D01*
G01Y416065D01*
X142240Y416090D01*
G03X142277Y416279I-1453J382D01*
G01Y416281D01*
G03X142282Y416327I-1490J185D01*
G01X142285Y416360D01*
X142327Y416453D01*
Y416454D01*
X142341Y416484D01*
X142376Y416523D01*
X142381Y416528D01*
X142392Y416542D01*
G02X142415Y416566I155J-126D01*
G01X145840D01*
G02X145978Y416510I-1J-200D01*
G03X148692Y415420I2715J2837D01*
G03X152056Y417323I-1J3927D01*
G02X152106Y417378I170J-105D01*
G03X152690Y418567I-918J1189D01*
G01Y418570D01*
G03X152620Y419025I-1502J2D01*
G02X152611Y419098I190J61D01*
G03X152618Y419347I-3919J235D01*
G03X152269Y420965I-3927J0D01*
G02Y421129I183J82D01*
G03X152618Y422747I-3578J1618D01*
G03X152611Y422996I-3926J14D01*
G01X152608Y423035D01*
X152609Y423039D01*
G03X152618Y423065I-1415J504D01*
G01X152649Y423160D01*
X152653Y423183D01*
X152654Y423188D01*
X152667Y423261D01*
G03X152680Y423348I-1479J265D01*
G01X152685Y423397D01*
G03X152691Y423525I-1497J134D01*
G03X152107Y424715I-1504J0D01*
G02X152057Y424770I120J160D01*
G03X148692Y426674I-3365J-2022D01*
G03X146154Y425742I2J-3926D01*
G01X146138Y425737D01*
X146106D01*
G02X146039Y425749I1J200D01*
G03X144723Y425978I-1315J-3663D01*
G01X142518D01*
G02X142462Y426015I81J183D01*
G01X142325Y426143D01*
X142233Y426229D01*
G02X142212Y426256I147J136D01*
G01X142215Y426339D01*
G03X142216Y426459I-3925J93D01*
G01Y426461D01*
G03X142088Y427460I-3927J5D01*
G02X142083Y427483I192J54D01*
G03X142067Y427538I-198J-28D01*
G01X142063Y427547D01*
G03X141867Y428078I-3772J-1091D01*
G02Y428242I183J82D01*
G03X142216Y429860I-3578J1618D01*
G03X142209Y430107I-3926J12D01*
G02X142218Y430180I199J12D01*
G03X142242Y430264I-1433J455D01*
G03X142283Y430499I-1456J375D01*
G01Y430500D01*
X142286Y430527D01*
X142312Y430596D01*
X142314Y430601D01*
X142335Y430651D01*
X142361Y430680D01*
X142398Y430722D01*
G02X142401Y430725I143J-140D01*
G03X142405Y430729I-139J143D01*
G02X142416Y430740I147J-136D01*
G01X145840D01*
G02X145978Y430684I-1J-200D01*
G03X148692Y429594I2715J2837D01*
G03X152056Y431497I-1J3927D01*
G02X152106Y431552I170J-105D01*
G03X152690Y432741I-918J1189D01*
G01Y432744D01*
G03X152620Y433199I-1502J2D01*
G02X152611Y433272I190J61D01*
G03X152618Y433521I-3919J235D01*
G03X152269Y435139I-3927J0D01*
G02Y435303I183J82D01*
G03X152618Y436921I-3578J1618D01*
G03X152611Y437170I-3926J14D01*
G01X152608Y437209D01*
X152609Y437213D01*
G03X152618Y437239I-1415J504D01*
G01X152649Y437334D01*
X152653Y437357D01*
X152654Y437362D01*
X152667Y437435D01*
G03X152680Y437522I-1479J265D01*
G01X152685Y437571D01*
G03X152691Y437699I-1497J134D01*
G03X152107Y438889I-1504J0D01*
G02X152057Y438944I120J160D01*
G03X148692Y440848I-3365J-2022D01*
G03X146232Y439981I1J-3927D01*
G02X146043Y439948I-125J156D01*
G03X144795Y440152I-1249J-3723D01*
G01X142885D01*
G03X142445Y440127I2J-3926D01*
G01X142270Y440107D01*
X142262Y440140D01*
G03X142260Y440149I-195J-39D01*
G01Y440151D01*
X142255Y440169D01*
G03X142237Y440244I-1469J-313D01*
G01X142233Y440261D01*
X142229Y440273D01*
G03X142217Y440311I-1438J-433D01*
G02X142209Y440384I191J58D01*
G03X142216Y440633I-3919J235D01*
G03X141867Y442251I-3927J0D01*
G02Y442415I183J82D01*
G03X142216Y444033I-3578J1618D01*
G03X142209Y444282I-3926J14D01*
G01X142206Y444321D01*
X142207Y444325D01*
G03X142216Y444351I-1415J504D01*
G01X142247Y444446D01*
X142251Y444469D01*
X142252Y444474D01*
X142265Y444547D01*
G03X142278Y444634I-1479J265D01*
G01X142283Y444683D01*
G03X142289Y444811I-1497J134D01*
G03X141705Y446001I-1504J0D01*
G02X141655Y446056I120J160D01*
G03X138290Y447960I-3365J-2022D01*
G03X137392Y447855I4J-3927D01*
G02X137161Y447973I-46J195D01*
G01X136447Y449699D01*
G03X135704Y450861I-3628J-1501D01*
G02X135652Y450989I148J135D01*
G03X135356Y452331I-3923J-162D01*
G01X134610Y454134D01*
G03X133867Y455296I-3628J-1501D01*
G02X133815Y455424I148J135D01*
G03X133519Y456766I-3923J-162D01*
G01X132773Y458569D01*
G03X132030Y459731I-3628J-1501D01*
G02X131978Y459859I148J135D01*
G03X131682Y461201I-3923J-162D01*
G01X131006Y462835D01*
G02X130991Y462912I185J76D01*
G01Y465674D01*
G02X131050Y465816I200J0D01*
G01X132083Y466849D01*
G02X132225Y466908I142J-141D01*
G01X132494D01*
X132567Y466938D01*
X132575Y466946D01*
X132698Y466896D01*
G03X134178Y466606I1481J3636D01*
G01X135438D01*
G02X135576Y466550I-1J-200D01*
G03X138290Y465460I2715J2837D01*
G03X141654Y467363I-1J3927D01*
G02X141704Y467418I170J-105D01*
G03X142288Y468607I-918J1189D01*
G01Y468610D01*
G03X142218Y469065I-1502J2D01*
G02X142209Y469138I190J61D01*
G03X142216Y469387I-3919J235D01*
G03X141867Y471005I-3927J0D01*
G02Y471169I183J82D01*
G03X142216Y472787I-3578J1618D01*
G03X142209Y473036I-3926J14D01*
G02X142218Y473109I199J12D01*
G03X142283Y473442I-1433J452D01*
G01X142284Y473454D01*
G03X142287Y473510I-1498J108D01*
G01X142289Y473546D01*
X142314Y473609D01*
X142325Y473621D01*
X142388Y473692D01*
G02X142395Y473699I145J-138D01*
G01X142405Y473709D01*
G02X142415Y473718I139J-144D01*
G01X145840D01*
G02X145978Y473662I-1J-200D01*
G03X148692Y472572I2715J2837D01*
G03X152056Y474475I-1J3927D01*
G02X152106Y474530I170J-105D01*
G03X152690Y475719I-918J1189D01*
G01Y475722D01*
G03X152620Y476177I-1502J2D01*
G02X152611Y476250I190J61D01*
G03X152618Y476499I-3919J235D01*
G03X152269Y478117I-3927J0D01*
G02Y478281I183J82D01*
G03X152618Y479899I-3578J1618D01*
G03X152611Y480148I-3926J14D01*
G01X152608Y480187D01*
X152609Y480191D01*
G03X152618Y480217I-1415J504D01*
G01X152649Y480312D01*
X152653Y480335D01*
X152654Y480340D01*
X152667Y480413D01*
G03X152680Y480500I-1479J265D01*
G01X152685Y480549D01*
G03X152691Y480677I-1497J134D01*
G03X152107Y481867I-1504J0D01*
G02X152057Y481922I120J160D01*
G03X148692Y483826I-3365J-2022D01*
G03X145977Y482736I0J-3926D01*
G01X145948Y482708D01*
X145878Y482680D01*
X145761D01*
X145723Y482697D01*
G03X145159Y482896I-1585J-3593D01*
G02X145151Y482898I44J195D01*
G03X143978Y483080I-1176J-3709D01*
G01X142570D01*
G02X142438Y483140I11J200D01*
G01X142272Y483309D01*
G02X142215Y483454I143J140D01*
G03X142216Y483560I-3925J90D01*
G03X141867Y485178I-3927J0D01*
G02Y485342I183J82D01*
G03X142216Y486960I-3578J1618D01*
G03X142209Y487209I-3926J14D01*
G02X142218Y487282I199J12D01*
G03X142288Y487737I-1432J453D01*
G01Y487755D01*
G03X142251Y488072I-1502J-15D01*
G01X142245Y488100D01*
X142248Y488155D01*
X142258Y488183D01*
G02X142322Y488273I189J-66D01*
G01X142408Y488341D01*
X142410D01*
X142426Y488354D01*
X142467Y488376D01*
X142490Y488381D01*
G02X142582I46J-195D01*
G01X142633Y488369D01*
X142654Y488358D01*
G03X144177Y487949I1750J3476D01*
G02X144199Y487946I-16J-199D01*
G03X144852Y487892I649J3872D01*
G01X145878D01*
X145948Y487864D01*
X145977Y487836D01*
G03X148692Y486746I2715J2836D01*
G03X152056Y488649I-1J3927D01*
G02X152106Y488704I170J-105D01*
G03X152690Y489893I-918J1189D01*
G01Y489896D01*
G03X152620Y490351I-1502J2D01*
G02X152611Y490424I190J61D01*
G03X152618Y490673I-3919J235D01*
G03X152269Y492291I-3927J0D01*
G02Y492455I183J82D01*
G03X152618Y494073I-3578J1618D01*
G03X152611Y494322I-3926J14D01*
G01X152608Y494361D01*
X152609Y494365D01*
G03X152618Y494391I-1415J504D01*
G01X152649Y494486D01*
X152653Y494509D01*
X152654Y494514D01*
X152667Y494587D01*
G03X152680Y494674I-1479J265D01*
G01X152685Y494723D01*
G03X152691Y494851I-1497J134D01*
G03X152107Y496041I-1504J0D01*
G02X152057Y496096I120J160D01*
G03X148692Y498000I-3365J-2022D01*
G03X146700Y497457I0J-3927D01*
G01Y497456D01*
X146669Y497438D01*
G02X146518Y497417I-101J172D01*
G01X146486Y497425D01*
X146391Y497587D01*
G03X146377Y497601I-2759J-2745D01*
G01X145146Y498832D01*
G03X145085Y498892I-2759J-2744D01*
G02X145083Y498894I140J142D01*
G01X144716Y499261D01*
G03X144446Y499507I-2753J-2751D01*
G01X144424Y499525D01*
X142868Y501853D01*
X142861Y501895D01*
G03X142259Y503396I-3867J-680D01*
G01X141314Y504810D01*
G03X140462Y505726I-3265J-2182D01*
G02X140392Y505830I122J158D01*
G03X139870Y506970I-3785J-1044D01*
G01X138924Y508385D01*
G03X138474Y508941I-3264J-2182D01*
G02X138429Y509148I143J140D01*
G01X138551Y509487D01*
G02X138717Y509618I188J-68D01*
G03X141654Y511497I-427J3903D01*
G02X141704Y511552I170J-105D01*
G03X142288Y512741I-918J1189D01*
G01Y512744D01*
G03X142218Y513199I-1502J2D01*
G02X142209Y513272I190J61D01*
G03X142216Y513521I-3919J235D01*
G03X141867Y515139I-3927J0D01*
G02Y515303I183J82D01*
G03X142216Y516921I-3578J1618D01*
G03X142209Y517170I-3926J14D01*
G02X142217Y517242I199J14D01*
G03X142241Y517326I-1432J454D01*
G01Y517328D01*
G03X142288Y517657I-1454J376D01*
G02X142488Y517852I200J-5D01*
G01X145840D01*
G02X145978Y517796I-1J-200D01*
G03X148692Y516706I2715J2837D01*
G03X152056Y518609I-1J3927D01*
G02X152106Y518664I170J-105D01*
G03X152690Y519853I-918J1189D01*
G01Y519856D01*
G03X152620Y520311I-1502J2D01*
G02X152611Y520384I190J61D01*
G03X152618Y520633I-3919J235D01*
G03X152269Y522251I-3927J0D01*
G02Y522415I183J82D01*
G03X152618Y524033I-3578J1618D01*
G03X152611Y524283I-3926J15D01*
G01X152608Y524320D01*
X152649Y524447D01*
X152654Y524474D01*
Y524476D01*
X152660Y524506D01*
Y524507D01*
X152664Y524529D01*
G03X152680Y524636I-1477J276D01*
G01Y524638D01*
X152681Y524648D01*
G03X152687Y524720I-1493J161D01*
G01Y524724D01*
G03X152691Y524811I-1498J112D01*
G01Y524812D01*
G03X152107Y526001I-1503J0D01*
G02X152057Y526056I120J160D01*
G03X148692Y527960I-3365J-2022D01*
G03X145977Y526870I0J-3926D01*
G01X145948Y526842D01*
X145878Y526814D01*
X145364D01*
G02X145273Y526836I0J200D01*
G03X143587Y527263I-1783J-3498D01*
G01X143551Y527264D01*
X142920Y527525D01*
G03X142391Y527701I-1491J-3597D01*
G01X142390D01*
G02X142288Y527765I50J194D01*
G01X142255Y527805D01*
G02X142210Y527920I155J127D01*
G03X141867Y529312I-3920J-228D01*
G02Y529476I183J82D01*
G03X142216Y531094I-3578J1618D01*
G03X142209Y531344I-3926J15D01*
G01X142206Y531381D01*
X142247Y531508D01*
X142252Y531535D01*
Y531537D01*
X142258Y531567D01*
Y531568D01*
X142262Y531590D01*
G03X142278Y531697I-1477J276D01*
G01Y531699D01*
X142279Y531709D01*
Y531712D01*
X142281Y531727D01*
X142282Y531731D01*
G03X142288Y531872I-1496J134D01*
G01Y531876D01*
G03X142264Y532140I-1502J-3D01*
G01Y532141D01*
X142262Y532153D01*
X142261Y532161D01*
X142257Y532174D01*
X142248Y532222D01*
X142265Y532273D01*
G02X142338Y532371I189J-65D01*
G01X142643Y532591D01*
X142651Y532595D01*
G03X144688Y532024I2039J3355D01*
G01X145840D01*
G02X145978Y531969I0J-200D01*
G03X148691Y530880I2714J2837D01*
G01X148692D01*
G03X152058Y532785I0J3926D01*
G02X152107Y532840I171J-103D01*
G03X152690Y534028I-919J1188D01*
G01Y534030D01*
G03X152689Y534084I-1501J-1D01*
G01Y534092D01*
G03X152656Y534345I-1501J-67D01*
G03X152619Y534484I-1468J-316D01*
G02X152611Y534557I191J58D01*
G03X152618Y534806I-3919J235D01*
G03X152269Y536424I-3927J0D01*
G02Y536588I183J82D01*
G03X152618Y538206I-3578J1618D01*
G03X152611Y538455I-3926J14D01*
G02X152620Y538528I199J12D01*
G03X152690Y538982I-1432J453D01*
G01Y538985D01*
G03X152107Y540172I-1501J-1D01*
G02X152058Y540227I122J158D01*
G03X151501Y540949I-3366J-2021D01*
G02X151444Y541089I143J140D01*
G01X151446Y541372D01*
G02X151504Y541512I200J-1D01*
G01X151732Y541740D01*
G03X152583Y543013I-2776J2777D01*
G01X154378Y547345D01*
G03X154602Y548084I-3627J1503D01*
G01X154747Y548809D01*
X154764Y548849D01*
X154778Y548867D01*
G03X155480Y550449I-3150J2344D01*
G01X155850Y552314D01*
G03X155926Y553078I-3851J769D01*
G03X155886Y553638I-3927J1D01*
G02X155912Y553769I198J29D01*
G03X156388Y555012I-3376J2005D01*
G01X156767Y556925D01*
G03X156842Y557688I-3852J764D01*
G03X156802Y558248I-3927J1D01*
G02X156828Y558379I198J29D01*
G03X157304Y559622I-3376J2005D01*
G01X157475Y560491D01*
X157544Y560570D01*
X157571Y560580D01*
G03X158592Y562003I-481J1423D01*
G03X158023Y563181I-1504J0D01*
G02X157964Y563418I124J157D01*
G03X158220Y564232I-3596J1578D01*
G01X158599Y566145D01*
G03X158674Y566908I-3852J764D01*
G03X158634Y567468I-3927J1D01*
G02X158660Y567599I198J29D01*
G03X159136Y568842I-3376J2005D01*
G01X159515Y570755D01*
G03X159590Y571518I-3852J764D01*
G03X159550Y572078I-3927J1D01*
G02X159576Y572209I198J29D01*
G03X160052Y573452I-3376J2005D01*
G01X160431Y575365D01*
G03X160506Y576128I-3852J764D01*
G03X160466Y576688I-3927J1D01*
G02X160492Y576819I198J29D01*
G03X160968Y578062I-3376J2005D01*
G01X161347Y579975D01*
G03X161422Y580738I-3852J764D01*
G03X161387Y581254I-3927J-7D01*
G02X161416Y581387I198J26D01*
G03X161941Y582709I-3326J2086D01*
G01X162321Y584623D01*
G03X162396Y585388I-3851J764D01*
G03X162248Y586456I-3926J0D01*
G01X162235Y586502D01*
X190402Y728343D01*
G02X190409Y728368I196J-41D01*
G01X280139Y993438D01*
G02X280328Y993574I189J-64D01*
G01X288657D01*
G02X288806Y993508I1J-200D01*
G01X288834Y993477D01*
X288860Y993399D01*
X286855Y970461D01*
G02X286853Y970447I-199J21D01*
G01X285818Y963952D01*
X285268Y960500D01*
X280112Y928123D01*
G02X280025Y927987I-198J31D01*
G01X279744Y927801D01*
X279662Y927787D01*
X279621Y927797D01*
G03X279261Y927841I-361J-1458D01*
G03X277759Y926339I0J-1502D01*
G03X279150Y924841I1502J0D01*
G01X279192Y924838D01*
X279266Y924799D01*
X279475Y924535D01*
G02X279515Y924379I-157J-123D01*
G01X276950Y908269D01*
G03X276902Y907660I3843J-609D01*
G01Y907655D01*
G03X276910Y907406I3891J0D01*
G01X277885Y892333D01*
X277822Y892227D01*
X277766Y892201D01*
G03X276898Y890839I635J-1362D01*
G03X277947Y889407I1502J0D01*
G01X278005Y889389D01*
X278082Y889291D01*
X278791Y878330D01*
Y878300D01*
X277898Y868099D01*
G03X277884Y867758I3912J-331D01*
G01Y867756D01*
G03X277898Y867415I3926J-10D01*
G01X284043Y797182D01*
Y797178D01*
X284058Y796951D01*
X285438Y775625D01*
X285587Y773319D01*
X286233Y763340D01*
X286810Y754418D01*
X290109Y703455D01*
G03X290268Y702575I3884J247D01*
G01X296808Y681038D01*
G02X296810Y681032I-189J-66D01*
G01X299008Y672827D01*
G03X299400Y671880I3793J1015D01*
G01X326591Y624781D01*
X326596Y624740D01*
G03X327099Y623200I3903J423D01*
G01X328075Y621510D01*
G03X328885Y620522I3401J1962D01*
G02X328950Y620411I-131J-151D01*
G03X329400Y619215I3851J766D01*
G01X329776Y618565D01*
G02X329795Y618409I-173J-100D01*
G01X329712Y618131D01*
G02X329611Y618009I-192J56D01*
G03X328030Y616533I1785J-3497D01*
G02X327980Y616478I-170J105D01*
G03X327397Y615299I919J-1188D01*
G01Y615285D01*
G03X327467Y614834I1502J2D01*
G02X327476Y614761I-190J-61D01*
G03X327468Y614511I3919J-251D01*
G03X327817Y612893I3927J0D01*
G02Y612729I-182J-82D01*
G03X327468Y611112I3578J-1618D01*
G01Y611110D01*
G03X327470Y611006I3927J23D01*
G01Y611004D01*
X327472Y610926D01*
G02X327454Y610903I-166J111D01*
G01X327317Y610762D01*
G02X327315Y610760I-142J140D01*
G01X327243Y610688D01*
G02X327176Y610644I-141J142D01*
G01X327142Y610630D01*
X326125D01*
G03X324876Y610424I0J-3892D01*
G01X324872Y610423D01*
X324855Y610418D01*
X324845Y610415D01*
X324835Y610413D01*
G03X324810Y610408I750J-3817D01*
G01X324790Y610404D01*
G03X324280Y610264I773J-3814D01*
G03X324229Y610246I1270J-3679D01*
G03X324095Y610195I1317J-3662D01*
G01X324084Y610191D01*
G03X324059Y610180I1555J-3567D01*
G01X323807D01*
X323737Y610208D01*
X323708Y610236D01*
G03X320993Y611326I-2715J-2836D01*
G03X317628Y609422I0J-3926D01*
G02X317578Y609367I-170J105D01*
G03X316995Y608179I920J-1188D01*
G01Y608151D01*
G03X316998Y608077I1502J24D01*
G01X316999Y608070D01*
Y608062D01*
X317004Y607991D01*
G03X317005Y607980I199J13D01*
G01X317007Y607969D01*
X317017Y607918D01*
X317018Y607912D01*
G03X317065Y607722I1479J265D01*
G02X317074Y607648I-190J-61D01*
G03X317066Y607399I3919J-251D01*
G03X317415Y605781I3927J0D01*
G02Y605617I-182J-82D01*
G03X317066Y603999I3578J-1618D01*
G03X317074Y603749I3927J1D01*
G02X317065Y603676I-199J-12D01*
G03X316995Y603224I1432J-453D01*
G01Y603196D01*
G03X317005Y603045I1502J24D01*
G01X317014Y602970D01*
G03X317015Y602963I198J25D01*
G01X317017Y602954D01*
X317038Y602862D01*
Y602857D01*
X317042Y602846D01*
X317046Y602831D01*
X317047Y602826D01*
X317050Y602815D01*
G03X317066Y602762I1446J408D01*
G01X317067Y602759D01*
X317069Y602755D01*
X317087Y602698D01*
G03X317099Y602672I187J70D01*
G01X317100Y602670D01*
G03X317115Y602633I1400J546D01*
G01X317119Y602621D01*
X317127Y602605D01*
G03X317462Y602131I1371J614D01*
G03X317578Y602031I1038J1086D01*
G02X317628Y601976I-120J-160D01*
G03X320993Y600072I3365J2022D01*
G03X323707Y601162I-1J3927D01*
G02X323845Y601218I139J-144D01*
G01X327268D01*
G02X327278Y601209I-129J-153D01*
G01X327288Y601199D01*
X327334Y601147D01*
X327350Y601129D01*
X327372Y601104D01*
X327399Y601040D01*
X327401Y601005D01*
G03X327436Y600773I1498J107D01*
G03X327468Y600656I1464J338D01*
G02X327476Y600583I-191J-58D01*
G03X327468Y600338I3919J-251D01*
G03X327817Y598720I3927J0D01*
G02Y598556I-182J-82D01*
G03X327468Y596938I3578J-1618D01*
G03X327476Y596690I3927J3D01*
G02X327467Y596617I-199J-12D01*
G03X327425Y596451I1433J-451D01*
G02X327343Y596325I-196J38D01*
G01X327321Y596310D01*
X327262Y596279D01*
X327246Y596273D01*
G03X326650Y596028I1177J-3711D01*
G02X326559Y596006I-91J178D01*
G01X323845D01*
G02X323707Y596062I1J200D01*
G03X320993Y597152I-2715J-2837D01*
G03X317628Y595248I0J-3926D01*
G02X317578Y595193I-170J105D01*
G03X316995Y594005I920J-1188D01*
G01Y593977D01*
G03X316998Y593903I1502J24D01*
G01X316999Y593896D01*
Y593888D01*
X317004Y593817D01*
G03X317005Y593806I199J13D01*
G01X317007Y593795D01*
X317017Y593744D01*
X317018Y593738D01*
G03X317065Y593548I1479J265D01*
G02X317074Y593474I-190J-61D01*
G03X317066Y593225I3919J-251D01*
G03X317415Y591607I3927J0D01*
G02Y591443I-182J-82D01*
G03X317066Y589825I3578J-1618D01*
G03X317074Y589575I3927J1D01*
G02X317065Y589502I-199J-12D01*
G03X316995Y589050I1432J-453D01*
G01Y589022D01*
G03X317005Y588871I1502J24D01*
G01X317014Y588796D01*
G03X317015Y588789I198J25D01*
G01X317017Y588780D01*
X317038Y588688D01*
Y588683D01*
X317042Y588672D01*
X317046Y588657D01*
X317047Y588652D01*
X317050Y588641D01*
G03X317066Y588588I1446J408D01*
G01X317067Y588585D01*
X317069Y588581D01*
X317087Y588524D01*
G03X317099Y588498I187J70D01*
G01X317100Y588496D01*
G03X317115Y588459I1400J546D01*
G01X317119Y588447D01*
X317127Y588431D01*
G03X317462Y587957I1371J614D01*
G03X317578Y587857I1038J1086D01*
G02X317628Y587802I-120J-160D01*
G03X320993Y585898I3365J2022D01*
G03X323707Y586988I-1J3927D01*
G02X323845Y587044I139J-144D01*
G01X327269D01*
G02X327287Y587026I-132J-150D01*
G01X327330Y586977D01*
X327352Y586952D01*
X327400Y586837D01*
X327403Y586806D01*
Y586805D01*
G03X327467Y586485I1497J133D01*
G02X327476Y586412I-190J-61D01*
G03X327468Y586165I3919J-251D01*
G03X327817Y584547I3927J0D01*
G02Y584383I-182J-82D01*
G03X327468Y582765I3578J-1618D01*
G03X327470Y582649I3927J10D01*
G01X327472Y582593D01*
X327446Y582537D01*
X327425Y582515D01*
X327421Y582511D01*
X327329Y582417D01*
X327242Y582328D01*
G02X327129Y582275I-137J146D01*
G02X327105Y582274I-20J199D01*
G01X325735D01*
G03X324933Y582190I2J-3891D01*
G03X324882Y582179I795J-3809D01*
G03X324108Y581917I854J-3797D01*
G01X324107Y581916D01*
G03X324090Y581908I1648J-3525D01*
G01X324082Y581905D01*
G03X324068Y581899I1525J-3577D01*
G02X324064Y581897I-91J178D01*
G03X324059Y581895I72J-187D01*
G03X323984Y581857I1721J-3490D01*
G02X323891Y581834I-93J177D01*
G01X323846D01*
G02X323708Y581889I0J200D01*
G03X320993Y582978I-2714J-2837D01*
G03X317627Y581074I-1J-3926D01*
G02X317578Y581019I-171J103D01*
G03X316995Y579846I919J-1188D01*
G01Y579810D01*
G03X317065Y579372I1503J16D01*
G02X317074Y579299I-190J-61D01*
G03X317066Y579052I3919J-251D01*
G03X317415Y577434I3927J0D01*
G02Y577270I-182J-82D01*
G03X317066Y575652I3578J-1618D01*
G03X317074Y575402I3927J1D01*
G02X317066Y575329I-199J-15D01*
G03X317044Y575254I1429J-460D01*
G03X316996Y574938I1453J-382D01*
G01X316995Y574914D01*
Y574865D01*
G03X317579Y573684I1504J9D01*
G02X317628Y573629I-122J-158D01*
G03X320993Y571726I3365J2024D01*
G01X320994D01*
G03X323707Y572815I-1J3926D01*
G02X323845Y572870I138J-145D01*
G01X327270D01*
G02X327286Y572854I-133J-149D01*
G01X327357Y572776D01*
X327370Y572736D01*
X327401Y572660D01*
X327403Y572630D01*
G03X327406Y572601I1496J140D01*
G03X327467Y572311I1494J163D01*
G02X327476Y572238I-190J-61D01*
G03X327468Y571991I3919J-251D01*
G03X327817Y570373I3927J0D01*
G02Y570209I-182J-82D01*
G03X327468Y568591I3578J-1618D01*
G03X327476Y568344I3927J4D01*
G02X327467Y568271I-199J-12D01*
G03X327397Y567816I1433J-453D01*
G01Y567807D01*
G03X327460Y567379I1502J2D01*
G01X327464Y567366D01*
X327475Y567300D01*
X327469Y567266D01*
X327453Y567174D01*
G02X327412Y567082I-197J33D01*
G01X327324Y566958D01*
X327255Y566860D01*
G02X327228Y566834I-152J131D01*
G03X327226Y566832I140J-142D01*
G02X327218Y566826I-124J157D01*
G01X326844D01*
G02X326767Y566841I-1J200D01*
G01X325511Y567362D01*
G03X324012Y567660I-1500J-3628D01*
G01X323807D01*
X323737Y567688D01*
X323708Y567716D01*
G03X320993Y568806I-2715J-2836D01*
G03X317628Y566902I0J-3926D01*
G02X317578Y566847I-170J105D01*
G03X316995Y565659I920J-1188D01*
G01Y565631D01*
G03X316998Y565557I1502J24D01*
G01X316999Y565550D01*
Y565542D01*
X317004Y565471D01*
G03X317005Y565460I199J13D01*
G01X317007Y565449D01*
X317017Y565398D01*
X317018Y565392D01*
G03X317065Y565202I1479J265D01*
G02X317074Y565128I-190J-61D01*
G03X317066Y564879I3919J-251D01*
G03X317415Y563261I3927J0D01*
G02Y563097I-182J-82D01*
G03X317066Y561479I3578J-1618D01*
G03X317074Y561229I3927J1D01*
G02X317065Y561156I-199J-12D01*
G03X316995Y560704I1432J-453D01*
G01Y560676D01*
G03X317005Y560525I1502J24D01*
G01X317014Y560450D01*
G03X317015Y560443I198J25D01*
G01X317017Y560434D01*
X317038Y560342D01*
Y560337D01*
X317042Y560326D01*
X317046Y560311D01*
X317047Y560306D01*
X317050Y560295D01*
G03X317066Y560242I1446J408D01*
G01X317067Y560239D01*
X317069Y560235D01*
X317087Y560178D01*
G03X317095Y560159I188J68D01*
G02X317103Y560142I-177J-94D01*
G03X317116Y560110I1398J549D01*
G01X317117Y560109D01*
X317119Y560101D01*
X317127Y560085D01*
G03X317578Y559512I1371J615D01*
G02X317628Y559457I-120J-160D01*
G03X320993Y557552I3365J2019D01*
G03X323439Y558407I0J3926D01*
G01X323482Y558442D01*
X323589Y558457D01*
X324301Y558162D01*
G03X325800Y557864I1500J3628D01*
G01X329308D01*
G03X330806Y558162I-2J3927D01*
G01X334244Y559586D01*
G02X334259Y559591I71J-187D01*
G01X335989Y560150D01*
G03X337179Y560778I-1194J3705D01*
G01X337225Y560813D01*
G02X337271Y560840I123J-157D01*
G01X337800Y561059D01*
G03X339073Y561911I-1505J3626D01*
G01X340671Y563509D01*
G02X340690Y563526I143J-140D01*
G01X340882Y563676D01*
X343218Y565504D01*
G02X343463Y565505I123J-158D01*
G01X343517Y565464D01*
X343552Y565333D01*
X343083Y564201D01*
X343059Y564166D01*
X343042Y564151D01*
G03X342799Y563907I2634J-2866D01*
G02X342795Y563903I-143J139D01*
G03X342002Y562688I2835J-2717D01*
G01X341313Y561024D01*
G03X341023Y559788I3628J-1503D01*
G02X340974Y559669I-200J13D01*
G03X340302Y558586I2956J-2584D01*
G01X339613Y556922D01*
G03X339323Y555684I3628J-1503D01*
G02X339274Y555565I-200J13D01*
G03X338603Y554484I2956J-2584D01*
G01X337973Y552962D01*
G02X337869Y552856I-185J77D01*
G01X337765Y552810D01*
X337726Y552793D01*
X337603D01*
X337572Y552804D01*
G03X337091Y552883I-481J-1424D01*
G03X337089I-1J-1503D01*
G01X337078D01*
G03X335586Y551557I0J-1502D01*
G01X335580Y551503D01*
G03X335575Y551381I1498J-122D01*
G03X336485Y550000I1503J0D01*
G01X336500Y549995D01*
G02X336626Y549775I-71J-187D01*
G01X336622Y549757D01*
G02X336616Y549737I-194J47D01*
G01X336540Y549556D01*
X336399Y549219D01*
X336183Y548703D01*
X336182Y548701D01*
G03X336169Y548671I3564J-1562D01*
G01Y548670D01*
X336154Y548633D01*
G03X336146Y548613I3609J-1455D01*
G03X336121Y548548I3620J-1429D01*
G01Y548547D01*
X336094Y548475D01*
G03X336093Y548472I188J-64D01*
G01X336092Y548466D01*
X336062Y548376D01*
G03X335966Y548012I3711J-1173D01*
G03X335894Y547533I3805J-817D01*
G01Y547525D01*
X335892Y547509D01*
G03X335888Y547451I3881J-297D01*
G01X335886Y547417D01*
X335849Y547329D01*
X335830Y547306D01*
G03X335661Y547091I3000J-2532D01*
G02X335657Y547085I-168J108D01*
G03X335463Y546817I3053J-2414D01*
G03X335460Y546811I177J-92D01*
G03X335189Y546328I3250J-2141D01*
G01X335179Y546307D01*
X335153Y546273D01*
X335130Y546254D01*
X335129Y546253D01*
X335039Y546178D01*
X334997Y546166D01*
G03X333955Y545132I403J-1448D01*
G03X333897Y544737I1444J-414D01*
G01Y544717D01*
G03X334152Y543880I1502J0D01*
G01X334168Y543856D01*
X334206Y543739D01*
X334198Y543691D01*
G03X334157Y543332I3842J-621D01*
G01X334156Y543313D01*
X334145Y543272D01*
X334141Y543253D01*
X334103Y543163D01*
X334079Y543138D01*
G03X333816Y542810I2901J-2595D01*
G01X333802Y542789D01*
X333800Y542787D01*
G03X333704Y542644I3182J-2240D01*
G03X333392Y542049I3278J-2098D01*
G01X332719Y540444D01*
G03X332608Y540147I3587J-1510D01*
G01X332596Y540110D01*
X332525Y540025D01*
G02X332468Y539978I-154J128D01*
G01X332439Y539962D01*
X332410Y539946D01*
X332340Y539936D01*
X332301Y539945D01*
G03X331395Y540052I-910J-3819D01*
G03X328030Y538148I0J-3926D01*
G02X327980Y538093I-170J105D01*
G03X327397Y536905I920J-1188D01*
G01Y536877D01*
G03X327400Y536803I1502J24D01*
G01X327401Y536796D01*
Y536788D01*
X327406Y536717D01*
G03X327407Y536706I199J13D01*
G01X327409Y536695D01*
X327419Y536644D01*
X327420Y536638D01*
G03X327467Y536448I1479J265D01*
G02X327476Y536374I-190J-61D01*
G03X327468Y536125I3919J-251D01*
G03X327817Y534507I3927J0D01*
G02Y534343I-182J-82D01*
G03X327468Y532726I3578J-1618D01*
G01Y532724D01*
G03X327470Y532620I3927J23D01*
G01Y532618D01*
X327472Y532540D01*
G02X327454Y532517I-166J111D01*
G01X327317Y532376D01*
G02X327315Y532374I-142J140D01*
G01X327243Y532302D01*
G02X327176Y532258I-141J142D01*
G01X327142Y532244D01*
X326069D01*
G03X325589Y532214I2J-3892D01*
G01X325587D01*
G03X323820Y531794I0J-3927D01*
G01X323764D01*
G03X320993Y532940I-2772J-2780D01*
G03X317628Y531036I0J-3926D01*
G02X317578Y530981I-170J105D01*
G03X316995Y529793I920J-1188D01*
G01Y529765D01*
G03X316998Y529691I1502J24D01*
G01X316999Y529684D01*
Y529676D01*
X317004Y529605D01*
G03X317005Y529594I199J13D01*
G01X317007Y529583D01*
X317017Y529532D01*
X317018Y529526D01*
G03X317065Y529336I1479J265D01*
G02X317074Y529262I-190J-61D01*
G03X317066Y529013I3919J-251D01*
G03X317415Y527395I3927J0D01*
G02Y527231I-182J-82D01*
G03X317066Y525613I3578J-1618D01*
G03X317074Y525363I3927J1D01*
G02X317065Y525290I-199J-12D01*
G03X316995Y524838I1432J-453D01*
G01Y524810D01*
G03X317005Y524659I1502J24D01*
G01X317014Y524584D01*
G03X317015Y524577I198J25D01*
G01X317017Y524568D01*
X317038Y524476D01*
Y524471D01*
X317042Y524460D01*
X317046Y524445D01*
X317047Y524440D01*
X317050Y524429D01*
G03X317066Y524376I1446J408D01*
G01X317067Y524373D01*
X317069Y524369D01*
X317087Y524312D01*
G03X317099Y524286I187J70D01*
G01X317100Y524284D01*
G03X317115Y524247I1400J546D01*
G01X317119Y524235D01*
X317127Y524219D01*
G03X317462Y523745I1371J614D01*
G03X317578Y523645I1038J1087D01*
G02X317628Y523590I-120J-160D01*
G03X320993Y521686I3365J2022D01*
G03X323707Y522776I-1J3927D01*
G02X323845Y522832I139J-144D01*
G01X327268D01*
G02X327278Y522823I-129J-153D01*
G01X327288Y522813D01*
X327334Y522761D01*
X327350Y522743D01*
X327372Y522718D01*
X327399Y522654D01*
X327401Y522619D01*
G03X327452Y522325I1497J108D01*
G01Y522323D01*
G03X327471Y522260I1448J402D01*
G01Y522258D01*
G03X327479Y522235I1423J482D01*
G03X327468Y521952I3916J-294D01*
G03X327817Y520334I3927J0D01*
G02Y520170I-182J-82D01*
G03X327468Y518553I3578J-1618D01*
G01Y518551D01*
G03X327470Y518447I3927J23D01*
G01Y518445D01*
X327472Y518369D01*
G02X327447Y518336I-171J104D01*
G01X327317Y518202D01*
G02X327315Y518200I-142J140D01*
G01X327243Y518128D01*
G02X327176Y518084I-141J142D01*
G01X327142Y518070D01*
X326088D01*
G03X324316Y517642I2J-3892D01*
G02X324225Y517620I-91J178D01*
G01X323807D01*
X323737Y517648D01*
X323708Y517676D01*
G03X320993Y518766I-2715J-2836D01*
G03X317628Y516862I0J-3926D01*
G02X317578Y516807I-170J105D01*
G03X316995Y515619I920J-1188D01*
G01Y515591D01*
G03X317031Y515284I1502J21D01*
G01X317043Y515238D01*
G03X317070Y515149I1450J391D01*
G01Y515147D01*
G03X317077Y515127I1421J486D01*
G03X317066Y514839I3916J-294D01*
G03X317415Y513221I3927J0D01*
G02Y513057I-182J-82D01*
G03X317066Y511439I3578J-1618D01*
G03X317074Y511189I3927J1D01*
G02X317065Y511116I-199J-12D01*
G03X316995Y510664I1432J-453D01*
G01Y510636D01*
G03X317023Y510373I1502J27D01*
G01Y510372D01*
G03X317032Y510333I1467J318D01*
G01Y510331D01*
G03X317057Y510236I1464J334D01*
G01Y510234D01*
X317063Y510210D01*
G03X317578Y509471I1434J450D01*
G02X317628Y509416I-120J-160D01*
G03X320993Y507512I3365J2022D01*
G03X323707Y508602I-1J3927D01*
G02X323845Y508658I139J-144D01*
G01X331733D01*
G03X333236Y508957I0J3927D01*
G01X337290Y510636D01*
G02X337507Y510593I76J-185D01*
G01X337550Y510550D01*
X337574Y510431D01*
X337529Y510325D01*
G03X337234Y509110I3619J-1522D01*
G02X337185Y508994I-200J16D01*
G03X336518Y507930I2950J-2591D01*
G01X335819Y506270D01*
G03X335524Y505055I3619J-1522D01*
G02X335475Y504939I-200J16D01*
G03X334808Y503875I2950J-2591D01*
G01X334109Y502215D01*
G03X333834Y501191I3620J-1521D01*
G02X333824Y501152I-198J30D01*
G03X333621Y500093I3684J-1255D01*
G03X333619Y500055I3885J-224D01*
G02X333605Y499988I-200J7D01*
G03X333391Y499275I3637J-1480D01*
G01X332730Y495949D01*
X332729Y495948D01*
X332493Y495799D01*
X332469Y495784D01*
X332441Y495776D01*
X332369Y495795D01*
G03X331395Y495918I-975J-3804D01*
G03X328030Y494014I0J-3926D01*
G02X327980Y493959I-170J105D01*
G03X327397Y492771I920J-1188D01*
G01Y492743D01*
G03X327433Y492436I1502J21D01*
G01X327445Y492390D01*
G03X327472Y492301I1450J391D01*
G01Y492299D01*
G03X327479Y492279I1421J486D01*
G03X327468Y491991I3916J-294D01*
G03X327817Y490373I3927J0D01*
G02Y490209I-182J-82D01*
G03X327468Y488591I3578J-1618D01*
G03X327476Y488343I3927J3D01*
G02X327467Y488270I-199J-12D01*
G03X327411Y488020I1433J-452D01*
G01X327410Y488014D01*
G02X327276Y487852I-198J27D01*
G03X326853Y487679I1272J-3715D01*
G02X326767Y487660I-85J181D01*
G01X323845D01*
G02X323707Y487716I1J200D01*
G03X320993Y488806I-2715J-2837D01*
G03X317628Y486902I0J-3926D01*
G02X317578Y486847I-170J105D01*
G03X316995Y485659I920J-1188D01*
G01Y485631D01*
G03X317031Y485324I1502J21D01*
G01X317043Y485278D01*
G03X317070Y485189I1450J391D01*
G01Y485187D01*
G03X317077Y485167I1421J486D01*
G03X317066Y484879I3916J-294D01*
G03X317415Y483261I3927J0D01*
G02Y483097I-182J-82D01*
G03X317066Y481479I3578J-1618D01*
G03X317074Y481229I3927J1D01*
G02X317065Y481156I-199J-12D01*
G03X316995Y480704I1432J-453D01*
G01Y480676D01*
G03X317023Y480413I1502J27D01*
G01Y480412D01*
G03X317032Y480373I1467J318D01*
G01Y480371D01*
G03X317057Y480276I1464J334D01*
G01Y480274D01*
X317063Y480250D01*
G03X317578Y479511I1434J450D01*
G02X317628Y479456I-120J-160D01*
G03X320993Y477552I3365J2022D01*
G03X323707Y478642I-1J3927D01*
G02X323845Y478698I139J-144D01*
G01X327268D01*
G02X327278Y478689I-129J-153D01*
G01X327288Y478679D01*
X327334Y478627D01*
X327350Y478609D01*
X327372Y478584D01*
X327399Y478520D01*
X327401Y478485D01*
G03X327452Y478191I1497J108D01*
G01Y478189D01*
G03X327471Y478126I1448J402D01*
G01Y478124D01*
G03X327479Y478101I1423J482D01*
G03X327468Y477818I3916J-294D01*
G03X327817Y476200I3927J0D01*
G02Y476036I-182J-82D01*
G03X327468Y474418I3578J-1618D01*
G03X327470Y474303I3927J11D01*
G01X327472Y474246D01*
X327464Y474228D01*
X327450Y474197D01*
X327291Y474025D01*
X327265Y473997D01*
X327129Y473931D01*
X327090Y473928D01*
G03X325976Y473685I264J-3883D01*
G01X325975Y473684D01*
X325936Y473669D01*
G03X325766Y473599I1396J-3633D01*
G02X325762Y473597I-91J178D01*
G03X325559Y473507I1489J-3633D01*
G01X325557D01*
X325517Y473488D01*
X323845D01*
G02X323707Y473543I0J200D01*
G03X320994Y474632I-2714J-2837D01*
G01X320993D01*
G03X317627Y472728I0J-3927D01*
G02X317578Y472673I-171J103D01*
G03X316995Y471500I919J-1188D01*
G01Y471464D01*
G03X317065Y471026I1503J16D01*
G02X317074Y470953I-190J-61D01*
G03X317066Y470706I3919J-251D01*
G03X317415Y469088I3927J0D01*
G02Y468924I-182J-82D01*
G03X317066Y467306I3578J-1618D01*
G03X317074Y467056I3927J1D01*
G02X317066Y466983I-199J-15D01*
G03X317050Y466930I1429J-460D01*
G03X316996Y466592I1447J-404D01*
G01X316995Y466568D01*
Y466519D01*
G03X317579Y465338I1504J9D01*
G02X317628Y465283I-122J-158D01*
G03X320993Y463380I3365J2024D01*
G01X320994D01*
G03X323707Y464469I-1J3926D01*
G02X323845Y464524I138J-145D01*
G01X331582D01*
G03X333763Y465186I-1J3927D01*
G01X345353Y472929D01*
G03X346800Y474691I-2180J3266D01*
G01X354016Y492114D01*
X354080Y492173D01*
X354103Y492180D01*
G03X355172Y493604I-433J1438D01*
G01Y493642D01*
G03X355161Y493804I-1502J-21D01*
G03X354985Y494345I-1490J-186D01*
G02X354981Y494351I164J113D01*
G01X354978Y494437D01*
X362493Y512578D01*
G02X362536Y512643I185J-76D01*
G01X363197Y513305D01*
G03X364049Y514578I-2774J2778D01*
G01X398004Y596550D01*
G03X398302Y598048I-3629J1500D01*
G01Y629791D01*
G03X398169Y630804I-3926J0D01*
G01X396790Y635966D01*
G03X396398Y636915I-3794J-1012D01*
G01X362916Y694939D01*
G02X362896Y694986I172J101D01*
G01X359795Y706354D01*
G02X359788Y706389I192J57D01*
G01X356373Y745420D01*
G02X356555Y745636I199J17D01*
G01X356611Y745641D01*
X356711Y745592D01*
X356741Y745545D01*
G03X357055Y745155I1959J1256D01*
G01X369815Y732395D01*
G02X369874Y732253I-141J-142D01*
G01Y686800D01*
G03X370555Y685155I2327J0D01*
G01X400315Y655395D01*
G02X400374Y655253I-141J-142D01*
G01Y493300D01*
G03X401055Y491655I2327J0D01*
G01X410655Y482055D01*
G03X412300Y481374I1645J1646D01*
G01X420653D01*
G02X420795Y481315I0J-200D01*
G01X476615Y425495D01*
G02X476674Y425353I-141J-142D01*
G01Y417300D01*
G03X477355Y415655I2327J0D01*
G01X518415Y374595D01*
G02X518474Y374453I-141J-142D01*
G01Y348200D01*
G03X519155Y346555I2327J0D01*
G01X527055Y338655D01*
G03X528700Y337974I1645J1646D01*
G01X572502D01*
G03X573296Y338114I-1J2326D01*
G01X573329Y338126D01*
X573480D01*
G03X575100Y338797I0J2291D01*
G01X578718Y342415D01*
G02X578860Y342474I142J-141D01*
G01X765218D01*
G02X765360Y342415I0J-200D01*
G01X767940Y339835D01*
G03X769560Y339164I1620J1620D01*
G01X791650D01*
G03X791850Y339364I0J200D01*
G01Y339474D01*
G02X792050Y339674I200J0D01*
G01X805853D01*
G02X805995Y339615I0J-200D01*
G01X811055Y334555D01*
G03X812700Y333874I1645J1646D01*
G01X865400D01*
G03X867045Y334555I0J2327D01*
G01X867705Y335215D01*
G02X867847Y335274I142J-141D01*
G01X868410D01*
G02X868589Y335163I0J-200D01*
G01X868749Y334841D01*
G02X868729Y334631I-179J-89D01*
G03X868422Y333722I1195J-910D01*
G03X871426I1502J0D01*
G03X871119Y334631I-1502J-1D01*
G02X871099Y334841I159J121D01*
G01X871259Y335163D01*
G02X871438Y335274I179J-89D01*
G01X886953D01*
G02X887095Y335215I0J-200D01*
G01X906255Y316055D01*
G03X907900Y315374I1645J1646D01*
G01X929000D01*
G03X930645Y316055I0J2327D01*
G01X932105Y317515D01*
G02X932247Y317574I142J-141D01*
G01X935378D01*
G02X935561Y317454I0J-200D01*
G01X935733Y317063D01*
X935714Y316947D01*
X935673Y316903D01*
G03X935198Y315685I1327J-1219D01*
G01Y312283D01*
G03X938802I1802J0D01*
G01Y315685D01*
G03X938327Y316903I-1802J-1D01*
G01X938286Y316947D01*
X938267Y317063D01*
X938439Y317454D01*
G02X938622Y317574I183J-80D01*
G01X940436D01*
G03X942081Y318255I0J2327D01*
G01X943231Y319405D01*
G03X943912Y321050I-1646J1645D01*
G01Y321852D01*
G02X943971Y321994I200J0D01*
G01X944376Y322399D01*
G03X945058Y324044I-1645J1646D01*
G03X942731Y326370I-2326J0D01*
G03X941312Y325888I-1J-2326D01*
G01X941286Y325868D01*
X941224Y325846D01*
X940838D01*
X940776Y325868D01*
X940750Y325888D01*
G03X939333Y326370I-1418J-1844D01*
G01X939331D01*
G03X937005Y324081I0J-2326D01*
G01Y324080D01*
G02X936925Y323924I-200J4D01*
G01X936634Y323706D01*
X936542Y323689D01*
X936498Y323702D01*
G03X935875Y323786I-620J-2242D01*
G01X933925D01*
G03X932600Y323372I0J-2326D01*
G02X932486Y323336I-114J164D01*
G01X930740D01*
G03X929095Y322655I0J-2327D01*
G01X927635Y321195D01*
G02X927493Y321136I-142J141D01*
G01X925914D01*
G02X925800Y321172I0J200D01*
G03X924475Y321586I-1325J-1912D01*
G01X922525D01*
G03X921200Y321172I0J-2326D01*
G02X921086Y321136I-114J164D01*
G01X915814D01*
G02X915700Y321172I0J200D01*
G03X914375Y321586I-1325J-1912D01*
G01X912425D01*
G03X911100Y321172I0J-2326D01*
G02X910986Y321136I-114J164D01*
G01X909407D01*
G02X909265Y321195I0J200D01*
G01X898144Y332317D01*
G02X898103Y332540I142J141D01*
G01X898281Y332938D01*
X898387Y333002D01*
X898449Y332998D01*
G03X898533Y332996I78J1500D01*
G03X897031Y334498I0J1502D01*
G03X897033Y334414I1502J-6D01*
G01X897037Y334352D01*
X896973Y334246D01*
X896575Y334068D01*
G02X896352Y334109I-82J183D01*
G01X891138Y339322D01*
G02X891095Y339541I141J141D01*
G02X891279Y339664I185J-77D01*
G01X906260D01*
G03X907905Y340345I0J2327D01*
G01X919065Y351505D01*
G02X919207Y351564I142J-141D01*
G01X921839D01*
G02X922020Y351450I0J-200D01*
G01X922175Y351122D01*
G02X922149Y350910I-181J-85D01*
G03X921809Y349959I1162J-952D01*
G03X924813I1502J0D01*
G03X924473Y350910I-1502J-1D01*
G02X924447Y351122I155J127D01*
G01X924602Y351450D01*
G02X924783Y351564I181J-86D01*
G01X927293D01*
G02X927435Y351505I0J-200D01*
G01X930395Y348545D01*
G03X932040Y347864I1645J1646D01*
G01X936805D01*
G02X936973Y347773I0J-200D01*
G01X937184Y347449D01*
X937192Y347349D01*
X937171Y347302D01*
G03X936974Y346367I2129J-937D01*
G01Y346363D01*
G03X939300Y344036I2327J0D01*
G03X940719Y344519I0J2326D01*
G01X940744Y344539D01*
X940807Y344560D01*
X941193D01*
X941256Y344539D01*
X941281Y344519D01*
G03X942700Y344036I1419J1843D01*
G03X945026Y346361I0J2326D01*
G01Y346363D01*
G03X944345Y348008I-2327J0D01*
G01X943940Y348413D01*
G02X943882Y348555I142J141D01*
G01Y349845D01*
G03X943200Y351490I-2327J-1D01*
G01X941745Y352945D01*
G03X940100Y353626I-1645J-1646D01*
G01X935650D01*
G02X935471Y353737I0J200D01*
G01X935310Y354058D01*
G02X935329Y354267I179J89D01*
G03X935630Y355168I-1201J902D01*
G03X934128Y356670I-1502J0D01*
G03X932639Y355362I0J-1502D01*
G01X932632Y355305D01*
X932560Y355217D01*
X932165Y355083D01*
G02X931959Y355131I-64J189D01*
G01X930445Y356645D01*
G03X928977Y357319I-1645J-1647D01*
G02X928795Y357489I16J199D01*
G03X925824Y357496I-1486J-221D01*
G02X925627Y357326I-198J30D01*
G01X923071D01*
G02X922874Y357496I1J200D01*
G03X919904I-1485J-229D01*
G02X919707Y357326I-198J30D01*
G01X917700D01*
G03X916055Y356645I0J-2327D01*
G01X904895Y345485D01*
G02X904753Y345426I-142J141D01*
G01X885347D01*
G02X885205Y345485I0J200D01*
G01X877545Y353145D01*
G03X875900Y353826I-1645J-1646D01*
G01X835847D01*
G02X835705Y353885I0J200D01*
G01X834845Y354745D01*
G03X833200Y355426I-1645J-1646D01*
G01X818227D01*
G02X818150Y355441I-1J200D01*
G01X797367Y364049D01*
G03X796477Y364226I-890J-2149D01*
G01X595347D01*
G02X595205Y364285I0J200D01*
G01X531345Y428145D01*
G03X529700Y428826I-1645J-1646D01*
G01X512447D01*
G02X512305Y428885I0J200D01*
G01X503456Y437734D01*
G02X503412Y437951I141J142D01*
G01X503553Y438293D01*
G02X503736Y438417I185J-76D01*
G01X503737D01*
G03X505231Y439919I-8J1502D01*
G03X503729Y441421I-1502J0D01*
G03X502227Y439927I0J-1502D01*
G01Y439926D01*
G02X502103Y439743I-200J2D01*
G01X501761Y439602D01*
G02X501544Y439646I-75J185D01*
G01X482385Y458805D01*
G02X482326Y458947I141J142D01*
G01Y467115D01*
G02X482487Y467311I200J0D01*
G03Y470257I-294J1473D01*
G02X482326Y470453I39J196D01*
G01Y471115D01*
G02X482487Y471311I200J0D01*
G03Y474257I-294J1473D01*
G02X482326Y474453I39J196D01*
G01Y475115D01*
G02X482487Y475311I200J0D01*
G03Y478257I-294J1473D01*
G02X482326Y478453I39J196D01*
G01Y520300D01*
G03X481645Y521945I-2327J0D01*
G01X480685Y522905D01*
G02X480626Y523047I141J142D01*
G01Y552753D01*
G02X480685Y552895I200J0D01*
G01X481545Y553755D01*
G03X482226Y555400I-1646J1645D01*
G01Y633953D01*
G02X482285Y634095I200J0D01*
G01X494305Y646115D01*
G02X494447Y646174I142J-141D01*
G01X538310D01*
G03X539600Y646565I-1J2326D01*
G01X544534Y649861D01*
G03X545391Y650906I-1293J1934D01*
G01X549454Y660714D01*
G02X549627Y660837I185J-77D01*
G01X549985Y660859D01*
G02X550171Y660759I13J-200D01*
G03X551475Y660002I1304J745D01*
G03Y663006I0J1502D01*
G01X551474D01*
G03X551079Y662953I0J-1502D01*
G01X551024Y662938D01*
X550915Y662970D01*
X550639Y663283D01*
G02X550605Y663492I151J132D01*
G01X555649Y675672D01*
G03X555826Y676562I-2149J890D01*
G01Y752653D01*
G02X555885Y752795I200J0D01*
G01X558745Y755655D01*
G03X559426Y757300I-1646J1645D01*
G01Y769300D01*
G03X558745Y770945I-2327J0D01*
G01X550409Y779282D01*
G02X550350Y779424I141J142D01*
G01Y779449D01*
X550380Y779521D01*
X550813Y779955D01*
G03X551494Y781600I-1646J1645D01*
G03X549168Y783926I-2326J0D01*
G03X547657Y783369I0J-2328D01*
G02X547528Y783321I-130J152D01*
G01X547408D01*
G02X547279Y783369I1J200D01*
G03X545768Y783926I-1511J-1771D01*
G03X543442Y781600I0J-2326D01*
G03X544123Y779955I2327J0D01*
G01X544528Y779550D01*
G02X544586Y779408I-142J-141D01*
G01Y777917D01*
G03X545268Y776272I2327J1D01*
G01X553605Y767935D01*
G02X553664Y767793I-141J-142D01*
G01Y758807D01*
G02X553605Y758665I-200J0D01*
G01X550745Y755805D01*
G03X550064Y754160I1646J-1645D01*
G01Y677286D01*
G02X550049Y677209I-200J-1D01*
G01X540489Y654130D01*
G02X540416Y654040I-185J76D01*
G01X537315Y651970D01*
G02X537204Y651936I-112J166D01*
G01X492940D01*
G03X491295Y651255I0J-2327D01*
G01X477145Y637105D01*
G03X476464Y635460I1646J-1645D01*
G01Y556907D01*
G02X476405Y556765I-200J0D01*
G01X475545Y555905D01*
G03X474864Y554260I1646J-1645D01*
G01Y521540D01*
G03X475545Y519895I2327J0D01*
G01X476505Y518935D01*
G02X476564Y518793I-141J-142D01*
G01Y493994D01*
G02X476440Y493809I-200J0D01*
G01X476384Y493785D01*
X476266Y493809D01*
X470041Y500034D01*
G02X469992Y500114I141J142D01*
G01Y500115D01*
G03X468558Y501171I-1434J-446D01*
G03X467056Y499669I0J-1502D01*
G03X468111Y498235I1502J0D01*
G01X468113D01*
G02X468193Y498186I-62J-190D01*
G01X468548Y497831D01*
G02X468597Y497627I-141J-142D01*
G01X468469Y497235D01*
X468383Y497162D01*
X468327Y497153D01*
G03X467056Y495669I231J-1484D01*
G03X468558Y494167I1502J0D01*
G03X470042Y495438I0J1502D01*
G01X470051Y495494D01*
X470124Y495580D01*
X470516Y495708D01*
G02X470720Y495659I62J-190D01*
G01X474335Y492045D01*
G02X474394Y491903I-141J-142D01*
G01Y477381D01*
G02X474322Y477228I-200J1D01*
G01X474086Y477031D01*
G02X473924Y476987I-129J153D01*
G01X473923D01*
G03X473658Y477011I-267J-1478D01*
G03Y474007I0J-1502D01*
G03X473922Y474031I-3J1502D01*
G01X473924D01*
X473968Y474039D01*
X474052Y474016D01*
X474322Y473790D01*
G02X474394Y473637I-128J-154D01*
G01Y472381D01*
G02X474322Y472228I-200J1D01*
G01X474086Y472031D01*
G02X473924Y471987I-129J153D01*
G01X473923D01*
G03X473658Y472011I-267J-1478D01*
G03Y469007I0J-1502D01*
G03X473922Y469031I-3J1502D01*
G01X473924D01*
X473968Y469039D01*
X474052Y469016D01*
X474322Y468790D01*
G02X474394Y468637I-128J-154D01*
G01Y445683D01*
G03X474776Y444761I1306J1D01*
G01X480002Y439535D01*
G02X480051Y439455I-141J-142D01*
G01Y439454D01*
G03X481485Y438398I1434J446D01*
G03X482987Y439900I0J1502D01*
G03X481932Y441334I-1502J0D01*
G01X481930D01*
G02X481850Y441383I62J190D01*
G01X477065Y446167D01*
G02X477006Y446309I141J142D01*
G01Y455551D01*
G02X477129Y455735I200J-1D01*
G02X477348Y455692I78J-184D01*
G01X492149Y440891D01*
G02X492181Y440650I-141J-141D01*
G03X491983Y439904I1304J-745D01*
G01Y439903D01*
G03X493485Y438401I1502J0D01*
G01X493486D01*
G03X494232Y438599I1J1502D01*
G02X494473Y438567I100J-173D01*
G01X509295Y423745D01*
G03X510940Y423064I1645J1646D01*
G01X528193D01*
G02X528335Y423005I0J-200D01*
G01X592195Y359145D01*
G03X593840Y358464I1645J1646D01*
G01X711289D01*
G02X711473Y358344I1J-200D01*
G01X711620Y358009D01*
G02X711585Y357794I-183J-81D01*
G01X711584Y357793D01*
G03X711190Y356779I1108J-1014D01*
G03X714194I1502J0D01*
G03X713800Y357793I-1502J0D01*
G01X713799Y357794D01*
G02X713764Y358009I148J134D01*
G01X713911Y358344D01*
G02X714095Y358464I183J-80D01*
G01X793903D01*
G02X794081Y358355I0J-200D01*
G01X794243Y358038D01*
G02X794228Y357830I-178J-92D01*
G01X794227Y357829D01*
G03X793943Y356950I1218J-879D01*
G03X796947I1502J0D01*
G03X796902Y357314I-1502J-1D01*
G01X796888Y357369D01*
X796922Y357476D01*
X797237Y357747D01*
G02X797444Y357780I130J-152D01*
G01X816613Y349841D01*
G03X817503Y349664I890J2149D01*
G01X821149D01*
G02X821329Y349550I-1J-200D01*
G01X821510Y349171D01*
X821496Y349057D01*
X821459Y349012D01*
G03X821124Y348066I1168J-946D01*
G03X824128I1502J0D01*
G03X823793Y349012I-1503J0D01*
G01X823756Y349057D01*
X823742Y349171D01*
X823923Y349550D01*
G02X824103Y349664I181J-86D01*
G01X831693D01*
G02X831835Y349605I0J-200D01*
G01X832695Y348745D01*
G03X834340Y348064I1645J1646D01*
G01X874393D01*
G02X874535Y348005I0J-200D01*
G01X881162Y341378D01*
G02X881205Y341159I-141J-141D01*
G02X881021Y341036I-185J77D01*
G01X875552D01*
G02X875356Y341196I0J200D01*
G03X872414I-1471J-304D01*
G02X872218Y341036I-196J40D01*
G01X871748D01*
G02X871563Y341160I0J200D01*
G01X871400Y341559D01*
X871424Y341678D01*
X871467Y341721D01*
G03X871915Y342791I-1054J1070D01*
G03X868911I-1502J0D01*
G03X869359Y341721I1502J0D01*
G01X869402Y341678D01*
X869426Y341559D01*
X869263Y341160D01*
G02X869078Y341036I-185J76D01*
G01X866340D01*
G03X864695Y340355I0J-2327D01*
G01X864035Y339695D01*
G02X863893Y339636I-142J141D01*
G01X847614D01*
G02X847500Y339672I0J200D01*
G03X846175Y340086I-1325J-1912D01*
G01X844223D01*
G03X842901Y339673I1J-2326D01*
G02X842787Y339638I-113J165D01*
G01X842749D01*
G03X841377Y340086I-1373J-1878D01*
G01X839423D01*
G03X838101Y339673I1J-2326D01*
G02X837987Y339638I-113J165D01*
G01X837949D01*
G03X836577Y340086I-1373J-1878D01*
G01X834623D01*
G03X833301Y339673I1J-2326D01*
G02X833187Y339638I-113J165D01*
G01X833149D01*
G03X831777Y340086I-1373J-1878D01*
G01X829825D01*
G03X828500Y339672I0J-2326D01*
G02X828386Y339636I-114J164D01*
G01X814207D01*
G02X814065Y339695I0J200D01*
G01X809005Y344755D01*
G03X807360Y345436I-1645J-1646D01*
G01X770807D01*
G02X770665Y345495I0J200D01*
G01X768605Y347555D01*
G03X767651Y348132I-1646J-1644D01*
G02X767590Y348163I59J191D01*
G03X766210Y348626I-1381J-1829D01*
G01X577868D01*
G03X576590Y348236I1J-2292D01*
G01X576540D01*
G03X574895Y347555I0J-2327D01*
G01X571187Y343847D01*
G02X571045Y343788I-142J141D01*
G01X564237D01*
G02X564129Y343820I0J200D01*
G03X562876Y344186I-1253J-1960D01*
G01X560922D01*
G03X559671Y343820I2J-2326D01*
G01X559647Y343804D01*
X559592Y343788D01*
X559408D01*
X559353Y343804D01*
X559329Y343820D01*
G03X558078Y344186I-1253J-1960D01*
G01X556122D01*
G03X554871Y343820I2J-2326D01*
G01X554847Y343804D01*
X554792Y343788D01*
X554608D01*
X554553Y343804D01*
X554529Y343820D01*
G03X553278Y344186I-1253J-1960D01*
G01X553062D01*
G02X552883Y344296I0J200D01*
G01X552697Y344668D01*
X552706Y344780D01*
X552740Y344825D01*
G03X553038Y345723I-1204J898D01*
G03X550034I-1502J0D01*
G03X550495Y344640I1503J0D01*
G02X550554Y344461I-138J-145D01*
G01X550488Y344084D01*
X550427Y344006D01*
X550380Y343986D01*
G03X550071Y343820I943J-2127D01*
G02X549963Y343788I-108J168D01*
G01X548937D01*
G02X548829Y343820I0J200D01*
G03X547576Y344186I-1253J-1960D01*
G01X545625D01*
G03X544300Y343772I0J-2326D01*
G02X544186Y343736I-114J164D01*
G01X530207D01*
G02X530065Y343795I0J200D01*
G01X524295Y349565D01*
G02X524236Y349707I141J142D01*
G01Y352432D01*
G02X524409Y352631I200J1D01*
G03Y355607I-203J1488D01*
G02X524236Y355806I27J198D01*
G01Y375960D01*
G03X523555Y377605I-2327J0D01*
G01X490982Y410178D01*
G02X490934Y410382I142J141D01*
G01X491063Y410775D01*
X491149Y410848D01*
X491206Y410856D01*
G03X492487Y412342I-221J1486D01*
G03X490985Y413844I-1502J0D01*
G03X489499Y412563I0J-1502D01*
G01X489491Y412506D01*
X489418Y412420D01*
X489025Y412291D01*
G02X488821Y412339I-63J190D01*
G01X483797Y417363D01*
G02X483773Y417617I141J141D01*
G03X484034Y418464I-1242J846D01*
G03X482532Y419966I-1502J0D01*
G03X482436Y419963I-1J-1502D01*
G01Y426860D01*
G03X481755Y428505I-2327J0D01*
G01X442751Y467509D01*
X442722Y467563D01*
X442717Y467593D01*
G03X442073Y468824I-2289J-414D01*
G01X440693Y470204D01*
G03X439464Y470848I-1645J-1645D01*
G02X439358Y470903I35J197D01*
G01X439332Y470929D01*
G03X438678Y472219I-2299J-355D01*
G01X437298Y473599D01*
G03X436069Y474243I-1645J-1645D01*
G02X435963Y474298I35J197D01*
G01X435937Y474324D01*
G03X435283Y475614I-2299J-355D01*
G01X433903Y476994D01*
G03X432674Y477638I-1645J-1645D01*
G02X432568Y477693I35J197D01*
G01X432542Y477719D01*
G03X431888Y479008I-2299J-356D01*
G01X430508Y480388D01*
G03X429278Y481032I-1645J-1645D01*
G01X429248Y481037D01*
X429194Y481066D01*
X423805Y486455D01*
G03X422160Y487136I-1645J-1646D01*
G01X413807D01*
G02X413665Y487195I0J200D01*
G01X406195Y494665D01*
G02X406136Y494807I141J142D01*
G01Y656760D01*
G03X405455Y658405I-2327J0D01*
G01X375695Y688165D01*
G02X375636Y688307I141J142D01*
G01Y733760D01*
G03X374955Y735405I-2327J0D01*
G01X362195Y748165D01*
G02X362136Y748307I141J142D01*
G01Y764286D01*
G02X362172Y764400I200J0D01*
G03X362586Y765725I-1912J1325D01*
G01Y767677D01*
G03X362173Y768999I-2326J-1D01*
G02X362138Y769113I165J113D01*
G01Y769151D01*
G03X362586Y770523I-1878J1373D01*
G01Y772477D01*
G03X362173Y773799I-2326J-1D01*
G02X362138Y773913I165J113D01*
G01Y773951D01*
G03X362586Y775323I-1878J1373D01*
G01Y777277D01*
G03X362173Y778599I-2326J-1D01*
G02X362138Y778713I165J113D01*
G01Y778751D01*
G03X362586Y780123I-1878J1373D01*
G01Y782075D01*
G03X362172Y783400I-2326J0D01*
G02X362136Y783514I164J114D01*
G01Y787393D01*
G02X362195Y787535I200J0D01*
G01X368365Y793705D01*
G02X368507Y793764I142J-141D01*
G01X386364D01*
G02X386521Y793688I0J-200D01*
G01X386744Y793404D01*
X386764Y793314D01*
X386753Y793270D01*
G03X386688Y792725I2262J-546D01*
G03X389015Y790398I2327J0D01*
G03X390526Y790956I-1J2327D01*
G02X390656Y791004I130J-152D01*
G01X390774D01*
G02X390904Y790956I0J-200D01*
G03X392415Y790398I1512J1769D01*
G03X394742Y792725I0J2327D01*
G03X394060Y794370I-2327J-1D01*
G01X393655Y794775D01*
G02X393596Y794917I141J142D01*
G01Y795250D01*
G03X392915Y796895I-2327J0D01*
G01X390965Y798845D01*
G03X389320Y799526I-1645J-1646D01*
G01X367000D01*
G03X365355Y798845I0J-2327D01*
G01X357055Y790545D01*
G03X356374Y788900I1646J-1645D01*
G01Y749997D01*
G02X356182Y749797I-200J0D01*
G02X355974Y749979I-9J200D01*
G01X345197Y873156D01*
G02Y873190I199J17D01*
G01X354499Y979785D01*
G02X354531Y979877I199J-18D01*
G01X356565Y982964D01*
X356581Y982979D01*
X356816Y983214D01*
G02X356923Y983268I139J-143D01*
G02X356956Y983271I35J-197D01*
G01X373953D01*
G02X374008Y983263I-1J-200D01*
G01X374033Y983256D01*
X374057Y983241D01*
G03X374160Y983212I104J171D01*
G01X402459D01*
G02X402594Y983159I-1J-200D01*
G01X402681Y983079D01*
X402793Y982976D01*
G02X402838Y982917I-134J-149D01*
G01X402854Y982884D01*
X402857Y982846D01*
G03X404354Y981468I1497J124D01*
G03X405381Y981874I0J1502D01*
G01X405382Y981875D01*
G02X405452Y981917I136J-147D01*
G02X405518Y981928I65J-189D01*
G01X405823D01*
G02X405877Y981921I2J-200D01*
G01X405927Y981874D01*
G03X407981I1027J1096D01*
G01X407982Y981875D01*
G02X408052Y981917I136J-147D01*
G02X408118Y981928I65J-189D01*
G01X408423D01*
G02X408477Y981921I2J-200D01*
G01X408527Y981874D01*
G03X409554Y981468I1027J1096D01*
G03X409754Y981481I3J1502D01*
G03X411051Y982844I-200J1489D01*
G01X411055Y982883D01*
X411070Y982915D01*
G02X411115Y982975I180J-88D01*
G01X411239Y983089D01*
X411241Y983091D01*
X411313Y983158D01*
G02X411449Y983212I137J-146D01*
G01X502668D01*
G02X502855Y983083I0J-200D01*
G01X502988Y982734D01*
G02X502934Y982513I-187J-71D01*
G03X502431Y981392I998J-1121D01*
G03X505435I1502J0D01*
G03X504932Y982513I-1501J0D01*
G02X504878Y982734I133J150D01*
G01X505011Y983083D01*
G02X505198Y983212I187J-71D01*
G01X520783D01*
G03X520925Y983271I0J200D01*
G01X536065Y998411D01*
G03X536124Y998553I-141J142D01*
G01Y1001770D01*
Y1001772D01*
X536123Y1001845D01*
G02X536132Y1001908I200J4D01*
G02X536141Y1001931I191J-61D01*
G01X536159Y1001971D01*
X536183Y1001992D01*
Y1023182D01*
G02X536186Y1023215I200J-2D01*
G02X536240Y1023322I197J-32D01*
G01X544808Y1031890D01*
G03X544867Y1032032I-141J142D01*
G01Y1055361D01*
G02X544870Y1055394I200J-2D01*
G02X544924Y1055501I197J-32D01*
G01X559687Y1070264D01*
G03X559746Y1070406I-141J142D01*
G01Y1102911D01*
G02X559749Y1102944I200J-2D01*
G02X559803Y1103051I197J-32D01*
G01X561307Y1104555D01*
G02X561414Y1104609I139J-143D01*
G02X561447Y1104612I35J-197D01*
G01X577925D01*
G03X578067Y1104671I0J200D01*
G01X580844Y1107448D01*
G03X580903Y1107590I-141J142D01*
G01Y1112924D01*
X580906Y1112941D01*
X580907Y1112952D01*
G02X580941Y1113040I198J-26D01*
G01X580981Y1113080D01*
G02X581010Y1113104I141J-141D01*
G01X581081Y1113152D01*
X581083D01*
X581268Y1113280D01*
G02X581394Y1113307I103J-172D01*
G01X581398D01*
X581439Y1113302D01*
X581463Y1113293D01*
G03X582010Y1113189I549J1398D01*
G01X582103D01*
G03X582131Y1113191I0J200D01*
G01X582186Y1113199D01*
X582189D01*
G03X583514Y1114691I-178J1492D01*
G03X582929Y1115881I-1503J0D01*
G01X582918Y1115889D01*
X582891Y1115916D01*
X582880Y1115929D01*
G02X582837Y1116045I157J124D01*
G01X582835Y1116208D01*
X582833Y1116358D01*
Y1116364D01*
G02X582902Y1116515I200J0D01*
G01X582916Y1116527D01*
X582919Y1116529D01*
X582920Y1116530D01*
G03X583469Y1117691I-953J1161D01*
G03X581967Y1119193I-1502J0D01*
G01X581964D01*
G03X581441Y1119099I0J-1502D01*
G02X581347Y1119088I-70J187D01*
G01X581298Y1119094D01*
X580988Y1119310D01*
G02X580906Y1119439I115J163D01*
G01X580903Y1119453D01*
Y1125524D01*
X580906Y1125541D01*
X580907Y1125552D01*
G02X580941Y1125640I198J-26D01*
G01X580981Y1125680D01*
G02X581010Y1125704I141J-141D01*
G01X581081Y1125752D01*
X581083D01*
X581268Y1125880D01*
G02X581394Y1125907I103J-172D01*
G01X581398D01*
X581439Y1125902D01*
X581463Y1125893D01*
G03X582010Y1125789I549J1398D01*
G01X582103D01*
G03X582131Y1125791I0J200D01*
G01X582186Y1125799D01*
X582189D01*
G03X583514Y1127291I-178J1492D01*
G03X582929Y1128481I-1503J0D01*
G01X582918Y1128489D01*
X582891Y1128516D01*
X582880Y1128529D01*
G02X582837Y1128645I157J124D01*
G01X582835Y1128808D01*
X582833Y1128958D01*
Y1128964D01*
G02X582902Y1129115I200J0D01*
G01X582916Y1129127D01*
X582919Y1129129D01*
X582920Y1129130D01*
G03X583469Y1130291I-953J1161D01*
G03X581967Y1131793I-1502J0D01*
G01X581964D01*
G03X581441Y1131699I0J-1502D01*
G02X581347Y1131688I-70J187D01*
G01X581298Y1131694D01*
X580988Y1131910D01*
G02X580906Y1132039I115J163D01*
G01X580903Y1132053D01*
Y1138124D01*
X580906Y1138141D01*
X580907Y1138152D01*
G02X580941Y1138240I198J-26D01*
G01X580981Y1138280D01*
G02X581010Y1138304I141J-141D01*
G01X581081Y1138352D01*
X581083D01*
X581268Y1138480D01*
G02X581394Y1138507I103J-172D01*
G01X581398D01*
X581439Y1138502D01*
X581463Y1138493D01*
G03X582010Y1138389I549J1398D01*
G01X582103D01*
G03X582131Y1138391I0J200D01*
G01X582186Y1138399D01*
X582189D01*
G03X583514Y1139891I-178J1492D01*
G03X582929Y1141081I-1503J0D01*
G01X582918Y1141089D01*
X582891Y1141116D01*
X582880Y1141129D01*
G02X582837Y1141245I157J124D01*
G01X582835Y1141408D01*
X582833Y1141558D01*
Y1141564D01*
G02X582902Y1141715I200J0D01*
G01X582916Y1141727D01*
X582919Y1141729D01*
X582920Y1141730D01*
G03X583469Y1142891I-953J1161D01*
G03X581967Y1144393I-1502J0D01*
G01X581964D01*
G03X581441Y1144299I0J-1502D01*
G02X581347Y1144288I-70J187D01*
G01X581298Y1144294D01*
X580988Y1144510D01*
G02X580906Y1144639I115J163D01*
G01X580903Y1144653D01*
Y1150724D01*
X580906Y1150741D01*
X580907Y1150752D01*
G02X580941Y1150840I198J-26D01*
G01X580981Y1150880D01*
G02X581010Y1150904I141J-141D01*
G01X581081Y1150952D01*
X581083D01*
X581268Y1151080D01*
G02X581394Y1151107I103J-172D01*
G01X581398D01*
X581439Y1151102D01*
X581463Y1151093D01*
G03X582010Y1150989I549J1398D01*
G01X582103D01*
G03X582131Y1150991I0J200D01*
G01X582186Y1150999D01*
X582189D01*
G03X583514Y1152491I-178J1492D01*
G03X582929Y1153681I-1503J0D01*
G01X582918Y1153689D01*
X582891Y1153716D01*
X582880Y1153729D01*
G02X582837Y1153845I157J124D01*
G01X582835Y1154008D01*
X582833Y1154158D01*
Y1154164D01*
G02X582902Y1154315I200J0D01*
G01X582916Y1154327D01*
X582919Y1154329D01*
X582920Y1154330D01*
G03X583469Y1155491I-953J1161D01*
G03X581967Y1156993I-1502J0D01*
G01X581964D01*
G03X581441Y1156899I0J-1502D01*
G02X581347Y1156888I-70J187D01*
G01X581298Y1156894D01*
X580988Y1157110D01*
G02X580906Y1157239I115J163D01*
G01X580903Y1157253D01*
Y1163324D01*
X580906Y1163341D01*
X580907Y1163352D01*
G02X580941Y1163440I198J-26D01*
G01X580981Y1163480D01*
G02X581010Y1163504I141J-141D01*
G01X581081Y1163552D01*
X581083D01*
X581268Y1163680D01*
G02X581394Y1163707I103J-172D01*
G01X581398D01*
X581439Y1163702D01*
X581463Y1163693D01*
G03X582010Y1163589I549J1398D01*
G01X582103D01*
G03X582131Y1163591I0J200D01*
G01X582186Y1163599D01*
X582189D01*
G03X583514Y1165091I-178J1492D01*
G03X582929Y1166281I-1503J0D01*
G01X582918Y1166289D01*
X582891Y1166316D01*
X582880Y1166329D01*
G02X582837Y1166445I157J124D01*
G01X582835Y1166608D01*
X582833Y1166758D01*
Y1166764D01*
G02X582902Y1166915I200J0D01*
G01X582916Y1166927D01*
X582919Y1166929D01*
X582920Y1166930D01*
G03X583469Y1168091I-953J1161D01*
G03X581967Y1169593I-1502J0D01*
G01X581964D01*
G03X581441Y1169499I0J-1502D01*
G02X581347Y1169488I-70J187D01*
G01X581298Y1169494D01*
X580988Y1169710D01*
G02X580906Y1169839I115J163D01*
G01X580903Y1169853D01*
Y1175924D01*
X580906Y1175941D01*
X580907Y1175952D01*
G02X580941Y1176040I198J-26D01*
G01X580981Y1176080D01*
G02X581010Y1176104I141J-141D01*
G01X581081Y1176152D01*
X581083D01*
X581268Y1176280D01*
G02X581394Y1176307I103J-172D01*
G01X581398D01*
X581439Y1176302D01*
X581463Y1176293D01*
G03X582010Y1176189I549J1398D01*
G01X582103D01*
G03X582131Y1176191I0J200D01*
G01X582186Y1176199D01*
X582189D01*
G03X583514Y1177691I-178J1492D01*
G03X582929Y1178881I-1503J0D01*
G01X582918Y1178889D01*
X582891Y1178916D01*
X582880Y1178929D01*
G02X582837Y1179045I157J124D01*
G01X582835Y1179208D01*
X582833Y1179358D01*
Y1179364D01*
G02X582902Y1179515I200J0D01*
G01X582916Y1179527D01*
X582920Y1179530D01*
G03X583443Y1180413I-953J1161D01*
G01X583450Y1180451D01*
X583514Y1180551D01*
G02X583572Y1180610I169J-108D01*
G01X583820Y1180774D01*
X583867Y1180780D01*
X583905Y1180785D01*
X585886Y1180288D01*
G02X585920Y1180274I-59J-191D01*
G01X585943Y1180262D01*
X585962Y1180246D01*
X586027Y1180189D01*
G02X586056Y1180158I-131J-151D01*
G01X586069Y1180140D01*
X586078Y1180117D01*
G03X587467Y1179189I1389J576D01*
G03X588452Y1179557I0J1502D01*
G01X588466Y1179569D01*
X588480Y1179577D01*
G02X588536Y1179600I103J-171D01*
G02X588632I48J-194D01*
G01X589655Y1179345D01*
G03X590582Y1179228I947J3776D01*
G01X590595D01*
X590634Y1179223D01*
X590642Y1179222D01*
G03X590819Y1179195I315J1469D01*
G01X590824D01*
X590864Y1179190D01*
G03X590884Y1179189I20J199D01*
G01X590961D01*
G03X591278Y1179223I-1J1502D01*
G01X591287Y1179225D01*
X591325Y1179230D01*
X596234D01*
G03X597632Y1179490I-1J3891D01*
G01X597650Y1179497D01*
X597706Y1179507D01*
G02X597741Y1179510I35J-197D01*
G01X598028D01*
G02X598228Y1179310I0J-200D01*
G01Y1169626D01*
G02X598225Y1169594I-200J3D01*
G01X598212Y1169530D01*
X598206Y1169514D01*
X598204Y1169510D01*
G03X598150Y1169351I1108J-465D01*
G01X598147Y1169339D01*
G03X598121Y1169187I1169J-278D01*
G03X598114Y1169052I1195J-130D01*
G01Y1160649D01*
G03X598132Y1160566I200J0D01*
G01X598210Y1160392D01*
G02X598228Y1160310I-182J-83D01*
G01Y1158343D01*
X598210Y1158303D01*
G03X598194Y1158266I1094J-495D01*
G01Y1158262D01*
X598183Y1158230D01*
G03X598114Y1157835I1132J-401D01*
G01Y1153169D01*
G03X598132Y1153086I200J0D01*
G01X598210Y1152912D01*
G02X598228Y1152830I-182J-83D01*
G01Y1150863D01*
X598210Y1150823D01*
G03X598194Y1150786I1094J-495D01*
G01Y1150782D01*
X598183Y1150750D01*
G03X598114Y1150355I1132J-401D01*
G01Y1149428D01*
G03X598132Y1149345I200J0D01*
G01X598210Y1149171D01*
G02X598228Y1149089I-182J-83D01*
G01Y1147122D01*
X598210Y1147082D01*
G03X598194Y1147045I1094J-495D01*
G01Y1147041D01*
X598183Y1147009D01*
G03X598114Y1146614I1132J-401D01*
G01Y1145688D01*
G03X598132Y1145605I200J0D01*
G01X598210Y1145431D01*
G02X598228Y1145349I-182J-83D01*
G01Y1143382D01*
X598210Y1143342D01*
G03X598194Y1143305I1094J-495D01*
G01Y1143301D01*
X598183Y1143269D01*
G03X598114Y1142874I1132J-401D01*
G01Y1141948D01*
G03X598132Y1141865I200J0D01*
G01X598210Y1141691D01*
G02X598228Y1141609I-182J-83D01*
G01Y1139642D01*
X598210Y1139602D01*
G03X598194Y1139565I1094J-495D01*
G01Y1139561D01*
X598183Y1139529D01*
G03X598114Y1139134I1132J-401D01*
G01Y1138208D01*
G03X598132Y1138125I200J0D01*
G01X598210Y1137951D01*
G02X598228Y1137869I-182J-83D01*
G01Y1135902D01*
X598210Y1135862D01*
G03X598194Y1135825I1094J-495D01*
G01Y1135821D01*
X598183Y1135789D01*
G03X598114Y1135394I1132J-401D01*
G01Y1134468D01*
G03X598132Y1134385I200J0D01*
G01X598210Y1134211D01*
G02X598228Y1134129I-182J-83D01*
G01Y1132162D01*
X598210Y1132122D01*
G03X598194Y1132085I1094J-495D01*
G01Y1132081D01*
X598183Y1132049D01*
G03X598114Y1131654I1132J-401D01*
G01Y1130728D01*
G03X598132Y1130645I200J0D01*
G01X598210Y1130471D01*
G02X598228Y1130389I-182J-83D01*
G01Y1128422D01*
X598210Y1128382D01*
G03X598194Y1128345I1094J-495D01*
G01Y1128341D01*
X598183Y1128309D01*
G03X598114Y1127914I1132J-401D01*
G01Y1126987D01*
G03X598132Y1126904I200J0D01*
G01X598210Y1126730D01*
G02X598228Y1126648I-182J-83D01*
G01Y1124681D01*
X598210Y1124641D01*
G03X598194Y1124604I1094J-495D01*
G01Y1124600D01*
X598183Y1124568D01*
G03X598114Y1124173I1132J-401D01*
G01Y1123247D01*
G03X598132Y1123164I200J0D01*
G01X598210Y1122990D01*
G02X598228Y1122908I-182J-83D01*
G01Y1120941D01*
X598210Y1120901D01*
G03X598194Y1120864I1094J-495D01*
G01Y1120860D01*
X598183Y1120828D01*
G03X598114Y1120433I1132J-401D01*
G01Y1119878D01*
X598123Y1119857D01*
X598125Y1119851D01*
G03X598127Y1119846I187J72D01*
G01X598141Y1119814D01*
X598204Y1119661D01*
Y1119660D01*
G03X598211Y1119644I1104J473D01*
G01X598228Y1119605D01*
Y1119316D01*
G03X598287Y1119174I200J0D01*
G01X598944Y1118517D01*
G02X599003Y1118367I-141J-142D01*
G01X599001Y1118353D01*
G03X599000Y1118345I1291J-165D01*
G01Y1118342D01*
X598998Y1118329D01*
G03X598993Y1118215I1297J-114D01*
G01Y1118204D01*
G03X600291Y1116906I1302J4D01*
G01X600297D01*
G03X600441Y1116914I0J1302D01*
G02X600604Y1116857I22J-199D01*
G01X602777Y1114684D01*
G02X602835Y1114534I-142J-141D01*
G01Y1114532D01*
G03X602833Y1114469I1200J-70D01*
G01Y1114467D01*
G03X604034Y1113266I1202J1D01*
G01X604037D01*
G03X604101Y1113268I-6J1202D01*
G02X604184Y1113255I11J-200D01*
G01X604220Y1113241D01*
X606517Y1110944D01*
G02X606555Y1110890I-142J-140D01*
G01X606578Y1110843D01*
X606576Y1110805D01*
G03X606574Y1110728I1200J-70D01*
G01Y1110727D01*
G03X607775Y1109526I1202J1D01*
G01X607785D01*
G03X607838Y1109528I-19J1202D01*
G01X607841D01*
X607882Y1109530D01*
X607924Y1109513D01*
G02X607992Y1109469I-72J-186D01*
G01X609300Y1108161D01*
G03X609442Y1108102I142J141D01*
G01X630928D01*
G02X631082Y1108029I0J-200D01*
G03X632086Y1107556I1004J829D01*
G03X632220Y1107563I-1J1302D01*
G01X632265Y1107568D01*
X632350Y1107538D01*
X632602Y1107285D01*
G02X632659Y1107123I-142J-141D01*
G03X632655Y1107074I1296J-130D01*
G03X632652Y1106988I1299J-88D01*
G01Y1103248D01*
G03X633955Y1101945I1303J0D01*
G01X633958D01*
G03X634194Y1101967I-2J1303D01*
G01X634196D01*
X634217Y1101971D01*
X634307Y1101943D01*
X634574Y1101689D01*
G02X634634Y1101521I-139J-144D01*
G01Y1101520D01*
G03X634625Y1101376I1193J-147D01*
G03X635827Y1102578I1202J0D01*
G03X635683Y1102569I3J-1202D01*
G01X635682D01*
G02X635514Y1102629I-24J199D01*
G01X635260Y1102896D01*
X635232Y1102986D01*
X635236Y1103008D01*
G03X635258Y1103245I-1281J238D01*
G01Y1103524D01*
G02X635324Y1103673I200J0D01*
G01X635578Y1103900D01*
X635658Y1103926D01*
G37*
G36*
G01X4539Y1256520D02*
X65631D01*
G02X65773Y1256461I0J-200D01*
G01X67076Y1255158D01*
G02X67135Y1255016I-141J-142D01*
G01Y1213141D01*
G02X67089Y1213013I-200J0D01*
G03Y1211095I1156J-959D01*
G02X67135Y1210967I-154J-128D01*
G01Y1192006D01*
G02X67119Y1191927I-200J-1D01*
G03X66029Y1186654I12212J-5274D01*
G03X67119Y1181381I13302J1D01*
G02X67135Y1181302I-184J-78D01*
G01Y1163136D01*
G02X67076Y1162994I-200J0D01*
G01X65016Y1160934D01*
G02X64874Y1160875I-142J141D01*
G01X5688D01*
G02X5546Y1160934I0J200D01*
G01X2441Y1164039D01*
G02X2382Y1164181I141J142D01*
G01Y1254363D01*
G02X2441Y1254505I200J0D01*
G01X4397Y1256461D01*
G02X4539Y1256520I142J-141D01*
G37*
G36*
G01X1081725Y1645992D02*
X1833071D01*
G02X1838945Y1640118I0J-5874D01*
G01Y1249999D01*
X1836948D01*
Y1640118D01*
G03X1833073Y1643994I-3876J0D01*
G01X1633526D01*
Y1644873D01*
X1578560D01*
Y1643994D01*
X1285912D01*
Y1644677D01*
X1232543D01*
Y1643994D01*
X1081724D01*
G03X1078854Y1642722I1J-3877D01*
G02X1070058Y1638822I-8797J7971D01*
G01X800966D01*
G02X792169Y1642722I0J11872D01*
G03X789299Y1643994I-2871J-2603D01*
G01X608951D01*
Y1644464D01*
X555228D01*
Y1643994D01*
X262776D01*
Y1644377D01*
X208818D01*
Y1643994D01*
X7874D01*
G03X3998Y1640118I0J-3876D01*
G01Y1529722D01*
X3918Y1529642D01*
X3998Y1529562D01*
Y1513090D01*
Y1244645D01*
X2000D01*
Y1640118D01*
G02X7874Y1645992I5874J0D01*
G01X789298D01*
G02X793649Y1644063I-1J-5873D01*
G03X800966Y1640819I7317J6631D01*
G01X1070058D01*
G03X1077374Y1644063I-1J9873D01*
G02X1081725Y1645992I4352J-3945D01*
G37*
G36*
G01X277688Y1485526D02*
X277638Y1485476D01*
G03X277579Y1485334I141J-142D01*
G01Y1456243D01*
G02X277557Y1456152I-200J0D01*
G02X277521Y1456102I-178J90D01*
G01X259352Y1437933D01*
G02X259322Y1437908I-142J140D01*
G01X249379Y1431264D01*
G02X249345Y1431245I-114J164D01*
G01X246180Y1429934D01*
G03X244907Y1429083I1504J-3627D01*
G01X237066Y1421242D01*
G03X236214Y1419969I2774J-2778D01*
G01X232512Y1411032D01*
G02X232469Y1410967I-185J76D01*
G01X217705Y1396203D01*
G03X217646Y1396061I141J-142D01*
G01Y1370975D01*
G02X217641Y1370931I-200J0D01*
G01X216816Y1367951D01*
X211167Y1347538D01*
X201680Y1313254D01*
G03X201619Y1312999I3752J-1032D01*
G01X195551Y1283451D01*
G02X195546Y1283433I-195J44D01*
G01X194999Y1281626D01*
G03X194830Y1280487I3757J-1139D01*
G01Y1279958D01*
G02X194826Y1279918I-200J0D01*
G01X193089Y1271460D01*
G03X193060Y1271303I3812J-785D01*
G03X193008Y1270672I3839J-634D01*
G03Y1270665I3891J-3D01*
G01Y1262301D01*
G03X193009Y1262192I3892J-19D01*
G01X193010Y1262178D01*
Y1260541D01*
G03X193223Y1259272I3891J1D01*
G01Y1259270D01*
G03X193228Y1259257I3634J1390D01*
G01X193230Y1259252D01*
G03X193234Y1259240I3693J1224D01*
G01X193237Y1259218D01*
X193241Y1259197D01*
G02X193242Y1259175I-199J-20D01*
G01Y1256074D01*
G02X193130Y1255894I-200J0D01*
G03Y1253554I569J-1170D01*
G01X193182Y1253529D01*
X193242Y1253432D01*
Y1252334D01*
G02X193130Y1252154I-200J0D01*
G03X192398Y1250984I569J-1170D01*
G01Y1250982D01*
G03X192405Y1250848I1302J1D01*
G01X192410Y1250803D01*
X192380Y1250718D01*
X192127Y1250466D01*
G02X191965Y1250409I-141J142D01*
G03X191691I-137J-1297D01*
G01X191683Y1250408D01*
X191682D01*
G03X191641Y1250402I168J-1291D01*
G01X191639D01*
G03X191429Y1250353I190J-1288D01*
G02X191191Y1250607I-47J195D01*
G03X191248Y1250984I-1231J379D01*
G03X188672I-1288J0D01*
G03X189959Y1249696I1288J0D01*
G01X189961D01*
G03X190094Y1249704I-11J1287D01*
G01X190096D01*
X190140Y1249709D01*
X190225Y1249678D01*
X190510Y1249392D01*
X190539Y1249306D01*
X190534Y1249261D01*
G03X190526Y1249115I1294J-144D01*
G01Y1245373D01*
G03X191828Y1244071I1302J0D01*
G03X191976Y1244079I4J1302D01*
G01X191977D01*
G02X192140Y1244022I22J-199D01*
G01X192394Y1243770D01*
X192425Y1243685D01*
X192420Y1243640D01*
G03X192412Y1243504I1280J-144D01*
G01Y1243502D01*
G03X193700Y1242215I1288J1D01*
G03X194988Y1243503I0J1288D01*
G03X194931Y1243880I-1288J-2D01*
G02X195171Y1244133I191J59D01*
G03X195376Y1244085I398J1240D01*
G01X195397Y1244082D01*
G02X195459Y1244053I-53J-193D01*
G01X195478Y1244038D01*
X195484Y1244033D01*
X195486Y1244031D01*
G03X195839Y1243748I2547J2815D01*
G01X195859Y1243734D01*
X195900Y1243686D01*
G02X195913Y1243670I-149J-134D01*
G01X195933Y1243640D01*
X195936Y1243635D01*
X195939Y1243629D01*
G03X196062Y1243409I3374J1742D01*
G03X196141Y1243283I3256J1953D01*
G02X196169Y1243217I-167J-110D01*
G03X197152Y1242233I1271J286D01*
G02X197218Y1242205I-44J-195D01*
G03X197625Y1241972I2086J3172D01*
G02X197717Y1241877I-90J-179D01*
G03X198031Y1241330I3464J1625D01*
G02X198058Y1241272I-165J-112D01*
G03X198509Y1240606I1251J362D01*
G03X198949Y1240382I800J1028D01*
G02X199008Y1240355I-53J-193D01*
G03X199754Y1239952I2180J3144D01*
G02X199879Y1239767I-75J-185D01*
G01Y1239763D01*
G03X200185Y1238925I1302J0D01*
G01X200155Y1238901D01*
G03X199947Y1238679I766J-926D01*
G03X199945Y1238676I166J-113D01*
G02X199941Y1238670I-168J108D01*
G03X199934Y1238661I154J-127D01*
G03X199928Y1238652I164J-116D01*
G01X199927Y1238650D01*
X199657Y1238229D01*
G03X199626Y1238133I169J-107D01*
G01X199611Y1237875D01*
Y1237873D01*
G02X199311Y1237592I-300J20D01*
G02X199010Y1237893I0J301D01*
G01Y1237931D01*
G03X198260Y1239043I-1201J-1D01*
G02X198068Y1239129I1046J2592D01*
G01X198059Y1239138D01*
X197920Y1239207D01*
X197918Y1239209D01*
G03X197407Y1239341I-549J-1069D01*
G01X197367Y1239342D01*
X197333Y1239357D01*
G02X197273Y1239398I81J183D01*
G01X197077Y1239594D01*
G02X197035Y1239656I142J141D01*
G01X197021Y1239688D01*
X197019Y1239728D01*
Y1239729D01*
G03X197006Y1239870I-1200J-40D01*
G01X196968Y1240018D01*
G03X196885Y1240240I-1161J-308D01*
G01X196884Y1240243D01*
X196873Y1240266D01*
G02X196864Y1240283I2465J1316D01*
G01X196858Y1240295D01*
X196856Y1240301D01*
X196852Y1240308D01*
X196763Y1240472D01*
X196761Y1240475D01*
X196754Y1240489D01*
X196749Y1240497D01*
G03X196730Y1240522I-168J-108D01*
G01X196655Y1240605D01*
X196653Y1240607D01*
X196551Y1240723D01*
X196549Y1240725D01*
G03X196514Y1240757I-151J-130D01*
G01X196419Y1240822D01*
G02X196417Y1240824I138J140D01*
G02X196274Y1240933I1622J2277D01*
G02X196272Y1240935I140J142D01*
G02X196188Y1241008I1791J2145D01*
G01X196123Y1241067D01*
X196109Y1241076D01*
X196052Y1241126D01*
G03X196006Y1241156I-131J-151D01*
G01X195711Y1241294D01*
X195702Y1241298D01*
X195693Y1241301D01*
X195688Y1241303D01*
G03X195662Y1241310I-65J-189D01*
G01X195527Y1241335D01*
X195520Y1241336D01*
G02X195498Y1241341I56J295D01*
G01X195474Y1241347D01*
G02X195417Y1241381I73J186D01*
G01X195351Y1241442D01*
G03X195053Y1241641I-809J-889D01*
G01X195049Y1241643D01*
X195008Y1241663D01*
G03X194987Y1241672I-89J-179D01*
G01X194936Y1241690D01*
G03X193688Y1241406I-398J-1133D01*
G01X193277Y1240995D01*
X193237Y1240980D01*
G03X192483Y1240226I463J-1217D01*
G01X192468Y1240186D01*
X192117Y1239835D01*
G03X191981Y1239670I855J-843D01*
G01X191961Y1239639D01*
G03X191770Y1239031I1009J-651D01*
G01X191768Y1238945D01*
Y1238870D01*
G03X191843Y1238455I1202J3D01*
G01X191904Y1238289D01*
G03X191939Y1238229I188J69D01*
G01X192057Y1238090D01*
X192058Y1238089D01*
G02X192130Y1237895I-228J-195D01*
G01Y1237893D01*
G02X191902Y1237601I-301J0D01*
G01X191884Y1237597D01*
X191740Y1237563D01*
G03X191680Y1237538I46J-195D01*
G01X191389Y1237356D01*
G03X191336Y1237308I106J-170D01*
G01X191252Y1237198D01*
X191249Y1237195D01*
G03X191183Y1237106I931J-760D01*
G02X191181Y1237103I-168J110D01*
G01X191168Y1237085D01*
X191103Y1237043D01*
X190786Y1236985D01*
G02X190637Y1237016I-37J197D01*
G03X189960Y1237225I-677J-992D01*
G03Y1234821I0J-1202D01*
G01X189961D01*
G03X190749Y1235116I-1J1202D01*
G02X190807Y1235151I131J-151D01*
G01X190909Y1235191D01*
G02X191093Y1235071I1J-200D01*
G01Y1235070D01*
G03X191125Y1235011I189J65D01*
G01X191233Y1234872D01*
G03X191852Y1234458I945J743D01*
G01X191884Y1234450D01*
X191899Y1234446D01*
G02X191915Y1233864I-69J-293D01*
G01X191907Y1233862D01*
X191740Y1233823D01*
G03X191680Y1233798I46J-195D01*
G01X191389Y1233616D01*
G03X191336Y1233568I106J-170D01*
G01X191252Y1233458D01*
X191249Y1233455D01*
G03X191183Y1233366I931J-760D01*
G02X191181Y1233363I-168J110D01*
G01X191168Y1233345D01*
X191103Y1233303D01*
X190786Y1233245D01*
G02X190637Y1233276I-37J197D01*
G03X189960Y1233485I-677J-992D01*
G03Y1231081I0J-1202D01*
G01X189961D01*
G03X190749Y1231376I-1J1202D01*
G02X190807Y1231411I131J-151D01*
G01X190909Y1231451D01*
G02X191093Y1231331I1J-200D01*
G01Y1231330D01*
G03X191125Y1231271I189J65D01*
G01X191233Y1231132D01*
G03X191852Y1230718I945J743D01*
G01X191884Y1230710D01*
X191899Y1230706D01*
G02X191915Y1230124I-69J-293D01*
G01X191907Y1230122D01*
X191740Y1230083D01*
G03X191680Y1230058I46J-195D01*
G01X191389Y1229876D01*
G03X191336Y1229828I106J-170D01*
G01X191252Y1229718D01*
X191249Y1229715D01*
G03X190976Y1228953I929J-763D01*
G01Y1228130D01*
G03X191042Y1227743I1201J6D01*
G01X191051Y1227717D01*
G03X190526Y1226672I778J-1045D01*
G01Y1222931D01*
G03X190940Y1221980I1303J1D01*
G01X190969Y1221953D01*
X191036Y1221805D01*
G02X191030Y1221760I-200J4D01*
G01X191027Y1221746D01*
G03X190976Y1221401I1151J-346D01*
G01Y1220649D01*
G03X191033Y1220290I1201J7D01*
G01X191035Y1220284D01*
X191036Y1220280D01*
X191040Y1220267D01*
X191093Y1220109D01*
G03X191125Y1220050I189J65D01*
G01X191233Y1219911D01*
G03X191852Y1219497I945J743D01*
G01X191884Y1219489D01*
X191899Y1219485D01*
G02X191915Y1218903I-69J-293D01*
G01X191907Y1218901D01*
X191740Y1218862D01*
G03X191680Y1218837I46J-195D01*
G01X191389Y1218655D01*
G03X191336Y1218607I106J-170D01*
G01X191262Y1218510D01*
X191259Y1218506D01*
G03X191250Y1218495I926J-767D01*
G03X191248Y1218493I140J-142D01*
G03X191181Y1218402I933J-757D01*
G02X191177Y1218396I-168J108D01*
G01X191168Y1218383D01*
X191104Y1218343D01*
X190786Y1218284D01*
G02X190637Y1218315I-37J197D01*
G03X189960Y1218524I-677J-992D01*
G03Y1216120I0J-1202D01*
G03X190171Y1216139I-2J1202D01*
G01X190220Y1216148D01*
X190313Y1216118D01*
X190579Y1215849D01*
G02X190634Y1215672I-142J-141D01*
G03X190614Y1215452I1197J-220D01*
G01Y1215451D01*
G03X190634Y1215232I1215J1D01*
G02X190579Y1215055I-197J-36D01*
G01X190348Y1214821D01*
G02X190171Y1214765I-142J141D01*
G03X189960Y1214784I-213J-1183D01*
G03Y1212380I0J-1202D01*
G01X189961D01*
G03X190749Y1212675I-1J1202D01*
G02X190807Y1212710I131J-151D01*
G01X190909Y1212750D01*
G02X191093Y1212630I1J-200D01*
G01Y1212629D01*
G03X191125Y1212570I189J65D01*
G01X191233Y1212431D01*
G03X191852Y1212017I945J743D01*
G01X191884Y1212009D01*
X191899Y1212005D01*
G02X191915Y1211423I-69J-293D01*
G01X191907Y1211421D01*
X191740Y1211382D01*
G03X191680Y1211357I46J-195D01*
G01X191389Y1211175D01*
G03X191336Y1211127I106J-170D01*
G01X191262Y1211030D01*
X191259Y1211026D01*
G03X191250Y1211015I926J-767D01*
G03X191248Y1211013I140J-142D01*
G03X190976Y1210252I930J-761D01*
G01Y1209429D01*
G03X191033Y1209070I1201J7D01*
G01X191035Y1209064D01*
X191036Y1209060D01*
X191040Y1209047D01*
X191093Y1208889D01*
G03X191125Y1208830I189J65D01*
G01X191233Y1208691D01*
G03X191852Y1208277I945J743D01*
G01X191884Y1208269D01*
X191899Y1208265D01*
G02X191915Y1207683I-69J-293D01*
G01X191907Y1207681D01*
X191740Y1207642D01*
G03X191680Y1207617I46J-195D01*
G01X191389Y1207435D01*
G03X191336Y1207387I106J-170D01*
G01X191262Y1207290D01*
X191259Y1207286D01*
G03X191250Y1207275I926J-767D01*
G03X191248Y1207273I140J-142D01*
G03X190976Y1206512I930J-761D01*
G01Y1205689D01*
G03X191033Y1205330I1201J7D01*
G01X191035Y1205324D01*
X191036Y1205320D01*
X191040Y1205307D01*
X191093Y1205149D01*
G03X191125Y1205090I189J65D01*
G01X191233Y1204951D01*
G03X191852Y1204537I945J743D01*
G01X191884Y1204529D01*
X191899Y1204525D01*
G02X191915Y1203943I-69J-293D01*
G01X191907Y1203941D01*
X191740Y1203902D01*
G03X191680Y1203877I46J-195D01*
G01X191389Y1203695D01*
G03X191336Y1203647I106J-170D01*
G01X191262Y1203550D01*
X191259Y1203546D01*
G03X191250Y1203535I926J-767D01*
G03X191248Y1203533I140J-142D01*
G03X190976Y1202772I930J-761D01*
G01Y1201948D01*
G03X191033Y1201589I1201J7D01*
G01X191035Y1201583D01*
X191036Y1201579D01*
X191040Y1201566D01*
X191093Y1201408D01*
G03X191125Y1201349I189J65D01*
G01X191233Y1201210D01*
G03X191852Y1200796I945J743D01*
G01X191884Y1200788D01*
X191899Y1200784D01*
G02X191915Y1200202I-69J-293D01*
G01X191907Y1200200D01*
X191740Y1200161D01*
G03X191680Y1200136I46J-195D01*
G01X191389Y1199954D01*
G03X191336Y1199906I106J-170D01*
G01X191252Y1199796D01*
X191249Y1199793D01*
G03X190976Y1199031I929J-763D01*
G01Y1198208D01*
G03X191033Y1197849I1201J7D01*
G01X191035Y1197843D01*
X191036Y1197839D01*
X191040Y1197826D01*
X191093Y1197668D01*
G03X191125Y1197609I189J65D01*
G01X191233Y1197470D01*
G03X191852Y1197056I945J743D01*
G01X191884Y1197048D01*
X191899Y1197044D01*
G02X191915Y1196462I-69J-293D01*
G01X191907Y1196460D01*
X191740Y1196421D01*
G03X191680Y1196396I46J-195D01*
G01X191389Y1196214D01*
G03X191336Y1196166I106J-170D01*
G01X191252Y1196056D01*
X191249Y1196053D01*
G03X190976Y1195291I929J-763D01*
G01Y1194468D01*
G03X191037Y1194097I1201J7D01*
G01X191040Y1194087D01*
X191042Y1194081D01*
Y1194080D01*
G02X191043Y1194077I-190J-65D01*
G01X191048Y1194057D01*
G02X191050Y1193982I-196J-43D01*
G03X190585Y1193012I780J-970D01*
G01Y1193011D01*
G03X190999Y1192084I1245J0D01*
G02X191048Y1192016I-134J-148D01*
G01X191052Y1192007D01*
G02X191046Y1191960I-200J2D01*
G01X191034Y1191921D01*
G03X190976Y1191552I1144J-369D01*
G01Y1187188D01*
G02X190776Y1186988I-200J0D01*
G01X169206D01*
G02X169064Y1187047I0J200D01*
G01X168864Y1187250D01*
G02X168806Y1187390I142J141D01*
G01Y1187401D01*
G03X166232I-1287J0D01*
G01Y1187390D01*
G02X166174Y1187250I-200J1D01*
G01X165974Y1187047D01*
G02X165832Y1186988I-142J141D01*
G01X165466D01*
G02X165324Y1187047I0J200D01*
G01X165124Y1187250D01*
G02X165066Y1187390I142J141D01*
G01Y1187401D01*
G03X162492I-1287J0D01*
G01Y1187390D01*
G02X162434Y1187250I-200J1D01*
G01X162234Y1187047D01*
G02X162092Y1186988I-142J141D01*
G01X157986D01*
G02X157844Y1187047I0J200D01*
G01X157644Y1187250D01*
G02X157586Y1187390I142J141D01*
G01Y1187401D01*
G03X155012I-1287J0D01*
G01Y1187390D01*
G02X154954Y1187250I-200J1D01*
G01X154754Y1187047D01*
G02X154612Y1186988I-142J141D01*
G01X154246D01*
G02X154104Y1187047I0J200D01*
G01X153904Y1187250D01*
G02X153846Y1187390I142J141D01*
G01Y1187401D01*
G03X151272I-1287J0D01*
G01Y1187390D01*
G02X151214Y1187250I-200J1D01*
G01X151014Y1187047D01*
G02X150872Y1186988I-142J141D01*
G01X124228D01*
G02X124137Y1187010I0J200D01*
G02X124087Y1187046I90J178D01*
G01X116053Y1195080D01*
G03X115911Y1195139I-142J-141D01*
G01X103916D01*
G02X103825Y1195161I0J200D01*
G02X103775Y1195197I90J178D01*
G01X91897Y1207075D01*
G03X91755Y1207134I-142J-141D01*
G01X81183D01*
G02X81092Y1207156I0J200D01*
G02X81042Y1207192I90J178D01*
G01X70480Y1217754D01*
G02X70444Y1217804I142J140D01*
G02X70422Y1217895I178J91D01*
G01Y1222431D01*
G02X70488Y1222580I200J0D01*
G01X70709Y1222779D01*
G02X70863Y1222829I134J-149D01*
G01X70864D01*
G03X71018Y1222821I155J1494D01*
G01X71020D01*
G03Y1225825I0J1502D01*
G01X71018D01*
G03X70864Y1225817I1J-1502D01*
G01X70863D01*
G02X70709Y1225867I-20J199D01*
G01X70488Y1226066D01*
G02X70422Y1226215I134J149D01*
G01Y1226791D01*
G02X70488Y1226940I200J1D01*
G01X70739Y1227167D01*
X70819Y1227193D01*
X70861Y1227189D01*
G03X71006Y1227182I145J1495D01*
G03Y1230186I0J1502D01*
G03X70861Y1230179I0J-1502D01*
G01X70819Y1230175D01*
X70739Y1230201D01*
X70488Y1230428D01*
G02X70422Y1230577I134J148D01*
G01Y1247966D01*
X70423Y1247967D01*
Y1257177D01*
G03X70364Y1257319I-200J0D01*
G01X69854Y1257829D01*
G03X69712Y1257888I-142J-141D01*
G01X4530D01*
G03X4537Y1258036I-1495J145D01*
G03X3035Y1259538I-1502J0D01*
G03X2651Y1259488I0J-1502D01*
G02X2400Y1259681I-51J193D01*
G01Y1641717D01*
G02X2459Y1641859I200J0D01*
G01X6041Y1645441D01*
G02X6183Y1645500I142J-141D01*
G01X176217D01*
G02X176359Y1645441I0J-200D01*
G01X176939Y1644861D01*
G02X176998Y1644719I-141J-142D01*
G01Y1639443D01*
G02X176939Y1639301I-200J0D01*
G01X173204Y1635565D01*
G02X173062Y1635506I-142J141D01*
G01X120679D01*
G03X119049Y1634831I0J-2306D01*
G01X108251Y1624033D01*
G03X107576Y1622403I1631J-1630D01*
G01Y1622402D01*
G03X109882Y1620096I2306J0D01*
G01X109883D01*
G03X111513Y1620771I0J2306D01*
G01X120946Y1630204D01*
G02X120975Y1630206I28J-198D01*
G01X132736D01*
G02X132820Y1630187I-1J-200D01*
G01X132863Y1630083D01*
G02X132820Y1629864I-184J-78D01*
G01X127328Y1624373D01*
G02X127189Y1624314I-142J141D01*
G01X127188D01*
G03X125293Y1622402I17J-1912D01*
G03X127205Y1620490I1912J0D01*
G03X129117Y1622385I0J1912D01*
G01Y1622386D01*
G02X129176Y1622525I200J-3D01*
G01X136028Y1629377D01*
G02X136170Y1629436I142J-141D01*
G01X147874D01*
G02X148058Y1629313I0J-200D01*
G01X148104Y1629204D01*
X148099Y1629179D01*
X142925Y1624005D01*
G03X142262Y1622404I1603J-1602D01*
G01Y1622402D01*
G03X144528Y1620136I2266J0D01*
G01X144530D01*
G03X146131Y1620799I-1J2266D01*
G01X152021Y1626689D01*
G02X152123Y1626742I139J-143D01*
G02X152161Y1626746I40J-196D01*
G01X163921D01*
G02X164102Y1626630I0J-200D01*
G01X164105Y1626622D01*
G02X164117Y1626505I-184J-78D01*
G01X164111Y1626477D01*
X164084Y1626427D01*
X162029Y1624372D01*
G02X161962Y1624328I-141J142D01*
G01X161925Y1624313D01*
X161884Y1624314D01*
X161850D01*
G03X163762Y1622402I0J-1912D01*
G01Y1622436D01*
X163761Y1622477D01*
X163776Y1622514D01*
G02X163820Y1622581I186J-74D01*
G01X167091Y1625851D01*
X167199Y1625959D01*
G02X167339Y1626016I140J-143D01*
G01X175428D01*
G02X175570Y1625957I0J-200D01*
G01X175888Y1625639D01*
G02X175947Y1625497I-141J-142D01*
G01Y1622327D01*
G03X176006Y1622185I200J0D01*
G01X176092Y1622099D01*
G03X176234Y1622040I142J141D01*
G01X176502D01*
G02X176644Y1621981I0J-200D01*
G01X177001Y1621624D01*
X177017Y1621584D01*
G03X179173Y1620096I2156J818D01*
G01X179176D01*
G03X179586Y1620133I-1J2306D01*
G01X179604Y1620136D01*
X179777D01*
G02X179919Y1620077I0J-200D01*
G01X180092Y1619904D01*
G02X180151Y1619762I-141J-142D01*
G01Y1615139D01*
G02X180092Y1614997I-200J0D01*
G01X179175Y1614080D01*
X179122Y1614077D01*
G03X177261Y1612166I51J-1911D01*
G03X178992Y1610263I1912J0D01*
G02X179173Y1610063I-19J-199D01*
G01Y1609483D01*
G02X179114Y1609341I-200J0D01*
G01X178665Y1608892D01*
X178641Y1608884D01*
G03X177267Y1607201I532J-1836D01*
G03X177261Y1607048I1906J-151D01*
G03X179175Y1605136I1912J0D01*
G01X179207D01*
X179248Y1605137D01*
X179285Y1605122D01*
G02X179350Y1605080I-74J-186D01*
G01X180799Y1603630D01*
G02X180858Y1603488I-141J-142D01*
G01Y1600709D01*
G02X180799Y1600567I-200J0D01*
G01X178942Y1598710D01*
X178907Y1598705D01*
G03X177685Y1598012I266J-1894D01*
G03X177261Y1596811I1489J-1201D01*
G03X179097Y1594900I1913J0D01*
G01X179135Y1594899D01*
X179203Y1594869D01*
X179332Y1594740D01*
G02X179391Y1594598I-141J-142D01*
G01Y1593888D01*
G02X179332Y1593746I-200J0D01*
G01X179246Y1593662D01*
G02X179112Y1593604I-141J142D01*
G03X178931Y1589796I61J-1911D01*
G03X179156Y1589781I239J1897D01*
G01X179157D01*
G02X179296Y1589722I-3J-200D01*
G01X181725Y1587293D01*
G03X182649Y1586910I924J923D01*
G01X185772D01*
G02X185800Y1586885I-118J-161D01*
G01X185804Y1586881D01*
G03X185806Y1586879I142J140D01*
G01Y1586878D01*
X186006Y1586598D01*
X186007Y1586597D01*
G02X186040Y1586511I-165J-113D01*
G01X186046Y1586465D01*
X186030Y1586419D01*
G03X185923Y1585816I1805J-631D01*
G01Y1585780D01*
G03X187818Y1583876I1912J8D01*
G01X187819D01*
G02X187958Y1583817I-3J-200D01*
G01X189458Y1582317D01*
G02X189501Y1582100I-142J-141D01*
G01X189478Y1582043D01*
X189377Y1581976D01*
X189276D01*
X189204Y1582005D01*
X189196Y1582013D01*
G03X187835Y1582582I-1361J-1343D01*
G03Y1578758I0J-1912D01*
G03X189195Y1579326I0J1912D01*
G02X189197Y1579328I142J-140D01*
G01X189204Y1579335D01*
X189276Y1579364D01*
X189394D01*
G02X189594Y1579164I0J-200D01*
G01Y1573018D01*
G02X189394Y1572818I-200J0D01*
G01X189355D01*
X189320Y1572832D01*
G03X189245Y1572846I-74J-188D01*
G01X186425D01*
G03X186222Y1572644I0J-203D01*
G01Y1571518D01*
G02X186194Y1571415I-200J-1D01*
G03Y1569453I1642J-981D01*
G02X186222Y1569350I-172J-102D01*
G01Y1566399D01*
G02X186194Y1566296I-200J-1D01*
G03Y1564334I1642J-981D01*
G02X186222Y1564231I-172J-102D01*
G01Y1563106D01*
G03X186425Y1562904I202J0D01*
G01X189245D01*
G03X189320Y1562918I1J202D01*
G01X189355Y1562932D01*
X189394D01*
G02X189594Y1562732I0J-200D01*
G01Y1543798D01*
G03X189976Y1542876I1306J1D01*
G01X216477Y1516375D01*
G03X217401Y1515992I924J923D01*
G01X219293D01*
G02X219435Y1515933I0J-200D01*
G01X220173Y1515195D01*
G03X221097Y1514812I924J923D01*
G01X224806D01*
G02X224948Y1514753I0J-200D01*
G01X225522Y1514179D01*
X225535Y1514140D01*
G03X226971Y1513076I1436J437D01*
G03X228471Y1514508I0J1502D01*
G01X228473Y1514548D01*
X228489Y1514582D01*
G02X228532Y1514642I181J-85D01*
G01X228741Y1514842D01*
G02X228869Y1514890I130J-152D01*
G01X231306D01*
G02X231344Y1514886I-2J-200D01*
G02X231446Y1514833I-37J-196D01*
G01X236912Y1509367D01*
G03X237054Y1509308I142J141D01*
G01X242739D01*
X242771Y1509297D01*
G03X243535Y1509166I766J2176D01*
G01X253473D01*
G03X255104Y1509842I-1J2307D01*
G01X271983Y1526721D01*
G02X272125Y1526780I142J-141D01*
G01X275989D01*
G02X276027Y1526776I-2J-200D01*
G02X276129Y1526723I-37J-196D01*
G01X277689Y1525163D01*
G02X277742Y1525061I-143J-139D01*
G02X277746Y1525023I-196J-40D01*
G01Y1485667D01*
G02X277724Y1485576I-200J0D01*
G02X277688Y1485526I-178J90D01*
G37*
G36*
G01X32083Y292800D02*
X43617D01*
G02X43759Y292741I0J-200D01*
G01X44967Y291533D01*
G02X45026Y291391I-141J-142D01*
G01Y164554D01*
G02X45010Y164475I-200J-1D01*
G01X44964Y164368D01*
X44935Y164340D01*
G03Y162188I1048J-1076D01*
G01X44964Y162160D01*
X45010Y162054D01*
G02X45026Y161975I-184J-78D01*
G01Y153135D01*
G02X44958Y152984I-200J-1D01*
G03Y147410I2435J-2787D01*
G02X45026Y147259I-132J-150D01*
G01Y117473D01*
G02X45017Y117414I-200J0D01*
G01X44993Y117335D01*
X44978Y117312D01*
G03Y115680I1261J-816D01*
G01X44993Y115657D01*
X45017Y115578D01*
G02X45026Y115519I-191J-59D01*
G01Y111398D01*
G03X45085Y111256I200J0D01*
G01X45242Y111099D01*
G02X45253Y111087I-142J-141D01*
G02X45301Y110952I-152J-130D01*
G01X45293Y110622D01*
X45259Y110548D01*
X45229Y110521D01*
G03X44738Y109410I1011J-1111D01*
G03X46240Y107908I1502J0D01*
G03X47351Y108399I0J1502D01*
G01X47378Y108429D01*
X47452Y108463D01*
X47782Y108471D01*
G02X47917Y108423I5J-200D01*
G01X47923Y108418D01*
X49165Y107176D01*
G03X49307Y107117I142J141D01*
G01X64854D01*
G02X65054Y106917I0J-200D01*
G01Y104249D01*
G03X65062Y104072I1802J-7D01*
G01Y104071D01*
G03X65089Y103888I1795J171D01*
G01X65101Y103829D01*
X65057Y103719D01*
X64994Y103674D01*
G02X64816Y103648I-115J164D01*
G01X64785Y103659D01*
X64773Y103665D01*
G03X64098Y103825I-675J-1342D01*
G01X64076D01*
G03X62596Y102323I22J-1502D01*
G03X65600I1502J0D01*
G03X65594Y102462I-1502J5D01*
G02X65607Y102554I199J19D01*
G01X65660Y102686D01*
G03X65666Y102692I-136J142D01*
G01X65676Y102700D01*
X65738Y102744D01*
X65856Y102747D01*
X65908Y102715D01*
G03X66855Y102446I947J1534D01*
G01X66856D01*
G03X66935Y102448I-6J1803D01*
G01X66976Y102450D01*
G03X68659Y104249I-120J1799D01*
G01Y105227D01*
X68658D01*
Y106941D01*
G02X68858Y107117I200J-26D01*
G01X79017D01*
G02X79157Y107060I0J-200D01*
G01X79158Y107059D01*
X80341Y105876D01*
G02X80399Y105683I-137J-146D01*
G01X80321Y105356D01*
G02X80215Y105223I-194J46D01*
G01X80192Y105211D01*
X80178Y105206D01*
G03X79158Y103783I483J-1423D01*
G03X80660Y102281I1502J0D01*
G03X80857Y102294I0J1502D01*
G01X80900Y102300D01*
X80982Y102275D01*
X81241Y102048D01*
G02X81291Y101980I-132J-150D01*
G01X81309Y101941D01*
Y66051D01*
G02X81162Y65858I-200J0D01*
G01X81161D01*
X80723Y65739D01*
X80598Y65790D01*
X80564Y65849D01*
G03X73307Y70016I-7257J-4236D01*
G03X64905Y61614I0J-8402D01*
G03X65525Y58447I8402J1D01*
G01X65544Y58400D01*
X65534Y58302D01*
X65320Y57984D01*
G02X65154Y57896I-166J112D01*
G01X57952D01*
X57857Y57955D01*
X57831Y58006D01*
X57644Y58374D01*
X57653Y58486D01*
X57686Y58532D01*
G03X58394Y60709I-2993J2177D01*
G03X57965Y62439I-3701J0D01*
G01X57941Y62484D01*
X57942Y62583D01*
X58149Y62966D01*
X58231Y63020D01*
X58282Y63025D01*
G03X54589Y65001I-349J3786D01*
G01X54614Y64954D01*
X54612Y64849D01*
X54409Y64508D01*
G02X54237Y64410I-172J102D01*
G01X47393D01*
G03X43692Y60709I0J-3701D01*
G03X44399Y58532I3701J-1D01*
G01X44433Y58486D01*
X44442Y58375D01*
X44256Y58007D01*
G02X44167Y57918I-179J90D01*
G01X44165Y57917D01*
G02X44076Y57896I-89J179D01*
G01X33769D01*
G02X33587Y58014I0J200D01*
G01X33413Y58401D01*
X33431Y58517D01*
X33471Y58562D01*
G03X33852Y59562I-1122J1000D01*
G03X32350Y61064I-1502J0D01*
G03X30859Y59743I0J-1502D01*
G01X30852Y59684D01*
G03X31228Y58562I1498J-122D01*
G01X31229Y58561D01*
G02X31262Y58347I-150J-133D01*
G01X31113Y58014D01*
G02X30931Y57896I-182J82D01*
G01X25766D01*
G02X25746Y57897I0J200D01*
G01X25745D01*
G02X25584Y58012I21J199D01*
G01X25407Y58395D01*
X25423Y58510D01*
X25461Y58555D01*
G03X25818Y59527I-1145J972D01*
G03X22814I-1502J0D01*
G03X23171Y58555I1502J0D01*
G01X23209Y58510D01*
X23225Y58395D01*
X23048Y58012D01*
G02X22906Y57900I-181J84D01*
G01X22886Y57896D01*
X5643D01*
G02X5501Y57955I0J200D01*
G01X5059Y58397D01*
X5030Y58425D01*
X5000Y58499D01*
Y290078D01*
G02X5059Y290220I200J0D01*
G01X5737Y290898D01*
G02X5879Y290957I142J-141D01*
G01X30074D01*
G03X30216Y291016I0J200D01*
G01X31941Y292741D01*
G02X32083Y292800I142J-141D01*
G37*
G36*
G01X166583Y1158303D02*
X166714Y1158354D01*
X168657D01*
G02X168762Y1158325I1J-200D01*
G03X169389Y1158148I628J1025D01*
G03X170016Y1158325I-1J1202D01*
G02X170121Y1158354I104J-171D01*
G01X172397D01*
G02X172502Y1158325I1J-200D01*
G03X173129Y1158148I628J1025D01*
G03X173756Y1158325I-1J1202D01*
G02X173861Y1158354I104J-171D01*
G01X176138D01*
G02X176243Y1158325I1J-200D01*
G03X176870Y1158148I628J1025D01*
G03X177497Y1158325I-1J1202D01*
G02X177602Y1158354I104J-171D01*
G01X179878D01*
G02X179983Y1158325I1J-200D01*
G03X180610Y1158148I628J1025D01*
G03X181237Y1158325I-1J1202D01*
G02X181342Y1158354I104J-171D01*
G01X183618D01*
G02X183723Y1158325I1J-200D01*
G03X184350Y1158148I628J1025D01*
G03X184977Y1158325I-1J1202D01*
G02X185082Y1158354I104J-171D01*
G01X187358D01*
G02X187463Y1158325I1J-200D01*
G03X188090Y1158148I628J1025D01*
G03X188278Y1158163I-1J1202D01*
G01X188327Y1158171D01*
X188417Y1158141D01*
X189966Y1156592D01*
G02X190025Y1156450I-141J-142D01*
G01Y1142285D01*
G03X190084Y1142143I200J0D01*
G01X190723Y1141504D01*
G02X190782Y1141362I-141J-142D01*
G01Y1141264D01*
X190771Y1141219D01*
X190760Y1141197D01*
G03X190628Y1140649I1072J-548D01*
G03X193032I1202J0D01*
G03X192951Y1141082I-1202J-1D01*
G01X192933Y1141129D01*
X192945Y1141227D01*
X193093Y1141441D01*
Y1141443D01*
X193156Y1141534D01*
G02X193210Y1141588I166J-112D01*
G01X193217Y1141592D01*
G02X193328Y1141626I112J-166D01*
G01X194076D01*
G02X194209Y1141576I1J-200D01*
G01X194228Y1141559D01*
X194307Y1141442D01*
X194427Y1141266D01*
G02X194449Y1141082I-165J-113D01*
G01X194448Y1141080D01*
G03X194368Y1140651I1122J-431D01*
G01Y1140633D01*
G03X195570Y1139447I1202J16D01*
G03X196772Y1140649I0J1202D01*
G03X196691Y1141082I-1202J-1D01*
G01X196673Y1141129D01*
X196685Y1141227D01*
X196833Y1141441D01*
Y1141443D01*
X196896Y1141534D01*
G02X196950Y1141588I166J-112D01*
G01X196957Y1141592D01*
G02X197068Y1141626I112J-166D01*
G01X197817D01*
G02X197950Y1141576I1J-200D01*
G01X197969Y1141559D01*
X198048Y1141442D01*
X198168Y1141266D01*
G02X198190Y1141082I-165J-113D01*
G01X198189Y1141080D01*
G03X198109Y1140651I1122J-431D01*
G01Y1140633D01*
G03X199311Y1139447I1202J16D01*
G03X200513Y1140649I0J1202D01*
G03X200432Y1141082I-1202J-1D01*
G01X200414Y1141129D01*
X200426Y1141227D01*
X200574Y1141441D01*
Y1141443D01*
X200637Y1141534D01*
G02X200691Y1141588I166J-112D01*
G01X200698Y1141592D01*
G02X200809Y1141626I112J-166D01*
G01X201557D01*
G02X201690Y1141576I1J-200D01*
G01X201709Y1141559D01*
X201788Y1141442D01*
X201908Y1141266D01*
G02X201930Y1141082I-165J-113D01*
G01X201929Y1141080D01*
G03X201849Y1140651I1122J-431D01*
G01Y1140633D01*
G03X203051Y1139447I1202J16D01*
G03X204253Y1140649I0J1202D01*
G03X204172Y1141082I-1202J-1D01*
G01X204154Y1141129D01*
X204166Y1141227D01*
X204314Y1141441D01*
Y1141443D01*
X204377Y1141534D01*
G02X204431Y1141588I166J-112D01*
G01X204438Y1141592D01*
G02X204549Y1141626I112J-166D01*
G01X205297D01*
G02X205430Y1141576I1J-200D01*
G01X205449Y1141559D01*
X205528Y1141442D01*
X205648Y1141266D01*
G02X205670Y1141082I-165J-113D01*
G01X205669Y1141080D01*
G03X205589Y1140651I1122J-431D01*
G01Y1140633D01*
G03X206791Y1139447I1202J16D01*
G03X207993Y1140649I0J1202D01*
G03X207912Y1141082I-1202J-1D01*
G01X207894Y1141129D01*
X207906Y1141227D01*
X208054Y1141441D01*
Y1141443D01*
X208117Y1141534D01*
G02X208171Y1141588I166J-112D01*
G01X208178Y1141592D01*
G02X208289Y1141626I112J-166D01*
G01X209037D01*
G02X209170Y1141576I1J-200D01*
G01X209189Y1141559D01*
X209268Y1141442D01*
X209388Y1141266D01*
G02X209410Y1141082I-165J-113D01*
G01X209409Y1141080D01*
G03X209329Y1140651I1122J-431D01*
G01Y1140633D01*
G03X210531Y1139447I1202J16D01*
G03X211733Y1140649I0J1202D01*
G03X211652Y1141082I-1202J-1D01*
G01X211634Y1141129D01*
X211646Y1141227D01*
X211794Y1141441D01*
Y1141443D01*
X211857Y1141534D01*
G02X211911Y1141588I166J-112D01*
G01X211918Y1141592D01*
G02X212029Y1141626I112J-166D01*
G01X212777D01*
G02X212910Y1141576I1J-200D01*
G01X212929Y1141559D01*
X213008Y1141442D01*
X213128Y1141266D01*
G02X213150Y1141082I-165J-113D01*
G01X213149Y1141080D01*
G03X213069Y1140651I1122J-431D01*
G01Y1140633D01*
G03X214271Y1139447I1202J16D01*
G03X215473Y1140649I0J1202D01*
G03X215392Y1141082I-1202J-1D01*
G01X215374Y1141129D01*
X215386Y1141227D01*
X215534Y1141441D01*
Y1141443D01*
X215597Y1141534D01*
G02X215651Y1141588I166J-112D01*
G01X215658Y1141592D01*
G02X215769Y1141626I112J-166D01*
G01X216517D01*
G02X216650Y1141576I1J-200D01*
G01X216669Y1141559D01*
X216748Y1141442D01*
X216868Y1141266D01*
G02X216890Y1141082I-165J-113D01*
G01X216889Y1141080D01*
G03X216809Y1140651I1122J-431D01*
G01Y1140633D01*
G03X218011Y1139447I1202J16D01*
G03X219213Y1140649I0J1202D01*
G03X219132Y1141082I-1202J-1D01*
G01X219114Y1141129D01*
X219126Y1141227D01*
X219274Y1141441D01*
Y1141443D01*
X219337Y1141534D01*
G02X219391Y1141588I166J-112D01*
G01X219398Y1141592D01*
G02X219509Y1141626I112J-166D01*
G01X220257D01*
G02X220390Y1141576I1J-200D01*
G01X220409Y1141559D01*
X220488Y1141442D01*
X220608Y1141266D01*
G02X220630Y1141082I-165J-113D01*
G01X220629Y1141080D01*
G03X220549Y1140651I1122J-431D01*
G01Y1140633D01*
G03X221751Y1139447I1202J16D01*
G03X222953Y1140649I0J1202D01*
G03X222872Y1141082I-1202J-1D01*
G01X222854Y1141129D01*
X222866Y1141227D01*
X223014Y1141441D01*
Y1141443D01*
X223077Y1141534D01*
G02X223131Y1141588I166J-112D01*
G01X223138Y1141592D01*
G02X223249Y1141626I112J-166D01*
G01X223998D01*
G02X224131Y1141576I1J-200D01*
G01X224150Y1141559D01*
X224229Y1141442D01*
X224349Y1141266D01*
G02X224371Y1141082I-165J-113D01*
G01X224370Y1141080D01*
G03X224290Y1140651I1122J-431D01*
G01Y1140633D01*
G03X225492Y1139447I1202J16D01*
G03X226694Y1140649I0J1202D01*
G03X226613Y1141082I-1202J-1D01*
G01X226595Y1141129D01*
X226607Y1141227D01*
X226755Y1141441D01*
Y1141443D01*
X226818Y1141534D01*
G02X226872Y1141588I166J-112D01*
G01X226879Y1141592D01*
G02X226990Y1141626I112J-166D01*
G01X227738D01*
G02X227871Y1141576I1J-200D01*
G01X227890Y1141559D01*
X227969Y1141442D01*
X228089Y1141266D01*
G02X228111Y1141082I-165J-113D01*
G01X228110Y1141080D01*
G03X228030Y1140651I1122J-431D01*
G01Y1140633D01*
G03X229232Y1139447I1202J16D01*
G03X230434Y1140649I0J1202D01*
G03X230353Y1141082I-1202J-1D01*
G01X230335Y1141129D01*
X230347Y1141227D01*
X230495Y1141441D01*
Y1141443D01*
X230558Y1141534D01*
G02X230612Y1141588I166J-112D01*
G01X230619Y1141592D01*
G02X230730Y1141626I112J-166D01*
G01X235218D01*
G02X235351Y1141576I1J-200D01*
G01X235370Y1141559D01*
X235449Y1141442D01*
X235569Y1141266D01*
G02X235591Y1141082I-165J-113D01*
G01X235590Y1141080D01*
G03X235510Y1140651I1122J-431D01*
G01Y1140633D01*
G03X236712Y1139447I1202J16D01*
G03X237914Y1140649I0J1202D01*
G03X237833Y1141082I-1202J-1D01*
G01X237815Y1141129D01*
X237827Y1141227D01*
X237975Y1141441D01*
Y1141443D01*
X238038Y1141534D01*
G02X238092Y1141588I166J-112D01*
G01X238099Y1141592D01*
G02X238210Y1141626I112J-166D01*
G01X238958D01*
G02X239091Y1141576I1J-200D01*
G01X239110Y1141559D01*
X239189Y1141442D01*
X239309Y1141266D01*
G02X239331Y1141082I-165J-113D01*
G01X239330Y1141080D01*
G03X239250Y1140651I1122J-431D01*
G01Y1140633D01*
G03X240452Y1139447I1202J16D01*
G03X241654Y1140649I0J1202D01*
G03X241573Y1141082I-1202J-1D01*
G01X241555Y1141129D01*
X241567Y1141227D01*
X241715Y1141441D01*
Y1141443D01*
X241778Y1141534D01*
G02X241832Y1141588I166J-112D01*
G01X241839Y1141592D01*
G02X241950Y1141626I112J-166D01*
G01X242698D01*
G02X242831Y1141576I1J-200D01*
G01X242850Y1141559D01*
X242929Y1141442D01*
X243049Y1141266D01*
G02X243071Y1141082I-165J-113D01*
G01X243070Y1141080D01*
G03X242990Y1140651I1122J-431D01*
G01Y1140633D01*
G03X244192Y1139447I1202J16D01*
G03X245394Y1140649I0J1202D01*
G03X245313Y1141082I-1202J-1D01*
G01X245295Y1141129D01*
X245307Y1141227D01*
X245455Y1141441D01*
Y1141443D01*
X245518Y1141534D01*
G02X245572Y1141588I166J-112D01*
G01X245579Y1141592D01*
G02X245690Y1141626I112J-166D01*
G01X246439D01*
G02X246572Y1141576I1J-200D01*
G01X246591Y1141559D01*
X246670Y1141442D01*
X246790Y1141266D01*
G02X246812Y1141082I-165J-113D01*
G01X246811Y1141080D01*
G03X246731Y1140651I1122J-431D01*
G01Y1140633D01*
G03X247933Y1139447I1202J16D01*
G03X249135Y1140649I0J1202D01*
G03X249054Y1141082I-1202J-1D01*
G01X249036Y1141129D01*
X249048Y1141227D01*
X249196Y1141441D01*
Y1141443D01*
X249259Y1141534D01*
G02X249313Y1141588I166J-112D01*
G01X249320Y1141592D01*
G02X249431Y1141626I112J-166D01*
G01X250179D01*
G02X250312Y1141576I1J-200D01*
G01X250331Y1141559D01*
X250410Y1141442D01*
X250530Y1141266D01*
G02X250552Y1141082I-165J-113D01*
G01X250551Y1141080D01*
G03X250471Y1140651I1122J-431D01*
G01Y1140633D01*
G03X251673Y1139447I1202J16D01*
G03X252875Y1140649I0J1202D01*
G03X252794Y1141082I-1202J-1D01*
G01X252776Y1141129D01*
X252788Y1141227D01*
X252936Y1141441D01*
Y1141443D01*
X252999Y1141534D01*
G02X253053Y1141588I166J-112D01*
G01X253060Y1141592D01*
G02X253171Y1141626I112J-166D01*
G01X253919D01*
G02X254052Y1141576I1J-200D01*
G01X254071Y1141559D01*
X254150Y1141442D01*
X254270Y1141266D01*
G02X254292Y1141082I-165J-113D01*
G01X254291Y1141080D01*
G03X254211Y1140651I1122J-431D01*
G01Y1140633D01*
G03X255413Y1139447I1202J16D01*
G03X256615Y1140649I0J1202D01*
G03X256534Y1141082I-1202J-1D01*
G01X256516Y1141129D01*
X256528Y1141227D01*
X256676Y1141441D01*
Y1141443D01*
X256739Y1141534D01*
G02X256793Y1141588I166J-112D01*
G01X256800Y1141592D01*
G02X256911Y1141626I112J-166D01*
G01X257659D01*
G02X257792Y1141576I1J-200D01*
G01X257811Y1141559D01*
X257890Y1141442D01*
X258010Y1141266D01*
G02X258032Y1141082I-165J-113D01*
G01X258031Y1141080D01*
G03X257951Y1140651I1122J-431D01*
G01Y1140633D01*
G03X259153Y1139447I1202J16D01*
G03X260355Y1140649I0J1202D01*
G03X260274Y1141082I-1202J-1D01*
G01X260256Y1141129D01*
X260268Y1141227D01*
X260416Y1141441D01*
Y1141443D01*
X260479Y1141534D01*
G02X260533Y1141588I166J-112D01*
G01X260540Y1141592D01*
G02X260651Y1141626I112J-166D01*
G01X261399D01*
G02X261532Y1141576I1J-200D01*
G01X261551Y1141559D01*
X261630Y1141442D01*
X261750Y1141266D01*
G02X261772Y1141082I-165J-113D01*
G01X261771Y1141080D01*
G03X261691Y1140651I1122J-431D01*
G01Y1140633D01*
G03X262893Y1139447I1202J16D01*
G03X264095Y1140649I0J1202D01*
G03X264014Y1141082I-1202J-1D01*
G01X263996Y1141129D01*
X264008Y1141227D01*
X264156Y1141441D01*
Y1141443D01*
X264219Y1141534D01*
G02X264273Y1141588I166J-112D01*
G01X264280Y1141592D01*
G02X264391Y1141626I112J-166D01*
G01X265139D01*
G02X265272Y1141576I1J-200D01*
G01X265291Y1141559D01*
X265370Y1141442D01*
X265490Y1141266D01*
G02X265512Y1141082I-165J-113D01*
G01X265511Y1141080D01*
G03X265431Y1140651I1122J-431D01*
G01Y1140633D01*
G03X266633Y1139447I1202J16D01*
G03X267835Y1140649I0J1202D01*
G03X267754Y1141082I-1202J-1D01*
G01X267736Y1141129D01*
X267748Y1141227D01*
X267896Y1141441D01*
Y1141443D01*
X267959Y1141534D01*
G02X268013Y1141588I166J-112D01*
G01X268020Y1141592D01*
G02X268131Y1141626I112J-166D01*
G01X268879D01*
G02X269012Y1141576I1J-200D01*
G01X269031Y1141559D01*
X269110Y1141442D01*
X269230Y1141266D01*
G02X269252Y1141082I-165J-113D01*
G01X269251Y1141080D01*
G03X269171Y1140651I1122J-431D01*
G01Y1140633D01*
G03X270373Y1139447I1202J16D01*
G03X271575Y1140649I0J1202D01*
G03X271494Y1141082I-1202J-1D01*
G01X271476Y1141129D01*
X271488Y1141227D01*
X271636Y1141441D01*
Y1141443D01*
X271699Y1141534D01*
G02X271753Y1141588I166J-112D01*
G01X271760Y1141592D01*
G02X271871Y1141626I112J-166D01*
G01X272620D01*
G02X272753Y1141576I1J-200D01*
G01X272772Y1141559D01*
X272851Y1141442D01*
X272971Y1141266D01*
G02X272993Y1141082I-165J-113D01*
G01X272992Y1141080D01*
G03X272912Y1140651I1122J-431D01*
G01Y1140633D01*
G03X274114Y1139447I1202J16D01*
G03X275316Y1140649I0J1202D01*
G03X275235Y1141082I-1202J-1D01*
G01X275217Y1141129D01*
X275229Y1141227D01*
X275377Y1141441D01*
Y1141443D01*
X275440Y1141534D01*
G02X275494Y1141588I166J-112D01*
G01X275501Y1141592D01*
G02X275612Y1141626I112J-166D01*
G01X276360D01*
G02X276493Y1141576I1J-200D01*
G01X276512Y1141559D01*
X276591Y1141442D01*
X276711Y1141266D01*
G02X276733Y1141082I-165J-113D01*
G01X276732Y1141080D01*
G03X276652Y1140651I1122J-431D01*
G01Y1140633D01*
G03X277854Y1139447I1202J16D01*
G03X279056Y1140649I0J1202D01*
G03X278975Y1141082I-1202J-1D01*
G01X278957Y1141129D01*
X278969Y1141227D01*
X279117Y1141441D01*
Y1141443D01*
X279180Y1141534D01*
G02X279234Y1141588I166J-112D01*
G01X279241Y1141592D01*
G02X279352Y1141626I112J-166D01*
G01X280100D01*
G02X280233Y1141576I1J-200D01*
G01X280252Y1141559D01*
X280331Y1141442D01*
X280451Y1141266D01*
G02X280473Y1141082I-165J-113D01*
G01X280472Y1141080D01*
G03X280392Y1140651I1122J-431D01*
G01Y1140633D01*
G03X281594Y1139447I1202J16D01*
G03X282796Y1140649I0J1202D01*
G03X282715Y1141082I-1202J-1D01*
G01X282697Y1141129D01*
X282709Y1141227D01*
X282857Y1141441D01*
Y1141443D01*
X282920Y1141534D01*
G02X282974Y1141588I166J-112D01*
G01X282981Y1141592D01*
G02X283092Y1141626I112J-166D01*
G01X283840D01*
G02X283973Y1141576I1J-200D01*
G01X283992Y1141559D01*
X284071Y1141442D01*
X284191Y1141266D01*
G02X284213Y1141082I-165J-113D01*
G01X284212Y1141080D01*
G03X284132Y1140651I1122J-431D01*
G01Y1140633D01*
G03X285334Y1139447I1202J16D01*
G03X286536Y1140649I0J1202D01*
G03X286455Y1141082I-1202J-1D01*
G01X286437Y1141129D01*
X286449Y1141227D01*
X286597Y1141441D01*
Y1141443D01*
X286660Y1141534D01*
G02X286714Y1141588I166J-112D01*
G01X286721Y1141592D01*
G02X286832Y1141626I112J-166D01*
G01X287728D01*
G02X287870Y1141567I0J-200D01*
G01X288029Y1141408D01*
X288048Y1141278D01*
X288016Y1141219D01*
G03X287872Y1140649I1058J-570D01*
G03X288871Y1139464I1202J0D01*
G01X288955Y1139450D01*
G03X288988Y1139447I35J197D01*
G01X289074D01*
G03X289322Y1139473I-1J1202D01*
G01X289366Y1139482D01*
X289454Y1139461D01*
X289659Y1139295D01*
X289662Y1139292D01*
X289750Y1139222D01*
X289788Y1139113D01*
X289774Y1139056D01*
G03X289742Y1138779I1170J-276D01*
G03X289774Y1138502I1202J-1D01*
G01X289788Y1138445D01*
X289750Y1138336D01*
X289662Y1138266D01*
X289659Y1138263D01*
X289489Y1138126D01*
G02X289322Y1138085I-127J155D01*
G03X289075Y1138111I-249J-1176D01*
G01X288988D01*
G03X288955Y1138108I2J-200D01*
G01X288871Y1138094D01*
G03X287872Y1136909I203J-1185D01*
G03X289074Y1135707I1202J0D01*
G01X289076D01*
G03X289429Y1135760I0J1202D01*
G01X289437Y1135763D01*
X289451Y1135766D01*
G03X289471Y1135773I-56J191D01*
G01X289487Y1135779D01*
X289551Y1135792D01*
G02X289592Y1135796I40J-196D01*
G01X289605D01*
G02X289805Y1135596I0J-200D01*
G01Y1135518D01*
X289785Y1135458D01*
X289766Y1135432D01*
G03X289621Y1135223I3045J-2267D01*
G03X289372Y1134772I3192J-2056D01*
G01X289347Y1134717D01*
G03X289282Y1134561I3471J-1538D01*
G01X289281Y1134558D01*
X289277Y1134549D01*
G02X289221Y1134472I-185J76D01*
G01X289215Y1134467D01*
X289183Y1134444D01*
X289074Y1134373D01*
X289019Y1134370D01*
G03X288996Y1131969I55J-1201D01*
G01X289021Y1131967D01*
X289089Y1131945D01*
X289122Y1131933D01*
X289204Y1131877D01*
X289223Y1131854D01*
X289274Y1131792D01*
X289289Y1131759D01*
X289291Y1131754D01*
G03X289432Y1131444I3523J1415D01*
G03X289451Y1131407I3387J1716D01*
G03X289765Y1130907I3362J1763D01*
G01X289784Y1130882D01*
X289804Y1130825D01*
X289805Y1130790D01*
Y1130783D01*
X289759Y1130696D01*
X289614Y1130598D01*
G02X289441Y1130574I-111J166D01*
G03X289075Y1130631I-366J-1145D01*
G01X289057D01*
G03X287872Y1129429I17J-1202D01*
G03X289074Y1128227I1202J0D01*
G01X289076D01*
G03X289429Y1128280I0J1202D01*
G01X289437Y1128283D01*
X289451Y1128286D01*
G03X289471Y1128293I-56J191D01*
G01X289487Y1128299D01*
X289551Y1128312D01*
G02X289592Y1128316I40J-196D01*
G01X289605D01*
G02X289805Y1128116I0J-200D01*
G01Y1128037D01*
X289785Y1127977D01*
X289766Y1127951D01*
G03X289621Y1127742I3045J-2267D01*
G03X289372Y1127291I3192J-2056D01*
G01X289347Y1127236D01*
G03X289282Y1127080I3471J-1538D01*
G01X289281Y1127077D01*
X289277Y1127068D01*
G02X289221Y1126991I-185J76D01*
G01X289215Y1126986D01*
X289183Y1126963D01*
X289074Y1126892D01*
X289019Y1126889D01*
G03X288996Y1124488I55J-1201D01*
G01X289021Y1124486D01*
X289089Y1124464D01*
X289122Y1124452D01*
X289204Y1124396D01*
X289223Y1124373D01*
X289274Y1124311D01*
X289289Y1124278D01*
X289291Y1124273D01*
G03X289432Y1123963I3523J1415D01*
G03X289451Y1123926I3387J1716D01*
G03X289765Y1123426I3362J1763D01*
G01X289784Y1123401D01*
X289804Y1123344D01*
X289805Y1123309D01*
Y1123302D01*
X289759Y1123215D01*
X289614Y1123117D01*
G02X289441Y1123093I-111J166D01*
G03X289075Y1123150I-366J-1145D01*
G01X289057D01*
G03X287872Y1121948I17J-1202D01*
G03X289074Y1120746I1202J0D01*
G01X289076D01*
G03X289429Y1120799I0J1202D01*
G01X289437Y1120802D01*
X289451Y1120805D01*
G03X289471Y1120812I-56J191D01*
G01X289487Y1120818D01*
X289551Y1120831D01*
G02X289592Y1120835I40J-196D01*
G01X289605D01*
G02X289805Y1120635I0J-200D01*
G01Y1120557D01*
X289785Y1120497D01*
X289766Y1120471D01*
G03X289621Y1120262I3045J-2267D01*
G03X289372Y1119811I3192J-2056D01*
G01X289347Y1119756D01*
G03X289282Y1119600I3471J-1538D01*
G01X289281Y1119597D01*
X289277Y1119588D01*
G02X289221Y1119511I-185J76D01*
G01X289215Y1119506D01*
X289183Y1119483D01*
X289074Y1119412D01*
X289019Y1119409D01*
G03X288996Y1117008I55J-1201D01*
G01X289021Y1117006D01*
X289089Y1116984D01*
X289122Y1116972D01*
X289204Y1116916D01*
X289223Y1116893D01*
X289274Y1116831D01*
X289289Y1116798D01*
X289291Y1116793D01*
G03X289432Y1116483I3523J1415D01*
G03X289451Y1116446I3387J1716D01*
G03X289765Y1115946I3362J1763D01*
G01X289784Y1115921D01*
X289804Y1115864D01*
X289805Y1115829D01*
Y1115822D01*
X289759Y1115735D01*
X289614Y1115637D01*
G02X289441Y1115613I-111J166D01*
G03X289075Y1115670I-366J-1145D01*
G01X289057D01*
G03X287872Y1114468I17J-1202D01*
G03X288871Y1113283I1202J0D01*
G01X288955Y1113269D01*
G03X288988Y1113266I35J197D01*
G01X289075D01*
G03X289322Y1113292I-2J1202D01*
G02X289489Y1113252I41J-196D01*
G01X289659Y1113114D01*
X289662Y1113111D01*
X289750Y1113041D01*
X289788Y1112932D01*
X289774Y1112875D01*
G03X289742Y1112598I1170J-276D01*
G03X289774Y1112321I1202J-1D01*
G01X289788Y1112264D01*
X289751Y1112157D01*
X289492Y1111946D01*
X289474Y1111931D01*
X289436Y1111912D01*
X289366Y1111895D01*
X289321Y1111904D01*
G03X289073Y1111930I-249J-1176D01*
G01X289064D01*
G03X287871Y1110734I9J-1202D01*
G01Y1110667D01*
X287800Y1110565D01*
X287741Y1110543D01*
G03X287691Y1110524I1323J-3558D01*
G03X287461Y1110425I1385J-3535D01*
G03X287319Y1110356I1588J-3449D01*
G01X287318Y1110355D01*
X287296Y1110344D01*
X287254Y1110333D01*
X287160D01*
X287111Y1110344D01*
X287087Y1110356D01*
X287086Y1110357D01*
G03X286722Y1110523I-1755J-3367D01*
G01X286699Y1110531D01*
X286663Y1110557D01*
X286637Y1110585D01*
G02X286622Y1110604I149J133D01*
G01X286572Y1110675D01*
X286555Y1110699D01*
X286535Y1110757D01*
X286534Y1110786D01*
G03X285333Y1111929I-1201J-59D01*
G03X284132Y1110787I0J-1203D01*
G01X284129Y1110730D01*
X284020Y1110571D01*
X283974Y1110534D01*
X283946Y1110523D01*
G03X283585Y1110357I1404J-3528D01*
G01X283583Y1110356D01*
X283581Y1110355D01*
X283556Y1110342D01*
X283509Y1110331D01*
G02X283415Y1110332I-45J195D01*
G01X283369Y1110344D01*
X283349Y1110355D01*
G03X283265Y1110397I-1740J-3375D01*
G01X283222Y1110418D01*
G03X283181Y1110437I-1617J-3435D01*
G01X283127Y1110461D01*
G03X283125Y1110462I-90J-178D01*
G01X282860Y1110577D01*
X282795Y1110675D01*
Y1110735D01*
G03X281593Y1111929I-1202J-8D01*
G03X280391Y1110731I0J-1202D01*
G02X280298Y1110562I-200J0D01*
G01X280281Y1110551D01*
X280261Y1110543D01*
X280259Y1110542D01*
G03X280076Y1110468I1331J-3555D01*
G03X279966Y1110418I1516J-3481D01*
G03X279871Y1110371I1636J-3426D01*
G03X279723Y1110291I1731J-3379D01*
G03X279643Y1110335I-1869J-3304D01*
G03X279241Y1110522I-1800J-3343D01*
G01X279231Y1110526D01*
X279221Y1110531D01*
G02X279151Y1110592I93J177D01*
G01X279074Y1110699D01*
X279055Y1110754D01*
X279054Y1110783D01*
G03X277853Y1111929I-1201J-56D01*
G03X276652Y1110784I0J-1202D01*
G01X276651Y1110755D01*
X276632Y1110701D01*
X276616Y1110678D01*
X276542Y1110572D01*
X276496Y1110535D01*
X276468Y1110524D01*
G03X276095Y1110350I1416J-3523D01*
G03X276090Y1110348I72J-187D01*
G01X276058Y1110324D01*
X275943Y1110315D01*
X275887Y1110345D01*
G03X275601Y1110481I-1772J-3357D01*
G01X275579Y1110490D01*
X275569Y1110495D01*
G03X275501Y1110523I-1479J-3496D01*
G01X275474Y1110534D01*
X275450Y1110553D01*
G02X275412Y1110594I126J155D01*
G01X275367Y1110657D01*
X275350Y1110681D01*
X275314Y1110787D01*
X275312Y1110813D01*
G03X274113Y1111929I-1199J-86D01*
G03X272911Y1110767I0J-1203D01*
G01Y1110766D01*
X272909Y1110718D01*
X272857Y1110623D01*
G02X272755Y1110533I-175J96D01*
G01X272753Y1110532D01*
G03X272695Y1110509I1370J-3540D01*
G01X272693D01*
G03X272677Y1110502I1514J-3482D01*
G03X272337Y1110342I1444J-3511D01*
G01X272315Y1110331D01*
X272268Y1110319D01*
X272216D01*
X272169Y1110331D01*
X272147Y1110342D01*
G03X271705Y1110542I-1783J-3351D01*
G02X271575Y1110729I70J187D01*
G03X269171I-1202J-2D01*
G02X269041Y1110542I-200J0D01*
G03X268620Y1110354I1335J-3554D01*
G01X268598Y1110343D01*
X268551Y1110332D01*
G02X268458I-47J194D01*
G01X268409Y1110343D01*
X268387Y1110355D01*
G03X268020Y1110524I-1770J-3360D01*
G02X267929Y1110595I72J187D01*
G01X267853Y1110703D01*
X267835Y1110756D01*
X267834Y1110785D01*
G03X265432I-1201J-57D01*
G01X265431Y1110756D01*
X265412Y1110703D01*
X265337Y1110597D01*
G02X265269Y1110536I-164J114D01*
G01X265250Y1110526D01*
X265240Y1110522D01*
G03X264856Y1110343I1410J-3526D01*
G02X264749Y1110320I-94J177D01*
G01X264706Y1110323D01*
G03X264282Y1110521I-1815J-3335D01*
G01X264268Y1110526D01*
X264254Y1110534D01*
G02X264192Y1110591I101J172D01*
G01X264113Y1110700D01*
X264095Y1110755D01*
X264094Y1110785D01*
G03X261692I-1201J-57D01*
G01X261691Y1110755D01*
X261673Y1110700D01*
X261594Y1110591D01*
G02X261532Y1110534I-163J115D01*
G01X261518Y1110526D01*
X261504Y1110521D01*
G03X261137Y1110353I1395J-3531D01*
G02X261133Y1110351I-91J178D01*
G02X261044Y1110330I-89J179D01*
G01X260983D01*
X260935Y1110341D01*
G03X260540Y1110524I-1791J-3348D01*
G02X260449Y1110595I72J187D01*
G01X260373Y1110703D01*
X260355Y1110756D01*
X260354Y1110785D01*
G03X257952I-1201J-57D01*
G01X257951Y1110756D01*
X257933Y1110703D01*
X257857Y1110597D01*
G02X257789Y1110536I-164J114D01*
G01X257770Y1110526D01*
X257760Y1110522D01*
G03X257376Y1110343I1410J-3526D01*
G02X257269Y1110320I-94J177D01*
G01X257226Y1110323D01*
G03X256802Y1110521I-1815J-3335D01*
G01X256788Y1110526D01*
X256774Y1110534D01*
G02X256712Y1110591I101J172D01*
G01X256633Y1110700D01*
X256615Y1110755D01*
X256614Y1110785D01*
G03X254212I-1201J-57D01*
G01X254211Y1110756D01*
X254192Y1110699D01*
X254114Y1110592D01*
G02X254061Y1110540I-164J114D01*
G01X254039Y1110526D01*
X254020Y1110519D01*
G03X253659Y1110354I1396J-3531D01*
G01X253637Y1110343D01*
X253590Y1110332D01*
G02X253497I-47J194D01*
G01X253448Y1110343D01*
X253426Y1110355D01*
G03X253203Y1110463I-1765J-3361D01*
G02X253085Y1110657I82J183D01*
G03X253087Y1110728I-1412J75D01*
G03X251983Y1112107I-1413J0D01*
G01X251946Y1112115D01*
X251884Y1112157D01*
X251364Y1112905D01*
G02X251353Y1113115I164J114D01*
G01X251381Y1113165D01*
X251480Y1113221D01*
X251545Y1113218D01*
X251551D01*
X251560Y1113217D01*
G03X251671Y1113212I112J1251D01*
G01X251673D01*
G03X250417Y1114468I0J1256D01*
G03X250518Y1113976I1256J1D01*
G01X250519Y1113973D01*
X250526Y1113955D01*
X250545Y1113871D01*
X250540Y1113834D01*
X250526Y1113730D01*
G02X250499Y1113653I-198J26D01*
G03X250471Y1113552I172J-102D01*
G01Y1111528D01*
G02X250445Y1111429I-200J0D01*
G03X250259Y1110728I1228J-701D01*
G03X250261Y1110656I1414J3D01*
G02X250142Y1110462I-200J-11D01*
G03X249919Y1110355I1530J-3474D01*
G01X249895Y1110342D01*
X249800Y1110321D01*
X249754Y1110332D01*
X249709Y1110343D01*
X249688Y1110354D01*
G03X249265Y1110543I-1757J-3365D01*
G02X249135Y1110730I70J187D01*
G03X246731I-1202J-2D01*
G02X246601Y1110543I-200J0D01*
G03X246183Y1110357I1332J-3555D01*
G01X246172Y1110352D01*
X246133Y1110337D01*
X246120Y1110334D01*
X246067Y1110321D01*
X245994Y1110330D01*
X245962Y1110347D01*
G03X245902Y1110378I-1773J-3358D01*
G03X245579Y1110524I-1724J-3384D01*
G01X245577D01*
X245576Y1110525D01*
G02X245489Y1110594I76J185D01*
G01X245448Y1110651D01*
G02X245422Y1110701I163J116D01*
G01X245394Y1110782D01*
X245392Y1110809D01*
G03X244192Y1111930I-1200J-82D01*
G03X242990Y1110732I0J-1202D01*
G01Y1110667D01*
X242919Y1110565D01*
X242860Y1110543D01*
G03X242454Y1110363I1333J-3555D01*
G01X242451Y1110361D01*
X242411Y1110342D01*
X242366Y1110332D01*
G02X242274I-46J194D01*
G01X242228Y1110343D01*
X242206Y1110354D01*
G03X241784Y1110543I-1760J-3364D01*
G02X241654Y1110730I70J187D01*
G03X239250I-1202J-2D01*
G02X239120Y1110543I-200J0D01*
G03X238700Y1110356I1331J-3555D01*
G01X238699Y1110355D01*
X238673Y1110342D01*
X238628Y1110332D01*
X238582Y1110321D01*
X238489Y1110343D01*
X238465Y1110355D01*
X238464Y1110356D01*
G03X238390Y1110393I-1735J-3377D01*
G03X238044Y1110543I-1681J-3404D01*
G01X237985Y1110565D01*
X237914Y1110667D01*
Y1110732D01*
G03X236712Y1111930I-1202J-4D01*
G03X235510Y1110730I0J-1202D01*
G02X235380Y1110543I-200J0D01*
G03X234352Y1109962I1331J-3555D01*
G02X234315Y1109938I-127J155D01*
G03X233761Y1109385I526J-1081D01*
G02X233738Y1109348I-180J86D01*
G03X233179Y1108378I2974J-2360D01*
G01X233167Y1108347D01*
X233146Y1108322D01*
X233128Y1108300D01*
X233025Y1108227D01*
G03X233023Y1108225I139J-141D01*
G01X233000Y1108209D01*
X232944Y1108189D01*
X232892Y1108187D01*
X232873Y1108185D01*
X232869Y1108184D01*
G03X232750Y1108168I100J-1198D01*
G01X232701Y1108159D01*
X232607Y1108188D01*
X232303Y1108492D01*
X232274Y1108587D01*
X232283Y1108635D01*
G03X232304Y1108858I-1181J224D01*
G03X229900I-1202J0D01*
G03X229909Y1108714I1202J3D01*
G01X229914Y1108666D01*
X229883Y1108578D01*
X229582Y1108290D01*
X229493Y1108263D01*
X229445Y1108271D01*
G03X229230Y1108289I-216J-1284D01*
G03X229018Y1108272I-2J-1302D01*
G01X228970Y1108264D01*
X228881Y1108291D01*
X228581Y1108579D01*
X228550Y1108666D01*
X228555Y1108714D01*
G03X228564Y1108858I-1193J147D01*
G03X227362Y1107656I-1202J0D01*
G03X227504Y1107664I3J1202D01*
G01X227552Y1107670D01*
X227639Y1107639D01*
X227926Y1107338D01*
X227954Y1107249D01*
X227946Y1107201D01*
G03X227928Y1106987I1284J-216D01*
G01Y1106710D01*
G02X227862Y1106562I-200J0D01*
G01X227609Y1106334D01*
X227529Y1106308D01*
X227487Y1106313D01*
G03X227362Y1106319I-120J-1196D01*
G03Y1103915I0J-1202D01*
G03X227486Y1103921I4J1202D01*
G01X227529Y1103926D01*
X227608Y1103900D01*
X227861Y1103672D01*
G02X227927Y1103524I-134J-148D01*
G01Y1103247D01*
G03X227945Y1103033I1303J2D01*
G01X227952Y1102986D01*
X227925Y1102897D01*
X227638Y1102597D01*
X227551Y1102565D01*
X227503Y1102571D01*
G03X227362Y1102579I-138J-1194D01*
G03Y1100175I0J-1202D01*
G03X227584Y1100196I-2J1202D01*
G01X227633Y1100205D01*
X227726Y1100176D01*
X228031Y1099871D01*
X228060Y1099778D01*
X228051Y1099729D01*
G03X228030Y1099507I1181J-224D01*
G03X228051Y1099285I1202J2D01*
G01X228060Y1099236D01*
X228031Y1099143D01*
X227726Y1098838D01*
X227633Y1098809D01*
X227584Y1098818D01*
G03X227362Y1098839I-224J-1181D01*
G03Y1096435I0J-1202D01*
G03X227584Y1096456I-2J1202D01*
G01X227633Y1096465D01*
X227726Y1096436D01*
X228031Y1096131D01*
X228060Y1096038D01*
X228051Y1095989D01*
G03X228030Y1095767I1181J-224D01*
G03X228051Y1095545I1202J2D01*
G01X228060Y1095496D01*
X228031Y1095403D01*
X227726Y1095098D01*
X227633Y1095069D01*
X227584Y1095078D01*
G03X227362Y1095099I-224J-1181D01*
G03Y1092695I0J-1202D01*
G03X227584Y1092716I-2J1202D01*
G01X227633Y1092725D01*
X227726Y1092696D01*
X228031Y1092391D01*
X228060Y1092298D01*
X228051Y1092249D01*
G03X228030Y1092027I1181J-224D01*
G03X228051Y1091805I1202J2D01*
G01X228060Y1091756D01*
X228031Y1091663D01*
X227726Y1091358D01*
X227633Y1091329D01*
X227584Y1091338D01*
G03X227362Y1091359I-224J-1181D01*
G03Y1088955I0J-1202D01*
G03X227584Y1088976I-2J1202D01*
G01X227633Y1088985D01*
X227726Y1088956D01*
X228031Y1088651D01*
X228060Y1088558D01*
X228051Y1088509D01*
G03X228030Y1088287I1181J-224D01*
G03X228051Y1088065I1202J2D01*
G01X228060Y1088016D01*
X228031Y1087923D01*
X227726Y1087618D01*
X227633Y1087589D01*
X227584Y1087598D01*
G03X227362Y1087619I-224J-1181D01*
G03Y1085215I0J-1202D01*
G03X227504Y1085223I3J1202D01*
G01X227552Y1085229D01*
X227639Y1085198D01*
X227926Y1084897D01*
X227954Y1084808D01*
X227946Y1084760D01*
G03X227928Y1084546I1284J-216D01*
G01Y1084270D01*
G02X227862Y1084122I-200J0D01*
G01X227609Y1083894D01*
X227529Y1083868D01*
X227487Y1083873D01*
G03X227362Y1083879I-120J-1196D01*
G03Y1081475I0J-1202D01*
G03X227487Y1081481I5J1202D01*
G01X227529Y1081486D01*
X227609Y1081460D01*
X227862Y1081232D01*
G02X227928Y1081084I-134J-148D01*
G01Y1080806D01*
G03X227936Y1080659I1302J-3D01*
G01X227941Y1080614D01*
X227912Y1080528D01*
X227628Y1080242D01*
X227543Y1080212D01*
X227497Y1080216D01*
G03X227362Y1080224I-144J-1279D01*
G03Y1077648I0J-1288D01*
G03X227577Y1077667I-5J1288D01*
G01X227624Y1077674D01*
X227714Y1077647D01*
X228015Y1077357D01*
X228046Y1077268D01*
X228040Y1077221D01*
G03X228030Y1077066I1192J-155D01*
G03X228040Y1076911I1202J0D01*
G01X228046Y1076864D01*
X228015Y1076775D01*
X227714Y1076485D01*
X227624Y1076458D01*
X227577Y1076465D01*
G03X227362Y1076484I-220J-1269D01*
G03Y1073908I0J-1288D01*
G03X227577Y1073927I-5J1288D01*
G01X227624Y1073934D01*
X227714Y1073907D01*
X228015Y1073617D01*
X228046Y1073528D01*
X228040Y1073481D01*
G03X228030Y1073326I1192J-155D01*
G03X228051Y1073103I1202J1D01*
G01X228060Y1073055D01*
X228031Y1072960D01*
X227727Y1072656D01*
X227632Y1072627D01*
X227584Y1072636D01*
G03X227361Y1072657I-224J-1181D01*
G03Y1070253I0J-1202D01*
G03X228398Y1070847I0J1202D01*
G01X228425Y1070893D01*
X228517Y1070946D01*
X228570D01*
G02X228770Y1070746I0J-200D01*
G01Y1070244D01*
X228757Y1070209D01*
G03X228490Y1068787I3660J-1423D01*
G01Y1047860D01*
G02X228480Y1047796I-200J-2D01*
G01X217396Y1015051D01*
G02X217348Y1014973I-190J63D01*
G01X203008Y1000633D01*
G02X202866Y1000574I-142J141D01*
G01X183323D01*
G03X183218Y1000544I0J-200D01*
G01X183194Y1000530D01*
X183169Y1000523D01*
G02X183114Y1000515I-56J192D01*
G01X6775D01*
X6701Y1000545D01*
X6673Y1000574D01*
X5840Y1001407D01*
G02X5781Y1001549I141J142D01*
G01Y1063417D01*
G02X5837Y1063556I200J0D01*
G01X6057Y1063784D01*
X6126Y1063816D01*
X6166Y1063817D01*
G03Y1066819I-58J1501D01*
G01X6126Y1066820D01*
X6057Y1066852D01*
X5837Y1067080D01*
G02X5781Y1067219I144J139D01*
G01Y1068710D01*
G02X5837Y1068849I200J0D01*
G01X6057Y1069077D01*
X6126Y1069109D01*
X6166Y1069110D01*
G03Y1072112I-58J1501D01*
G01X6126Y1072113D01*
X6057Y1072145D01*
X5837Y1072373D01*
G02X5781Y1072512I144J139D01*
G01Y1074089D01*
G02X5839Y1074230I200J0D01*
G01X6065Y1074458D01*
X6137Y1074489D01*
X6177D01*
G03Y1077493I-16J1502D01*
G01X6137D01*
X6065Y1077524D01*
X5839Y1077752D01*
G02X5781Y1077893I142J141D01*
G01Y1079407D01*
G02X5835Y1079544I200J0D01*
G01X6048Y1079772D01*
X6115Y1079804D01*
X6154Y1079806D01*
G03Y1082804I-101J1499D01*
G01X6115Y1082806D01*
X6048Y1082838D01*
X5835Y1083066D01*
G02X5781Y1083203I146J137D01*
G01Y1084648D01*
G02X5835Y1084785I200J0D01*
G01X6048Y1085013D01*
X6116Y1085045D01*
X6154Y1085047D01*
G03Y1088045I-99J1499D01*
G01X6116Y1088047D01*
X6048Y1088079D01*
X5835Y1088307D01*
G02X5781Y1088444I146J137D01*
G01Y1090066D01*
G02X5835Y1090203I200J0D01*
G01X6049Y1090431D01*
X6116Y1090463D01*
X6155Y1090465D01*
G03X7561Y1091964I-96J1499D01*
G03X6155Y1093463I-1502J0D01*
G01X6116Y1093465D01*
X6049Y1093497D01*
X5835Y1093725D01*
G02X5781Y1093862I146J137D01*
G01Y1153346D01*
G02X5838Y1153486I200J0D01*
G01X5839Y1153487D01*
X10588Y1158236D01*
G02X10590Y1158238I142J-140D01*
G02X10730Y1158295I140J-143D01*
G01X73853D01*
X73854D01*
G03X73930Y1158310I0J200D01*
G01X74034Y1158354D01*
X94055D01*
G02X94196Y1158295I-1J-200D01*
G01X94489Y1158003D01*
G03X94630Y1157944I142J141D01*
G01X109935D01*
G03X110076Y1158003I-1J200D01*
G01X110369Y1158295D01*
G02X110510Y1158354I142J-141D01*
G01X142476D01*
G02X142581Y1158325I1J-200D01*
G03X143208Y1158148I628J1025D01*
G03X143835Y1158325I-1J1202D01*
G02X143940Y1158354I104J-171D01*
G01X146216D01*
G02X146321Y1158325I1J-200D01*
G03X146948Y1158148I628J1025D01*
G03X147575Y1158325I-1J1202D01*
G02X147680Y1158354I104J-171D01*
G01X149957D01*
G02X150062Y1158325I1J-200D01*
G03X150689Y1158148I628J1025D01*
G03X151316Y1158325I-1J1202D01*
G02X151421Y1158354I104J-171D01*
G01X161177D01*
G02X161282Y1158325I1J-200D01*
G03X161909Y1158148I628J1025D01*
G03X162536Y1158325I-1J1202D01*
G02X162641Y1158354I104J-171D01*
G01X164584D01*
X164715Y1158303D01*
X164742Y1158281D01*
X164743Y1158280D01*
G03X166555I906J1070D01*
G01X166556Y1158281D01*
X166583Y1158303D01*
G37*
G36*
G01X86905Y201587D02*
G02X86950Y201695I199J-20D01*
G01X86956Y201702D01*
X87533Y202279D01*
G02X87634Y202332I140J-143D01*
G01X87636D01*
G02X87673Y202336I40J-196D01*
G01X97385D01*
G02X97546Y202236I-13J-200D01*
G01X97614Y202107D01*
X97720Y201904D01*
G02X97737Y201812I-183J-81D01*
G01X97734Y201758D01*
X97702Y201711D01*
G03X97442Y200907I1242J-846D01*
G01Y200905D01*
G03X97441Y200873I1500J-63D01*
G01Y200845D01*
G03X100445I1502J19D01*
G01Y200866D01*
G03X100184Y201711I-1502J-1D01*
G01X100178Y201719D01*
G02X100149Y201814I171J104D01*
G01X100146Y201867D01*
X100343Y202241D01*
G02X100501Y202336I171J-105D01*
G01X104025D01*
G02X104166Y202278I0J-200D01*
G01X106206Y200238D01*
X106221Y200207D01*
G03X106276Y200105I1349J661D01*
G01X106289Y200082D01*
X106305Y200027D01*
X106312Y200002D01*
G02X106318Y199955I-194J-49D01*
G01Y197596D01*
G02X106285Y197490I-200J4D01*
G03Y195840I1254J-825D01*
G02X106318Y195734I-167J-110D01*
G01Y193596D01*
G02X106285Y193490I-200J4D01*
G03Y191840I1254J-825D01*
G02X106318Y191734I-167J-110D01*
G01Y187512D01*
G02X106317Y187493I-200J1D01*
G01X106307Y187472D01*
G03Y186084I1345J-694D01*
G01X106317Y186063D01*
G02X106318Y186046I-199J-20D01*
G01Y181596D01*
G02X106285Y181490I-200J4D01*
G03Y179840I1254J-825D01*
G02X106318Y179734I-167J-110D01*
G01Y177596D01*
G02X106285Y177490I-200J4D01*
G03Y175840I1254J-825D01*
G02X106318Y175734I-167J-110D01*
G01Y173596D01*
G02X106285Y173490I-200J4D01*
G03Y171840I1254J-825D01*
G02X106318Y171734I-167J-110D01*
G01Y169596D01*
G02X106285Y169490I-200J4D01*
G03Y167840I1254J-825D01*
G02X106318Y167734I-167J-110D01*
G01Y163084D01*
G02X106316Y163057I-200J1D01*
G02X106270Y162956I-198J29D01*
G01X106198Y162880D01*
G02X106164Y162854I-138J145D01*
G01X106057Y162801D01*
X106024Y162797D01*
G03Y159815I181J-1491D01*
G01X106057Y159811D01*
X106164Y159758D01*
G02X106198Y159732I-104J-171D01*
G01X106270Y159656D01*
G02X106316Y159555I-152J-130D01*
G02X106318Y159528I-198J-28D01*
G01Y151308D01*
G02X106118Y151108I-200J0D01*
G01X99544D01*
G02X99372Y151206I0J200D01*
G01X99197Y151532D01*
G02X99178Y151619I181J85D01*
G01X99179Y151654D01*
X99195Y151705D01*
X99211Y151729D01*
G03X99463Y152562I-1251J833D01*
G03X97961Y154064I-1502J0D01*
G03X96672Y153333I0J-1502D01*
G01X96666Y153324D01*
X96521Y153228D01*
G02X96511Y153226I-44J195D01*
G01X96168Y153207D01*
G02X96080Y153225I-5J200D01*
G01X96058Y153235D01*
X96021Y153264D01*
X96005Y153285D01*
G03X94811Y153875I-1194J-913D01*
G03X93309Y152373I0J-1502D01*
G03X93474Y151689I1502J0D01*
G01X93475Y151688D01*
G02X93496Y151590I-179J-90D01*
G01X93494Y151539D01*
X93288Y151203D01*
G02X93282Y151194I-169J106D01*
G03X93280Y151192I139J-141D01*
G02X93118Y151108I-163J116D01*
G01X83801D01*
G02X83662Y151165I1J200D01*
G01X82535Y152293D01*
G03X81119Y152879I-1415J-1416D01*
G03X81053Y152878I-3J-2002D01*
G01X74759D01*
G03X73344Y152292I0J-2001D01*
G01X70007Y148956D01*
G03X69421Y147578I1415J-1415D01*
G01X69420Y147540D01*
G03X71418Y145538I2002J0D01*
G01X71460Y145539D01*
G03X72838Y146125I-37J2001D01*
G01X73175Y146463D01*
X75531Y148819D01*
G02X75548Y148834I141J-142D01*
G02X75653Y148875I122J-159D01*
G02X75671Y148876I20J-199D01*
G01X78150D01*
G02X78188Y148872I-2J-200D01*
G02X78233Y148858I-36J-197D01*
G01X78268Y148841D01*
X78298Y148809D01*
X78299Y148807D01*
X78472Y148617D01*
X78510Y148575D01*
X78525Y148558D01*
X78551Y148479D01*
X78547Y148435D01*
G03X78539Y148277I1494J-155D01*
G03X80041Y146775I1502J0D01*
G03X81231Y147360I0J1503D01*
G01X81255Y147391D01*
X81286Y147409D01*
G02X81344Y147433I105J-171D01*
G01X81505Y147459D01*
X81626Y147479D01*
G02X81694Y147478I31J-198D01*
G01X81738Y147468D01*
X81739Y147467D01*
G03X82888Y147104I1150J1639D01*
G01X106118D01*
G02X106259Y147045I-1J-200D01*
G02X106318Y146904I-141J-142D01*
G01Y124540D01*
X106315Y124524D01*
G03X106296Y124283I1483J-238D01*
G03X106315Y124042I1502J-3D01*
G01X106318Y124026D01*
Y120780D01*
G02X106307Y120724I-200J10D01*
G01X106264Y120618D01*
X106241Y120592D01*
G03Y118596I1124J-998D01*
G01X106264Y118570D01*
X106307Y118464D01*
G02X106318Y118408I-189J-66D01*
G01Y117780D01*
G02X106307Y117724I-200J10D01*
G01X106264Y117618D01*
X106241Y117592D01*
G03Y115596I1124J-998D01*
G01X106264Y115570D01*
X106307Y115464D01*
G02X106318Y115408I-189J-66D01*
G01Y114580D01*
G02X106307Y114524I-200J10D01*
G01X106264Y114418D01*
X106241Y114392D01*
G03Y112396I1124J-998D01*
G01X106264Y112370D01*
X106307Y112264D01*
G02X106318Y112208I-189J-66D01*
G01Y111580D01*
G02X106307Y111524I-200J10D01*
G01X106264Y111418D01*
X106241Y111392D01*
G03X105862Y110419I1124J-998D01*
G01Y110393D01*
G03X106062Y109644I1502J0D01*
G01X106075Y109622D01*
X106090Y109567D01*
G02X106039Y109372I-193J-54D01*
G01X105195Y108528D01*
G02X105128Y108484I-141J142D01*
G01X105094Y108470D01*
X68631D01*
G02X68541Y108492I1J200D01*
G01X68452Y108542D01*
G02X68412Y108573I102J172D01*
G01X68395Y108589D01*
X68382Y108610D01*
G03X65330I-1526J-961D01*
G01X65317Y108589D01*
X65300Y108573D01*
G02X65260Y108542I-142J141D01*
G01X65171Y108492D01*
G02X65081Y108470I-91J178D01*
G01X49370D01*
G02X49229Y108529I1J200D01*
G01X47425Y110333D01*
X47418Y110342D01*
G03X47172Y110588I-1178J-932D01*
G01X47163Y110595D01*
X46476Y111282D01*
G02X46417Y111423I141J142D01*
G01Y114907D01*
X46504Y115015D01*
X46573Y115031D01*
G03Y117961I-333J1465D01*
G01X46504Y117977D01*
X46417Y118085D01*
Y159263D01*
G02X46420Y159295I200J-3D01*
G01Y159297D01*
G02X46474Y159403I197J-34D01*
G01X47341Y160270D01*
G02X47447Y160324I140J-143D01*
G01X47449D01*
G02X47481Y160327I35J-197D01*
G01X82998D01*
G03X83140Y160386I0J200D01*
G01X86845Y164091D01*
G03X86904Y164233I-141J142D01*
G01Y201565D01*
X86905Y201587D01*
G37*
G36*
G01X46228Y275950D02*
X81475D01*
G02X81617Y275891I0J-200D01*
G01X82049Y275459D01*
G02X82051Y275457I-140J-142D01*
G02X82108Y275317I-143J-140D01*
G01Y267385D01*
G02X81995Y267205I-200J0D01*
G01X81618Y267023D01*
X81505Y267036D01*
X81459Y267072D01*
G03X80525Y267398I-934J-1175D01*
G03Y264394I0J-1502D01*
G03X81459Y264720I0J1501D01*
G01X81505Y264756D01*
X81618Y264769D01*
X81995Y264587D01*
G02X82108Y264407I-87J-180D01*
G01Y257901D01*
X82054Y257809D01*
X82009Y257782D01*
X82007D01*
X81719Y257613D01*
G02X81645Y257588I-100J174D01*
G01X81604Y257583D01*
X81511Y257608D01*
X81489Y257620D01*
G03X80767Y257805I-723J-1319D01*
G01X80766D01*
G03Y254801I0J-1502D01*
G01X80767D01*
G03X81489Y254986I-1J1504D01*
G01X81511Y254998D01*
X81565Y255013D01*
G02X81645Y255018I52J-193D01*
G01X81684Y255013D01*
X82008Y254824D01*
G02X82011Y254822I-109J-167D01*
G02X82108Y254651I-103J-171D01*
G01Y207215D01*
G02X82106Y207189I-200J2D01*
G01X82101Y207148D01*
X82098Y207137D01*
G03X82050Y206760I1454J-377D01*
G01Y206691D01*
G03X82051Y206670I200J-1D01*
G01X82058Y206603D01*
G03X82063Y206560I1494J152D01*
G01X82072Y206495D01*
G03X82076Y206476I197J32D01*
G01Y206475D01*
X82092Y206407D01*
G03X82097Y206388I1455J373D01*
G01Y206384D01*
G03X82101Y206371I1437J435D01*
G01X82108Y206345D01*
Y203071D01*
G03X82167Y202929I200J0D01*
G01X82784Y202312D01*
G03X82926Y202253I142J141D01*
G01X85417D01*
G02X85450Y202250I-2J-200D01*
G02X85557Y202196I-32J-197D01*
G01X85844Y201909D01*
G02X85903Y201767I-141J-142D01*
G01Y201591D01*
G03X85902Y201569I1200J-66D01*
G01Y193725D01*
G02X85816Y193561I-200J0D01*
G01X85566Y193386D01*
G02X85452Y193350I-114J164D01*
G01X85365D01*
X85334Y193361D01*
G03X84844Y193443I-490J-1420D01*
G01X84828D01*
G03X83342Y191941I16J-1502D01*
G03X84844Y190439I1502J0D01*
G01X84847D01*
G03X85365Y190532I-2J1502D01*
G01X85411Y190549D01*
X85508Y190537D01*
X85816Y190321D01*
G02X85902Y190157I-114J-164D01*
G01Y165175D01*
G02X85843Y165033I-200J0D01*
G01X82377Y161567D01*
X82349Y161538D01*
X82275Y161508D01*
X75261D01*
G02X75090Y161604I0J200D01*
G01X74913Y161896D01*
G02X74897Y161930I172J102D01*
G02X74908Y162094I188J70D01*
G01X74911Y162100D01*
X74928Y162135D01*
G03X75080Y162788I-1350J658D01*
G01Y162790D01*
Y162815D01*
G03X74677Y163817I-1502J-22D01*
G01X74676Y163818D01*
G02X74620Y163957I144J139D01*
G01Y164268D01*
X74647Y164338D01*
X74674Y164366D01*
G03Y166420I-1096J1027D01*
G01X74647Y166448D01*
X74620Y166518D01*
Y166868D01*
X74647Y166938D01*
X74674Y166966D01*
G03X75080Y167993I-1096J1027D01*
G03X74710Y168980I-1501J0D01*
G01X74686Y169008D01*
X74661Y169074D01*
Y169412D01*
X74686Y169478D01*
X74710Y169506D01*
G03X75080Y170493I-1131J987D01*
G03X72076I-1502J0D01*
G03X72446Y169506I1501J0D01*
G01X72470Y169478D01*
X72495Y169412D01*
Y169074D01*
X72470Y169008D01*
X72446Y168980D01*
G03X72076Y167993I1131J-987D01*
G03X72482Y166966I1502J0D01*
G01X72509Y166938D01*
X72536Y166868D01*
Y166518D01*
X72509Y166448D01*
X72482Y166420D01*
G03Y164366I1096J-1027D01*
G01X72509Y164338D01*
X72536Y164268D01*
Y163918D01*
X72509Y163849D01*
X72482Y163820D01*
G03X72076Y162821I1096J-1027D01*
G01Y162793D01*
G03X72228Y162134I1502J-1D01*
G01X72257Y162073D01*
G02X72259Y161930I-186J-74D01*
G02X72243Y161896I-188J68D01*
G01X72066Y161605D01*
X72039Y161559D01*
X71948Y161508D01*
X68324D01*
G02X68166Y161585I0J200D01*
G01X67943Y161870D01*
X67924Y161959D01*
X67935Y162005D01*
G03X67980Y162368I-1457J365D01*
G03X66478Y163870I-1502J0D01*
G03X65451Y163464I0J-1502D01*
G01X65423Y163437D01*
X65353Y163410D01*
X65003D01*
X64933Y163437D01*
X64905Y163464D01*
G03X63878Y163870I-1027J-1096D01*
G03X62376Y162368I0J-1502D01*
G03X62421Y162005I1502J2D01*
G01X62432Y161959D01*
X62413Y161870D01*
X62190Y161585D01*
G02X62032Y161508I-158J123D01*
G01X46884D01*
G02X46742Y161567I0J200D01*
G01X46673Y161636D01*
G02X46615Y161757I141J142D01*
G01Y161758D01*
G02X46716Y161952I199J20D01*
G01X46717Y161953D01*
G03X47486Y163264I-733J1311D01*
G03X46199Y164751I-1503J0D01*
G01X46125Y164762D01*
X46028Y164874D01*
Y275750D01*
G02X46228Y275950I200J0D01*
G37*
G36*
G01X137657Y54588D02*
X166715D01*
X166891Y54412D01*
Y52762D01*
X166720Y52591D01*
X137657D01*
G03X131720Y46654I0J-5937D01*
G01Y7874D01*
G02X125846Y2000I-5874J0D01*
G01X78602D01*
G02X72728Y7874I0J5874D01*
G01Y45793D01*
X74726D01*
Y7874D01*
G03X78602Y3998I3876J0D01*
G01X125846D01*
G03X129722Y7874I0J3876D01*
G01Y46654D01*
G02X137657Y54588I7935J-1D01*
G37*
G36*
G01X83310Y275932D02*
X105245D01*
X105319Y275902D01*
X105347Y275873D01*
X105958Y275262D01*
G02X106017Y275120I-141J-142D01*
G01Y205020D01*
X105987Y204946D01*
X105958Y204918D01*
X104437Y203397D01*
G02X104295Y203338I-142J141D01*
G01X83428D01*
X83354Y203368D01*
X83326Y203397D01*
X83168Y203555D01*
G02X83110Y203696I142J141D01*
G01Y204858D01*
G02X83170Y205001I200J0D01*
G01X83404Y205230D01*
X83478Y205259D01*
X83518Y205258D01*
X83552D01*
G03Y208262I0J1502D01*
G01X83518D01*
X83478Y208261D01*
X83404Y208290D01*
X83170Y208519D01*
G02X83110Y208661I140J143D01*
G01Y255107D01*
G02X83228Y255289I200J0D01*
G01X83552Y255436D01*
G02X83723Y255432I81J-183D01*
G01X83773Y255407D01*
X83792Y255392D01*
G03X84766Y255033I975J1143D01*
G03Y258037I0J1502D01*
G03X83792Y257678I1J-1502D01*
G01X83773Y257663D01*
X83723Y257638D01*
G02X83552Y257634I-90J179D01*
G01X83228Y257781D01*
G02X83110Y257963I82J182D01*
G01Y275732D01*
G02X83310Y275932I200J0D01*
G37*
G36*
G01X96681Y1184756D02*
X109606D01*
G02X109748Y1184697I0J-200D01*
G01X109946Y1184499D01*
G02X110005Y1184357I-141J-142D01*
G01Y1179470D01*
G02X109919Y1179306I-200J0D01*
G01X109607Y1179090D01*
X109510Y1179078D01*
X109464Y1179096D01*
G03X108933Y1179193I-531J-1405D01*
G03Y1176189I0J-1502D01*
G03X109464Y1176286I0J1502D01*
G01X109510Y1176304D01*
X109607Y1176292D01*
X109919Y1176076D01*
G02X110005Y1175912I-114J-164D01*
G01Y1166870D01*
G02X109919Y1166706I-200J0D01*
G01X109607Y1166490D01*
X109510Y1166478D01*
X109464Y1166496D01*
G03X108933Y1166593I-531J-1405D01*
G03Y1163589I0J-1502D01*
G03X109464Y1163686I0J1502D01*
G01X109510Y1163704D01*
X109607Y1163692D01*
X109919Y1163476D01*
G02X110005Y1163312I-114J-164D01*
G01Y1159431D01*
G02X109946Y1159289I-200J0D01*
G01X109662Y1159005D01*
G02X109520Y1158946I-142J141D01*
G01X95045D01*
G02X94903Y1159005I0J200D01*
G01X93987Y1159921D01*
G02X93928Y1160063I141J142D01*
G01Y1182003D01*
G02X93987Y1182145I200J0D01*
G01X96539Y1184697D01*
G02X96681Y1184756I142J-141D01*
G37*
G36*
G01X147438Y110661D02*
G03X147446Y110603I200J-2D01*
G02X147454Y110523I-191J-59D01*
G01X147441Y110412D01*
X147402Y110314D01*
G03X147100Y109410I1202J-904D01*
G03X148602Y107908I1502J0D01*
G03X149534Y108232I0J1502D01*
G01X149658Y108275D01*
G02X149799Y108217I0J-200D01*
G01X150368Y107648D01*
G03X150510Y107589I142J141D01*
G01X151246D01*
X151255Y107588D01*
X167230D01*
G02X167359Y107528I-14J-199D01*
G02X167416Y107389I-143J-140D01*
G01Y104249D01*
G03X167449Y103902I1802J-4D01*
G01Y103900D01*
G03X167450Y103896I1748J435D01*
G02X167452Y103887I-194J-48D01*
G01X167454Y103879D01*
G02X167450Y103797I-198J-31D01*
G02X167442Y103772I-194J48D01*
G01X167420Y103719D01*
X167386Y103695D01*
X167353Y103672D01*
G02X167330Y103658I-115J164D01*
G01X167291Y103649D01*
G03X166460Y103888I-831J-1325D01*
G03X168025Y102323I0J-1565D01*
G03X167989Y102654I-1565J-3D01*
G02X168035Y102698I160J-121D01*
G01X168057Y102713D01*
G02X168161Y102746I110J-167D01*
G01X168218Y102747D01*
X168270Y102715D01*
G03X169252Y102446I948J1534D01*
G01X169265Y102447D01*
G03X171020Y104247I-47J1801D01*
G01Y107389D01*
G02X171077Y107528I200J-1D01*
G02X171206Y107588I143J-139D01*
G01X207476D01*
G02X207604Y107530I-13J-199D01*
G01X209040Y106094D01*
G02X209093Y105993I-143J-140D01*
G01Y105991D01*
G02X209097Y105954I-196J-40D01*
G01Y98359D01*
G02X209029Y98209I-200J0D01*
G01X208772Y97982D01*
X208690Y97957D01*
X208648Y97963D01*
G03X208463Y97974I-181J-1491D01*
G03X206961Y96472I0J-1502D01*
G03X206971Y96299I1501J0D01*
G01X206976Y96256D01*
X206950Y96173D01*
X206717Y95918D01*
G02X206565Y95853I-148J135D01*
G01X206533D01*
G03X208035Y94351I0J-1502D01*
G03X208025Y94524I-1501J0D01*
G01X208020Y94567D01*
X208046Y94650D01*
X208279Y94905D01*
G02X208431Y94970I148J-135D01*
G01X208463D01*
G03X208574Y94974I1J1502D01*
G01X208620Y94977D01*
X208704Y94944D01*
X208948Y94680D01*
G02X208998Y94514I-148J-135D01*
G01Y94513D01*
G03X208980Y94296I1484J-232D01*
G01Y94282D01*
G03X209083Y93731I1502J-4D01*
G01X209097Y93696D01*
Y87622D01*
G02X209064Y87515I-200J3D01*
G01X209062Y87514D01*
Y87513D01*
X208972Y87441D01*
X208946Y87430D01*
G03Y84662I584J-1384D01*
G01X208972Y84651D01*
X209062Y84579D01*
Y84578D01*
X209064Y84577D01*
G02X209097Y84470I-167J-110D01*
G01Y62270D01*
G02X209036Y62127I-200J1D01*
G01X208875Y61970D01*
X208830Y61926D01*
G02X208764Y61883I-140J143D01*
G01X208728Y61869D01*
X208686Y61870D01*
G03X208646Y61871I-58J-1501D01*
G01X208644D01*
G03X207593Y61441I1J-1502D01*
G01X207589Y61437D01*
G02X207523Y61396I-137J146D01*
G01X207486Y61382D01*
X207295Y61392D01*
X207148Y61399D01*
G02X207068Y61420I10J200D01*
G01X207032Y61438D01*
X207005Y61471D01*
G03X205848Y62015I-1157J-958D01*
G03Y59011I0J-1502D01*
G03X206900Y59441I0J1502D01*
G01X206904Y59445D01*
G02X206970Y59486I137J-146D01*
G01X207007Y59500D01*
X207198Y59490D01*
X207345Y59483D01*
G02X207425Y59462I-10J-200D01*
G01X207460Y59445D01*
X207488Y59411D01*
G03X208645Y58867I1157J958D01*
G01X208694D01*
X208732Y58868D01*
X208764Y58855D01*
G02X208829Y58812I-76J-185D01*
G01X209036Y58611D01*
G02X209097Y58468I-139J-144D01*
G01Y54040D01*
G02X209075Y53949I-200J0D01*
G02X209039Y53899I-178J90D01*
G01X207835Y52695D01*
G02X207785Y52659I-140J142D01*
G02X207694Y52637I-91J178D01*
G01X189164D01*
G02X189073Y52659I0J200D01*
G02X189023Y52695I90J178D01*
G01X183881Y57837D01*
G03X183784Y57891I-142J-141D01*
G01X183774Y57893D01*
G02X183667Y57968I55J193D01*
G01X183465Y58269D01*
G02X183437Y58352I171J104D01*
G01X183432Y58400D01*
X183451Y58446D01*
G03X184071Y61613I-7782J3168D01*
G01Y61614D01*
G03X167267I-8402J0D01*
G03X167887Y58447I8402J1D01*
G01Y58446D01*
G02X167901Y58351I-185J-76D01*
G01X167896Y58302D01*
X167682Y57984D01*
G02X167517Y57896I-166J112D01*
G01X160370D01*
G02X160336Y57899I1J200D01*
G02X160275Y57920I34J197D01*
G01Y57921D01*
G02X160193Y58005I96J175D01*
G01X160032Y58323D01*
G02X160010Y58429I177J92D01*
G01X160013Y58458D01*
X160031Y58508D01*
X160048Y58531D01*
G03X160756Y60709I-2993J2177D01*
G01Y60710D01*
G03X160327Y62439I-3701J-1D01*
G01X160326Y62441D01*
G02X160304Y62535I178J91D01*
G01Y62583D01*
X160487Y62922D01*
G02X160489Y62925I167J-109D01*
G02X160521Y62968I175J-97D01*
G02X160554Y62995I143J-141D01*
G01X160593Y63020D01*
X160644Y63025D01*
G03X162571Y69857I-349J3786D01*
G03X156951Y65001I-2276J-3046D01*
G01Y65000D01*
X156952D01*
X156957Y64990D01*
G02X156975Y64902I-182J-83D01*
G01X156974Y64849D01*
X156771Y64508D01*
G02X156729Y64458I-172J102D01*
G02X156599Y64410I-130J152D01*
G01X149755D01*
G03X146054Y60709I0J-3701D01*
G01Y60707D01*
G03X146762Y58531I3701J1D01*
G01X146779Y58508D01*
X146797Y58458D01*
X146800Y58429D01*
G02X146778Y58323I-199J-14D01*
G01X146756Y58280D01*
X146610Y57992D01*
G02X146548Y57930I-169J107D01*
G01X146525Y57917D01*
G02X146437Y57896I-89J179D01*
G01X145904D01*
G02X145779Y57940I0J200D01*
G03X145777Y57942I-142J-140D01*
G02X145763Y57954I123J158D01*
G01X131218Y72499D01*
G02X131186Y72542I143J140D01*
G01Y72543D01*
G02X131176Y72711I176J95D01*
G01X131310Y73052D01*
G02X131371Y73136I187J-72D01*
G01X131382Y73143D01*
G02X131482Y73179I115J-164D01*
G03X139583Y81575I-300J8396D01*
G03X131181Y89977I-8402J0D01*
G03X122785Y81887I0J-8402D01*
G01X122784Y81873D01*
G02X122749Y81776I-199J17D01*
G01X122699Y81726D01*
G02X122658Y81704I-114J164D01*
G01X122476Y81632D01*
X122317Y81570D01*
G02X122135Y81588I-73J186D01*
G01X122117Y81600D01*
X107955Y95762D01*
G02X107911Y95829I142J141D01*
G01X107897Y95863D01*
Y108858D01*
G02X107916Y108943I200J0D01*
G01X108011Y109038D01*
X108040Y109052D01*
G03X108565Y109492I-677J1341D01*
G01X108589Y109524D01*
X108622Y109544D01*
G02X108685Y109568I102J-172D01*
G01X108964Y109609D01*
X109015Y109617D01*
X109090Y109598D01*
X109123Y109574D01*
Y109573D01*
G03X110010Y109282I889J1211D01*
G01X110013D01*
G03X111321Y110045I0J1503D01*
G02X111346Y110075I166J-113D01*
G01X111364Y110093D01*
X111387Y110106D01*
G02X111487Y110133I100J-173D01*
G01X111833D01*
G02X111845Y110132I-11J-199D01*
G01X111849D01*
G02X111926Y110110I-15J-199D01*
G01X111956Y110093D01*
X111992Y110056D01*
X112006Y110033D01*
X112007Y110031D01*
G03X113307Y109282I1300J754D01*
G03Y112286I0J1502D01*
G03X111998Y111522I0J-1503D01*
G02X111844Y111435I-165J113D01*
G01X111476D01*
G02X111322Y111522I11J200D01*
G03X110013Y112286I-1309J-739D01*
G03X108820Y111696I0J-1501D01*
G01X108818Y111693D01*
G02X108806Y111680I-153J129D01*
G01X108772Y111646D01*
G02X108681Y111608I-120J160D01*
G01X108420Y111569D01*
X108418D01*
X108400Y111566D01*
G02X108325Y111571I-24J198D01*
G01X108324D01*
X108287Y111580D01*
X108254Y111604D01*
G03X108244Y111611I-866J-1226D01*
G03X108240Y111615I-142J-138D01*
G03X108217Y111630I-832J-1251D01*
G02X108209Y111636I116J163D01*
G03X108205Y111639I-903J-1199D01*
G01X108183Y111654D01*
X108170Y111668D01*
G02X108148Y111698I150J133D01*
G01X108095Y111796D01*
G02X108074Y111883I179J89D01*
G01Y111905D01*
G02X108095Y111992I200J-2D01*
G01X108148Y112090D01*
G02X108170Y112120I172J-103D01*
G01X108183Y112134D01*
X108205Y112149D01*
G03X108866Y113394I-842J1245D01*
G03X108011Y114750I-1503J0D01*
G01X108010Y114751D01*
G02X107927Y114824I85J181D01*
G01X107912Y114847D01*
X107904Y114875D01*
G02X107897Y114927I193J52D01*
G01Y115058D01*
G02X107928Y115165I200J0D01*
G01X107943Y115188D01*
X107984Y115225D01*
X108011Y115238D01*
G03X108618Y117421I-648J1356D01*
G03X108309Y117762I-1255J-826D01*
G01X108286Y117780D01*
X108220Y117874D01*
Y117875D01*
G02X108210Y117937I190J62D01*
G01Y118254D01*
G02X108212Y118281I200J-1D01*
G02X108287Y118409I198J-30D01*
G03X108866Y119594I-923J1185D01*
G03X108011Y120950I-1503J0D01*
G01X108010Y120951D01*
G02X107927Y121024I85J181D01*
G01X107912Y121047D01*
X107904Y121075D01*
G02X107897Y121127I193J52D01*
G01Y122608D01*
G02X108052Y122802I200J-1D01*
G02X108054Y122803I88J-173D01*
G01X108062Y122804D01*
G03X109300Y124283I-264J1479D01*
G03X108063Y125762I-1503J0D01*
G01X108062D01*
X108049Y125764D01*
G02X107897Y125946I48J195D01*
G01Y131919D01*
G02X107930Y132029I200J0D01*
G02X108018Y132103I167J-110D01*
G01X108356Y132248D01*
G02X108470Y132261I79J-184D01*
G01X108498Y132256D01*
X108550Y132230D01*
X108572Y132209D01*
G03X108705Y132097I1033J1092D01*
G01X108734Y132075D01*
X108753Y132045D01*
G02X108780Y131983I-167J-110D01*
G01X108809Y131855D01*
X108838Y131728D01*
G02X108841Y131657I-195J-44D01*
G01X108837Y131625D01*
X108820Y131592D01*
G03X108650Y130898I1332J-694D01*
G03X111654I1502J0D01*
G03X111054Y132099I-1502J0D01*
G01X111038Y132111D01*
X111015Y132136D01*
X111007Y132149D01*
G02X110979Y132214I167J110D01*
G01X110921Y132469D01*
G02X110918Y132540I195J44D01*
G01X110922Y132571D01*
X110939Y132604D01*
G03X111035Y132831I-1331J697D01*
G01X111037Y132838D01*
X111043Y132856D01*
X111047Y132867D01*
X111068Y132894D01*
G02X111116Y132937I156J-126D01*
G02X111122Y132941I114J-164D01*
G01X111234Y133008D01*
X111236D01*
X111356Y133081D01*
G02X111415Y133102I96J-176D01*
G01X111447Y133108D01*
X111470Y133104D01*
X111486Y133101D01*
G03X111754Y133077I267J1478D01*
G01X111762D01*
G03X113256Y134579I-8J1502D01*
G03X111754Y136081I-1502J0D01*
G01Y136082D01*
G03X110467Y135353I0J-1501D01*
G03X110326Y135046I1286J-777D01*
G01X110324Y135041D01*
Y135040D01*
G02X110249Y134943I-188J68D01*
G01X110005Y134796D01*
G02X109946Y134775I-96J176D01*
G01X109914Y134769D01*
X109875Y134776D01*
G03X109608Y134800I-267J-1478D01*
G01X109607D01*
G03X108572Y134387I0J-1503D01*
G01X108569Y134384D01*
G02X108469Y134334I-136J147D01*
G01X108441Y134329D01*
X108412Y134333D01*
G02X108357Y134347I21J199D01*
G01X108018Y134493D01*
G02X107897Y134676I79J184D01*
G01Y167057D01*
G02X107934Y167173I200J0D01*
G01X107952Y167199D01*
X108001Y167235D01*
X108032Y167246D01*
G03Y170084I-492J1419D01*
G01X108030Y170085D01*
G02X107934Y170157I66J189D01*
G01X107916Y170183D01*
X107907Y170211D01*
G02X107897Y170273I190J62D01*
G01Y171057D01*
G02X107934Y171173I200J0D01*
G01X107952Y171199D01*
X108001Y171235D01*
X108032Y171246D01*
G03Y174084I-492J1419D01*
G01X108030Y174085D01*
G02X107934Y174157I66J189D01*
G01X107916Y174183D01*
X107907Y174211D01*
G02X107897Y174273I190J62D01*
G01Y175057D01*
G02X107934Y175173I200J0D01*
G01X107952Y175199D01*
X108001Y175235D01*
X108032Y175246D01*
G03Y178084I-492J1419D01*
G01X108030Y178085D01*
G02X107934Y178157I66J189D01*
G01X107916Y178183D01*
X107907Y178211D01*
G02X107897Y178273I190J62D01*
G01Y179057D01*
G02X107934Y179173I200J0D01*
G01X107952Y179199D01*
X108001Y179235D01*
X108032Y179246D01*
G03Y182084I-492J1419D01*
G01X108030Y182085D01*
G02X107934Y182157I66J189D01*
G01X107916Y182183D01*
X107907Y182211D01*
G02X107897Y182273I190J62D01*
G01Y185140D01*
G02X107952Y185273I200J-5D01*
G01X108042Y185297D01*
G03Y188259I-388J1481D01*
G01X107952Y188283D01*
G02X107897Y188416I145J138D01*
G01Y191057D01*
G02X107934Y191173I200J0D01*
G01X107952Y191199D01*
X108001Y191235D01*
X108032Y191246D01*
G03Y194084I-492J1419D01*
G01X108030Y194085D01*
G02X107934Y194157I66J189D01*
G01X107916Y194183D01*
X107907Y194211D01*
G02X107897Y194273I190J62D01*
G01Y195057D01*
G02X107934Y195173I200J0D01*
G01X107952Y195199D01*
X108001Y195235D01*
X108032Y195246D01*
G03Y198084I-492J1419D01*
G01X108030Y198085D01*
G02X107934Y198157I66J189D01*
G01X107916Y198183D01*
X107907Y198211D01*
G02X107897Y198273I190J62D01*
G01Y199245D01*
G02X107932Y199358I200J0D01*
G01X107954Y199388D01*
X108004Y199425D01*
X108035Y199435D01*
G03Y202293I-463J1429D01*
G01X108004Y202303D01*
X107954Y202340D01*
X107932Y202370D01*
G02X107897Y202483I165J113D01*
G01Y203245D01*
G02X107932Y203358I200J0D01*
G01X107954Y203388D01*
X108004Y203425D01*
X108035Y203435D01*
G03Y206293I-463J1429D01*
G01X108004Y206303D01*
X107954Y206340D01*
X107932Y206370D01*
G02X107897Y206483I165J113D01*
G01Y207245D01*
G02X107932Y207358I200J0D01*
G01X107954Y207388D01*
X108004Y207425D01*
X108035Y207435D01*
G03Y210293I-463J1429D01*
G01X108004Y210303D01*
X107954Y210340D01*
X107932Y210370D01*
G02X107897Y210483I165J113D01*
G01Y211245D01*
G02X107932Y211358I200J0D01*
G01X107954Y211388D01*
X108004Y211425D01*
X108035Y211435D01*
G03Y214293I-463J1429D01*
G01X108004Y214303D01*
X107954Y214340D01*
X107932Y214370D01*
G02X107897Y214483I165J113D01*
G01Y215245D01*
G02X107932Y215358I200J0D01*
G01X107954Y215388D01*
X108004Y215425D01*
X108035Y215435D01*
G03Y218293I-463J1429D01*
G01X108004Y218303D01*
X107954Y218340D01*
X107932Y218370D01*
G02X107897Y218483I165J113D01*
G01Y220245D01*
G02X107932Y220358I200J0D01*
G01X107954Y220388D01*
X108004Y220425D01*
X108035Y220435D01*
G03Y223293I-463J1429D01*
G01X108004Y223303D01*
X107954Y223340D01*
X107932Y223370D01*
G02X107897Y223483I165J113D01*
G01Y241449D01*
G02X107901Y241486I200J-3D01*
G01Y241488D01*
G02X107954Y241589I196J-39D01*
G01X108717Y242352D01*
G02X108857Y242409I140J-143D01*
G01X108895D01*
G03X108925Y242408I55J1200D01*
G01X118826D01*
G03X118856Y242409I-25J1201D01*
G01X122234D01*
X122238Y242408D01*
X126786D01*
G02X126925Y242352I0J-200D01*
G01X126991Y242289D01*
X127130Y242155D01*
G02X127169Y242098I-143J-140D01*
G01X127185Y242063D01*
X127186Y242022D01*
G03X130188I1501J56D01*
G01Y242023D01*
X130190Y242064D01*
X130205Y242098D01*
G02X130243Y242154I182J-83D01*
G01X130418Y242322D01*
X130449Y242352D01*
G02X130588Y242408I139J-144D01*
G01X136799D01*
G02X136850Y242398I-13J-200D01*
G02X136940Y242338I-62J-190D01*
G01X137066Y242189D01*
X137139Y242102D01*
G02X137178Y242028I-153J-128D01*
G01X137189Y241987D01*
X137182Y241943D01*
G03X137172Y241875I1481J-252D01*
G01X137168Y241838D01*
G03X137162Y241699I1496J-134D01*
G03X137695Y240551I1503J0D01*
G01X137712Y240536D01*
X137738Y240502D01*
X137748Y240480D01*
G02X137765Y240402I-183J-81D01*
G01X137762Y240284D01*
Y240282D01*
X137755Y240080D01*
G02X137751Y240047I-200J7D01*
G02X137735Y239999I-196J39D01*
G01X137733Y239995D01*
X137721Y239972D01*
X137692Y239938D01*
X137673Y239924D01*
G03X137061Y238714I890J-1210D01*
G03X140065I1502J0D01*
G03X139532Y239862I-1503J0D01*
G01X139515Y239877D01*
X139489Y239911D01*
X139479Y239933D01*
G02X139462Y240009I183J81D01*
G01X139472Y240338D01*
G02X139476Y240365I199J-16D01*
G01Y240367D01*
G02X139492Y240414I196J-40D01*
G01X139494Y240418D01*
X139506Y240441D01*
X139535Y240475D01*
X139554Y240489D01*
G03X140166Y241699I-890J1210D01*
G03X140146Y241943I-1502J0D01*
G01X140139Y241987D01*
X140150Y242028D01*
G02X140189Y242102I192J-54D01*
G01X140262Y242189D01*
X140388Y242338D01*
G02X140478Y242398I152J-130D01*
G02X140529Y242408I64J-190D01*
G01X144722D01*
G02X144749Y242406I-1J-200D01*
G02X144860Y242353I-26J-198D01*
G01X145689Y241523D01*
X147329Y239883D01*
G02X147388Y239742I-141J-142D01*
G01Y153134D01*
G02X147383Y153090I-200J0D01*
G02X147334Y152997I-195J44D01*
G03Y147397I2423J-2800D01*
G02X147383Y147304I-146J-137D01*
G02X147388Y147260I-195J-44D01*
G01Y125156D01*
X147374Y125121D01*
G03X147272Y124576I1400J-544D01*
G03X147374Y124031I1502J-1D01*
G01X147388Y123996D01*
Y122966D01*
G03X147403Y122890I200J0D01*
G01X147423Y122842D01*
G02X147438Y122766I-185J-76D01*
G01Y117514D01*
X147398Y117394D01*
G03Y115598I1203J-898D01*
G01X147438Y115478D01*
Y110661D01*
G37*
G36*
G01X108011Y276294D02*
X182985D01*
G02X183127Y276235I0J-200D01*
G01X184411Y274951D01*
G02X184413Y274949I-140J-142D01*
G02X184470Y274809I-143J-140D01*
G01Y267385D01*
G02X184357Y267205I-200J0D01*
G01X183980Y267023D01*
X183867Y267036D01*
X183821Y267072D01*
G03X182887Y267398I-934J-1175D01*
G03Y264394I0J-1502D01*
G03X183821Y264720I0J1501D01*
G01X183867Y264756D01*
X183980Y264769D01*
X184357Y264587D01*
G02X184470Y264407I-87J-180D01*
G01Y257901D01*
X184416Y257809D01*
X184371Y257782D01*
X184369D01*
X184081Y257613D01*
G02X184007Y257588I-100J174D01*
G01X183966Y257583D01*
X183873Y257608D01*
X183851Y257620D01*
G03X183129Y257805I-723J-1319D01*
G01X183128D01*
G03Y254801I0J-1502D01*
G01X183129D01*
G03X183851Y254986I-1J1504D01*
G01X183873Y254998D01*
X183927Y255013D01*
G02X184007Y255018I52J-193D01*
G01X184046Y255013D01*
X184370Y254824D01*
G02X184373Y254822I-109J-167D01*
G02X184470Y254651I-103J-171D01*
G01Y207215D01*
G02X184468Y207189I-200J2D01*
G01X184463Y207148D01*
X184460Y207137D01*
G03X184412Y206760I1454J-377D01*
G01Y206691D01*
G03X184413Y206670I200J-1D01*
G01X184420Y206603D01*
G03X184425Y206560I1494J152D01*
G01X184434Y206495D01*
G03X184438Y206476I197J32D01*
G01Y206475D01*
X184454Y206407D01*
G03X184459Y206388I1455J373D01*
G01Y206384D01*
G03X184463Y206371I1437J435D01*
G01X184470Y206345D01*
Y202582D01*
G03X184529Y202440I200J0D01*
G01X184950Y202019D01*
G03X185092Y201960I142J141D01*
G01X187810D01*
G02X187843Y201957I-2J-200D01*
G02X187950Y201903I-32J-197D01*
G01X188206Y201647D01*
G02X188264Y201506I-142J-141D01*
G01Y193640D01*
X188148Y193523D01*
X188126D01*
X187912Y193373D01*
G02X187810Y193338I-114J165D01*
G01X187767Y193335D01*
X187722Y193352D01*
X187696Y193361D01*
G03X187206Y193443I-490J-1420D01*
G01X187190D01*
G03X185704Y191941I16J-1502D01*
G03X187206Y190439I1502J0D01*
G01X187209D01*
G03X187696Y190521I-3J1502D01*
G01X187727Y190532D01*
X187815D01*
G02X187930Y190496I1J-200D01*
G01X188178Y190323D01*
G02X188201Y190304I-116J-163D01*
G01X188202Y190303D01*
G02X188264Y190158I-138J-145D01*
G01Y165175D01*
G02X188206Y165034I-200J0D01*
G01X184739Y161567D01*
X184711Y161538D01*
X184637Y161508D01*
X177623D01*
G02X177452Y161604I0J200D01*
G01X177275Y161896D01*
G02X177259Y161930I172J102D01*
G02X177270Y162094I188J70D01*
G01X177273Y162100D01*
X177290Y162135D01*
G03X177442Y162788I-1350J658D01*
G01Y162790D01*
Y162815D01*
G03X177039Y163817I-1502J-22D01*
G01X177038Y163818D01*
G02X176982Y163957I144J139D01*
G01Y164268D01*
X177009Y164338D01*
X177036Y164366D01*
G03Y166420I-1096J1027D01*
G01X177009Y166448D01*
X176982Y166518D01*
Y166868D01*
X177009Y166938D01*
X177036Y166966D01*
G03X177442Y167993I-1096J1027D01*
G03X177072Y168980I-1501J0D01*
G01X177048Y169008D01*
X177023Y169074D01*
Y169412D01*
X177048Y169478D01*
X177072Y169506D01*
G03X177442Y170493I-1131J987D01*
G03X174438I-1502J0D01*
G03X174808Y169506I1501J0D01*
G01X174832Y169478D01*
X174857Y169412D01*
Y169074D01*
X174832Y169008D01*
X174808Y168980D01*
G03X174438Y167993I1131J-987D01*
G03X174844Y166966I1502J0D01*
G01X174871Y166938D01*
X174898Y166868D01*
Y166518D01*
X174871Y166448D01*
X174844Y166420D01*
G03Y164366I1096J-1027D01*
G01X174871Y164338D01*
X174898Y164268D01*
Y163918D01*
X174871Y163849D01*
X174844Y163820D01*
G03X174438Y162821I1096J-1027D01*
G01Y162793D01*
G03X174590Y162134I1502J-1D01*
G01X174619Y162073D01*
G02X174621Y161930I-186J-74D01*
G02X174605Y161896I-188J68D01*
G01X174428Y161605D01*
X174401Y161559D01*
X174310Y161508D01*
X170686D01*
G02X170528Y161585I0J200D01*
G01X170305Y161870D01*
X170286Y161959D01*
X170297Y162005D01*
G03X170342Y162368I-1457J365D01*
G03X168840Y163870I-1502J0D01*
G03X167813Y163464I0J-1502D01*
G01X167785Y163437D01*
X167715Y163410D01*
X167365D01*
X167295Y163437D01*
X167267Y163464D01*
G03X166240Y163870I-1027J-1096D01*
G03X164738Y162368I0J-1502D01*
G03X164783Y162005I1502J2D01*
G01X164794Y161959D01*
X164775Y161870D01*
X164552Y161585D01*
G02X164394Y161508I-158J123D01*
G01X149246D01*
G02X149104Y161567I0J200D01*
G01X148448Y162223D01*
G02X148390Y162364I142J141D01*
G01Y240157D01*
G03X148331Y240298I-200J-1D01*
G01X145847Y242782D01*
X145565Y243064D01*
G03X145555Y243074I-854J-844D01*
G01X145554Y243075D01*
X145277Y243352D01*
G03X145137Y243410I-141J-142D01*
G01X129405D01*
X129359Y243422D01*
X129340Y243431D01*
X129338Y243432D01*
G03X129096Y243523I-648J-1355D01*
G03X128436Y243559I-410J-1445D01*
G03X128032Y243430I250J-1481D01*
G01X128012Y243420D01*
X127968Y243410D01*
X122305D01*
X122282Y243414D01*
G02X122143Y243503I29J198D01*
G01X121961Y243781D01*
X121933Y243824D01*
X121929Y243875D01*
X121925Y243924D01*
X121937Y243952D01*
Y243953D01*
X121946Y243973D01*
G03X122070Y244571I-1378J598D01*
G01Y244590D01*
G03X119066I-1502J-19D01*
G01Y244570D01*
G03X119191Y243971I1502J1D01*
G01X119211Y243925D01*
X119207Y243875D01*
X119203Y243824D01*
X118992Y243501D01*
G02X118834Y243411I-167J110D01*
G01X118822Y243410D01*
X108933D01*
X108924D01*
X108917Y243411D01*
G02X108785Y243469I9J200D01*
G01X107176Y245078D01*
X107147Y245106D01*
X107117Y245180D01*
Y275400D01*
G02X107174Y275540I200J0D01*
G01X107175Y275541D01*
X107869Y276235D01*
G02X107871Y276237I142J-140D01*
G02X108011Y276294I140J-143D01*
G37*
G36*
G01X189192Y1184864D02*
X190728D01*
G02X190885Y1184788I0J-200D01*
G03X190992Y1184669I945J742D01*
G02X191042Y1184461I-139J-143D01*
G03X191108Y1183524I1136J-391D01*
G01X191225Y1183407D01*
G02X191282Y1183246I-142J-141D01*
G01X191247Y1182893D01*
X191202Y1182817D01*
X191164Y1182791D01*
G03X190628Y1181791I665J-1000D01*
G03X191830Y1180589I1202J0D01*
G03X193031Y1181737I0J1202D01*
G01X193033Y1181776D01*
X193064Y1181845D01*
X193292Y1182063D01*
G02X193430Y1182118I138J-145D01*
G01X193970D01*
G02X194108Y1182063I0J-200D01*
G01X194336Y1181845D01*
X194367Y1181776D01*
X194369Y1181737D01*
G03X195555Y1180589I1201J54D01*
G01X195595D01*
X195667Y1180558D01*
X195892Y1180330D01*
G02X195950Y1180189I-142J-141D01*
G01Y1179653D01*
G02X195892Y1179512I-200J0D01*
G01X195667Y1179284D01*
X195595Y1179253D01*
X195555D01*
G03Y1176849I15J-1202D01*
G01X195595D01*
X195667Y1176818D01*
X195892Y1176590D01*
G02X195950Y1176449I-142J-141D01*
G01Y1175912D01*
G02X195892Y1175771I-200J0D01*
G01X195667Y1175543D01*
X195595Y1175512D01*
X195555D01*
G03Y1173108I15J-1202D01*
G01X195595D01*
X195667Y1173077D01*
X195892Y1172849D01*
G02X195950Y1172708I-142J-141D01*
G01Y1172172D01*
G02X195892Y1172031I-200J0D01*
G01X195667Y1171803D01*
X195595Y1171772D01*
X195555D01*
G03Y1169368I15J-1202D01*
G01X195595D01*
X195667Y1169337D01*
X195892Y1169109D01*
G02X195950Y1168968I-142J-141D01*
G01Y1168432D01*
G02X195892Y1168291I-200J0D01*
G01X195667Y1168063D01*
X195595Y1168032D01*
X195555D01*
G03X194368Y1166830I15J-1202D01*
G03X194378Y1166677I1202J2D01*
G01X194383Y1166634D01*
X194358Y1166552D01*
X194131Y1166294D01*
G02X193981Y1166226I-150J132D01*
G01X193419D01*
G02X193269Y1166294I0J200D01*
G01X193042Y1166552D01*
X193017Y1166634D01*
X193022Y1166677D01*
G03X193032Y1166830I-1192J155D01*
G03X190628I-1202J0D01*
G03X190638Y1166677I1202J2D01*
G01X190643Y1166634D01*
X190618Y1166552D01*
X190391Y1166294D01*
G02X190241Y1166226I-150J132D01*
G01X189679D01*
G02X189529Y1166294I0J200D01*
G01X189302Y1166552D01*
X189277Y1166634D01*
X189282Y1166677D01*
G03X189292Y1166830I-1192J155D01*
G03X186888I-1202J0D01*
G03X186898Y1166677I1202J2D01*
G01X186903Y1166634D01*
X186878Y1166552D01*
X186651Y1166294D01*
G02X186501Y1166226I-150J132D01*
G01X185939D01*
G02X185789Y1166294I0J200D01*
G01X185562Y1166552D01*
X185537Y1166634D01*
X185542Y1166677D01*
G03X185552Y1166830I-1192J155D01*
G03X183148I-1202J0D01*
G03X183158Y1166677I1202J2D01*
G01X183163Y1166634D01*
X183138Y1166552D01*
X182911Y1166294D01*
G02X182761Y1166226I-150J132D01*
G01X182199D01*
G02X182049Y1166294I0J200D01*
G01X181822Y1166552D01*
X181797Y1166634D01*
X181802Y1166677D01*
G03X181812Y1166830I-1192J155D01*
G03X179408I-1202J0D01*
G03X179418Y1166677I1202J2D01*
G01X179423Y1166634D01*
X179398Y1166552D01*
X179171Y1166294D01*
G02X179021Y1166226I-150J132D01*
G01X178459D01*
G02X178309Y1166294I0J200D01*
G01X178082Y1166552D01*
X178057Y1166634D01*
X178062Y1166677D01*
G03X178072Y1166830I-1192J155D01*
G03X175668I-1202J0D01*
G03X175678Y1166677I1202J2D01*
G01X175683Y1166634D01*
X175658Y1166552D01*
X175431Y1166294D01*
G02X175281Y1166226I-150J132D01*
G01X174718D01*
G02X174568Y1166294I0J200D01*
G01X174341Y1166552D01*
X174316Y1166634D01*
X174321Y1166677D01*
G03X174331Y1166830I-1192J155D01*
G03X171927I-1202J0D01*
G03X171937Y1166677I1202J2D01*
G01X171942Y1166634D01*
X171917Y1166552D01*
X171690Y1166294D01*
G02X171540Y1166226I-150J132D01*
G01X167238D01*
G02X167088Y1166294I0J200D01*
G01X166861Y1166552D01*
X166836Y1166634D01*
X166841Y1166677D01*
G03X166851Y1166830I-1192J155D01*
G03X164447I-1202J0D01*
G03X164457Y1166677I1202J2D01*
G01X164462Y1166634D01*
X164437Y1166552D01*
X164210Y1166294D01*
G02X164060Y1166226I-150J132D01*
G01X159758D01*
G02X159608Y1166294I0J200D01*
G01X159381Y1166552D01*
X159356Y1166634D01*
X159361Y1166677D01*
G03X159371Y1166830I-1192J155D01*
G03X156967I-1202J0D01*
G03X156977Y1166677I1202J2D01*
G01X156982Y1166634D01*
X156957Y1166552D01*
X156730Y1166294D01*
G02X156580Y1166226I-150J132D01*
G01X156018D01*
G02X155868Y1166294I0J200D01*
G01X155641Y1166552D01*
X155616Y1166634D01*
X155621Y1166677D01*
G03X155631Y1166830I-1192J155D01*
G03X153227I-1202J0D01*
G03X153237Y1166677I1202J2D01*
G01X153242Y1166634D01*
X153217Y1166552D01*
X152990Y1166294D01*
G02X152840Y1166226I-150J132D01*
G01X152277D01*
G02X152127Y1166294I0J200D01*
G01X151900Y1166552D01*
X151875Y1166634D01*
X151880Y1166677D01*
G03X151890Y1166830I-1192J155D01*
G03X149486I-1202J0D01*
G03X149496Y1166677I1202J2D01*
G01X149501Y1166634D01*
X149476Y1166552D01*
X149249Y1166294D01*
G02X149099Y1166226I-150J132D01*
G01X148538D01*
G02X148388Y1166294I0J200D01*
G01X148161Y1166552D01*
X148136Y1166634D01*
X148141Y1166677D01*
G03X148151Y1166830I-1192J155D01*
G03X145747I-1202J0D01*
G03X145757Y1166677I1202J2D01*
G01X145762Y1166634D01*
X145737Y1166552D01*
X145510Y1166294D01*
G02X145360Y1166226I-150J132D01*
G01X139301D01*
G03X138945Y1166184I-3J-1501D01*
G01X138922Y1166178D01*
X126039D01*
G02X125908Y1166227I0J200D01*
G03X124925Y1166593I-983J-1137D01*
G03X124196Y1166404I0J-1502D01*
G01X124137Y1166371D01*
X124005Y1166390D01*
X122850Y1167545D01*
G02X122791Y1167687I141J142D01*
G01Y1173538D01*
G02X122850Y1173680I200J0D01*
G01X123840Y1174670D01*
G02X123982Y1174729I142J-141D01*
G01X145345D01*
G02X145487Y1174670I0J-200D01*
G01X145716Y1174438D01*
X145746Y1174365D01*
X145745Y1174324D01*
Y1174310D01*
G03X148149I1202J0D01*
G01Y1174324D01*
X148148Y1174365D01*
X148178Y1174438D01*
X148407Y1174670D01*
G02X148549Y1174729I142J-141D01*
G01X149086D01*
G02X149228Y1174670I0J-200D01*
G01X149457Y1174438D01*
X149487Y1174365D01*
X149486Y1174324D01*
Y1174310D01*
G03X151890I1202J0D01*
G01Y1174324D01*
X151889Y1174365D01*
X151919Y1174438D01*
X152148Y1174670D01*
G02X152290Y1174729I142J-141D01*
G01X152827D01*
G02X152969Y1174670I0J-200D01*
G01X153198Y1174438D01*
X153228Y1174365D01*
X153227Y1174324D01*
Y1174310D01*
G03X155631I1202J0D01*
G01Y1174324D01*
X155630Y1174365D01*
X155660Y1174438D01*
X155889Y1174670D01*
G02X156031Y1174729I142J-141D01*
G01X156567D01*
G02X156709Y1174670I0J-200D01*
G01X156938Y1174438D01*
X156968Y1174365D01*
X156967Y1174324D01*
Y1174310D01*
G03X159371I1202J0D01*
G01Y1174324D01*
X159370Y1174365D01*
X159400Y1174438D01*
X159629Y1174670D01*
G02X159771Y1174729I142J-141D01*
G01X160307D01*
G02X160449Y1174670I0J-200D01*
G01X160678Y1174438D01*
X160708Y1174365D01*
X160707Y1174324D01*
Y1174310D01*
G03X163111I1202J0D01*
G01Y1174324D01*
X163110Y1174365D01*
X163140Y1174438D01*
X163369Y1174670D01*
G02X163511Y1174729I142J-141D01*
G01X164047D01*
G02X164189Y1174670I0J-200D01*
G01X164418Y1174438D01*
X164448Y1174365D01*
X164447Y1174324D01*
Y1174310D01*
G03X166851I1202J0D01*
G01Y1174324D01*
X166850Y1174365D01*
X166880Y1174438D01*
X167109Y1174670D01*
G02X167251Y1174729I142J-141D01*
G01X171527D01*
G02X171669Y1174670I0J-200D01*
G01X171898Y1174438D01*
X171928Y1174365D01*
X171927Y1174324D01*
Y1174310D01*
G03X174331I1202J0D01*
G01Y1174324D01*
X174330Y1174365D01*
X174360Y1174438D01*
X174589Y1174670D01*
G02X174731Y1174729I142J-141D01*
G01X175268D01*
G02X175410Y1174670I0J-200D01*
G01X175639Y1174438D01*
X175669Y1174365D01*
X175668Y1174324D01*
Y1174310D01*
G03X178072I1202J0D01*
G01Y1174324D01*
X178071Y1174365D01*
X178101Y1174438D01*
X178330Y1174670D01*
G02X178472Y1174729I142J-141D01*
G01X179008D01*
G02X179150Y1174670I0J-200D01*
G01X179379Y1174438D01*
X179409Y1174365D01*
X179408Y1174324D01*
Y1174310D01*
G03X181812I1202J0D01*
G01Y1174324D01*
X181811Y1174365D01*
X181841Y1174438D01*
X182070Y1174670D01*
G02X182212Y1174729I142J-141D01*
G01X182748D01*
G02X182890Y1174670I0J-200D01*
G01X183119Y1174438D01*
X183149Y1174365D01*
X183148Y1174324D01*
Y1174310D01*
G03X185552I1202J0D01*
G03X185226Y1175133I-1202J0D01*
G01X185171Y1175192D01*
X185173Y1175353D01*
X185994Y1176174D01*
G03X186053Y1176316I-141J142D01*
G01Y1177031D01*
G02X186112Y1177172I200J-1D01*
G01X186125Y1177186D01*
G03X186184Y1177327I-141J142D01*
G01Y1184120D01*
G02X186242Y1184261I200J0D01*
G01X186786Y1184805D01*
G02X186928Y1184864I142J-141D01*
G01X187034D01*
X187117Y1184824D01*
X187145Y1184788D01*
G03X189035I945J743D01*
G02X189192Y1184864I157J-124D01*
G37*
G36*
G01X181645Y1184785D02*
X183315D01*
G02X183463Y1184720I0J-200D01*
G03X184350Y1184329I887J811D01*
G03X184715Y1184386I-1J1202D01*
G01X184717D01*
G02X184918Y1184337I60J-191D01*
G01X185123Y1184132D01*
G02X185125Y1184130I-140J-142D01*
G02X185182Y1183990I-143J-140D01*
G01Y1183333D01*
G02X185103Y1183174I-200J0D01*
G01X184849Y1182981D01*
G02X184765Y1182944I-121J160D01*
G01X184720Y1182936D01*
X184674Y1182948D01*
X184672D01*
G03X184350Y1182993I-326J-1157D01*
G03Y1180589I0J-1202D01*
G03X184672Y1180634I-4J1202D01*
G01X184674D01*
X184720Y1180646D01*
X184765Y1180638D01*
G02X184849Y1180601I-37J-197D01*
G01X185103Y1180408D01*
G02X185182Y1180248I-121J-159D01*
G01Y1177742D01*
G02X185123Y1177600I-200J0D01*
G01X183974Y1176451D01*
X183946Y1176422D01*
X183872Y1176392D01*
X161416D01*
X161310Y1176472D01*
X161292Y1176537D01*
G03X161251Y1176658I-1253J-357D01*
G02X161504Y1176919I186J73D01*
G03X161909Y1176849I404J1132D01*
G03X160707Y1178051I0J1202D01*
G03X160716Y1177907I1202J3D01*
G01X160721Y1177859D01*
X160690Y1177772D01*
X160389Y1177484D01*
X160300Y1177457D01*
X160253Y1177465D01*
G03X160039Y1177482I-210J-1285D01*
G01X159864D01*
G02X159715Y1177548I0J200D01*
G01X159488Y1177800D01*
X159461Y1177880D01*
X159466Y1177922D01*
G03X159472Y1178051I-1297J125D01*
G03X158169Y1179354I-1303J0D01*
G01X157892D01*
G02X157744Y1179420I0J200D01*
G01X157516Y1179673D01*
X157490Y1179753D01*
X157494Y1179796D01*
G03X157501Y1179921I-1195J130D01*
G03X155097I-1202J0D01*
G03X155104Y1179796I1202J5D01*
G01X155108Y1179753D01*
X155082Y1179673D01*
X154854Y1179420D01*
G02X154706Y1179354I-148J134D01*
G01X154429D01*
G03X153126Y1178051I0J-1303D01*
G03X153552Y1177088I1303J1D01*
G01X153553Y1177087D01*
G02X153604Y1176868I-135J-147D01*
G01X153470Y1176520D01*
G02X153417Y1176443I-187J72D01*
G01X153416D01*
G02X153283Y1176392I-133J149D01*
G01X148093D01*
G02X147960Y1176443I0J200D01*
G01X147959D01*
G02X147906Y1176520I134J149D01*
G01X147749Y1176925D01*
X147778Y1177046D01*
X147824Y1177087D01*
G03X148249Y1178013I-877J963D01*
G01X148250Y1178038D01*
Y1178051D01*
G03X146947Y1179354I-1303J0D01*
G01X143206D01*
G03X142200Y1178877I2J-1303D01*
G01X142171Y1178843D01*
X142095Y1178805D01*
X141704Y1178794D01*
X141625Y1178827D01*
X141595Y1178860D01*
G03X140707Y1179252I-888J-810D01*
G03Y1176848I0J-1202D01*
G03X141596Y1177241I0J1202D01*
G01X141626Y1177273D01*
X141704Y1177307D01*
X142095Y1177297D01*
X142172Y1177259D01*
X142200Y1177225D01*
G03X142330Y1177088I1007J826D01*
G01X142376Y1177046D01*
X142405Y1176925D01*
X142248Y1176520D01*
G02X142195Y1176443I-187J72D01*
G01X142194D01*
G02X142061Y1176392I-133J149D01*
G01X126601D01*
G02X126586Y1176393I6J200D01*
G02X126446Y1176465I14J200D01*
G02X126429Y1176490I156J125D01*
G01X126226Y1176830D01*
X126224Y1176934D01*
X126249Y1176981D01*
G03X126427Y1177690I-1324J709D01*
G01Y1177713D01*
G03X124925Y1179193I-1502J-22D01*
G03X123806Y1178693I0J-1502D01*
G02X123585Y1178640I-149J133D01*
G01X123236Y1178773D01*
G02X123108Y1178960I72J187D01*
G01Y1184068D01*
G02X123165Y1184208I200J0D01*
G01X123166Y1184209D01*
X123683Y1184726D01*
G02X123685Y1184728I142J-140D01*
G02X123825Y1184785I140J-143D01*
G01X142173D01*
G02X142321Y1184720I0J-200D01*
G03X143430Y1184350I887J811D01*
G01X143479Y1184359D01*
X143572Y1184330D01*
X143877Y1184025D01*
X143906Y1183932D01*
X143897Y1183883D01*
G03X143876Y1183661I1181J-224D01*
G03X146280I1202J0D01*
G03X146259Y1183883I-1202J-2D01*
G01X146250Y1183932D01*
X146279Y1184025D01*
X146584Y1184330D01*
X146677Y1184359D01*
X146726Y1184350D01*
G03X147170I222J1181D01*
G01X147219Y1184359D01*
X147312Y1184330D01*
X147617Y1184025D01*
X147646Y1183932D01*
X147637Y1183883D01*
G03X147616Y1183661I1181J-224D01*
G03X150020I1202J0D01*
G03X150011Y1183805I-1202J-3D01*
G01X150006Y1183853D01*
X150037Y1183941D01*
X150338Y1184228D01*
X150427Y1184256D01*
X150474Y1184248D01*
G03X150689Y1184230I216J1285D01*
G01X150966D01*
G02X151115Y1184164I0J-200D01*
G01X151342Y1183911D01*
X151368Y1183831D01*
X151364Y1183788D01*
G03X151357Y1183661I1195J-130D01*
G03X153761I1202J0D01*
G03X153754Y1183788I-1202J-3D01*
G01X153750Y1183831D01*
X153776Y1183911D01*
X154003Y1184164D01*
G02X154152Y1184230I149J-134D01*
G01X154429D01*
G03X154643Y1184248I-2J1303D01*
G01X154690Y1184256D01*
X154779Y1184228D01*
X155080Y1183940D01*
X155111Y1183853D01*
X155106Y1183805D01*
G03X155097Y1183661I1193J-147D01*
G03X157501I1202J0D01*
G03X157480Y1183883I-1202J-2D01*
G01X157471Y1183932D01*
X157500Y1184025D01*
X157805Y1184330D01*
X157898Y1184359D01*
X157947Y1184350D01*
G03X158391I222J1181D01*
G01X158440Y1184359D01*
X158533Y1184330D01*
X158838Y1184025D01*
X158867Y1183932D01*
X158858Y1183883D01*
G03X158837Y1183661I1181J-224D01*
G03X160039Y1182459I1202J0D01*
G03X160261Y1182480I-2J1202D01*
G01X160310Y1182489D01*
X160403Y1182460D01*
X160708Y1182155D01*
X160737Y1182062D01*
X160728Y1182013D01*
G03X160707Y1181791I1181J-224D01*
G03X163111I1202J0D01*
G03X163090Y1182013I-1202J-2D01*
G01X163081Y1182062D01*
X163110Y1182155D01*
X163415Y1182460D01*
X163508Y1182489D01*
X163557Y1182480D01*
G03X163779Y1182459I224J1181D01*
G03X164001Y1182480I-2J1202D01*
G01X164050Y1182489D01*
X164143Y1182460D01*
X164448Y1182155D01*
X164477Y1182062D01*
X164468Y1182013D01*
G03X164447Y1181791I1181J-224D01*
G03X166851I1202J0D01*
G03X166830Y1182013I-1202J-2D01*
G01X166821Y1182062D01*
X166850Y1182155D01*
X167155Y1182460D01*
X167248Y1182489D01*
X167297Y1182480D01*
G03X167519Y1182459I224J1181D01*
G03X168721Y1183661I0J1202D01*
G03X168700Y1183883I-1202J-2D01*
G01X168691Y1183932D01*
X168720Y1184025D01*
X169025Y1184330D01*
X169118Y1184359D01*
X169167Y1184350D01*
G03X170276Y1184720I222J1181D01*
G02X170424Y1184785I148J-135D01*
G01X172094D01*
G02X172242Y1184720I0J-200D01*
G03X174016I887J811D01*
G02X174164Y1184785I148J-135D01*
G01X175835D01*
G02X175983Y1184720I0J-200D01*
G03X177757I887J811D01*
G02X177905Y1184785I148J-135D01*
G01X179575D01*
G02X179723Y1184720I0J-200D01*
G03X181497I887J811D01*
G02X181645Y1184785I148J-135D01*
G37*
G36*
G01X202875Y202336D02*
X206387D01*
G02X206528Y202278I0J-200D01*
G01X208568Y200238D01*
X208583Y200207D01*
G03X208622Y200132I1352J655D01*
G01X208623Y200131D01*
G03X208638Y200105I1308J738D01*
G01X208651Y200083D01*
X208667Y200027D01*
X208680Y199981D01*
Y197600D01*
G02X208647Y197490I-200J0D01*
G03Y195840I1254J-825D01*
G02X208680Y195730I-167J-110D01*
G01Y193600D01*
G02X208647Y193490I-200J0D01*
G03Y191840I1254J-825D01*
G02X208680Y191730I-167J-110D01*
G01Y187518D01*
X208670Y187475D01*
X208659Y187453D01*
G03Y186103I1355J-675D01*
G01X208670Y186081D01*
X208680Y186038D01*
Y181600D01*
G02X208647Y181490I-200J0D01*
G03Y179840I1254J-825D01*
G02X208680Y179730I-167J-110D01*
G01Y177600D01*
G02X208647Y177490I-200J0D01*
G03Y175840I1254J-825D01*
G02X208680Y175730I-167J-110D01*
G01Y173600D01*
G02X208647Y173490I-200J0D01*
G03Y171840I1254J-825D01*
G02X208680Y171730I-167J-110D01*
G01Y169600D01*
G02X208647Y169490I-200J0D01*
G03Y167840I1254J-825D01*
G02X208680Y167730I-167J-110D01*
G01Y163086D01*
G02X208624Y162946I-200J-1D01*
G01X208564Y162885D01*
G02X208509Y162845I-143J139D01*
G01X208420Y162802D01*
X208387Y162798D01*
G03Y159814I180J-1492D01*
G01X208420Y159810D01*
X208509Y159767D01*
G02X208564Y159727I-88J-179D01*
G01X208624Y159666D01*
G02X208680Y159526I-144J-139D01*
G01Y151308D01*
G02X208480Y151108I-200J0D01*
G01X201906D01*
G02X201730Y151213I0J200D01*
G01X201564Y151523D01*
G02X201540Y151625I176J95D01*
G01X201542Y151682D01*
X201573Y151729D01*
G03X201825Y152562I-1251J833D01*
G03X200323Y154064I-1502J0D01*
G03X199029Y153325I0J-1502D01*
G01X199003Y153281D01*
X198919Y153229D01*
X198740Y153219D01*
X198487Y153204D01*
X198397Y153245D01*
X198367Y153285D01*
G03X197173Y153875I-1194J-913D01*
G03X195671Y152373I0J-1502D01*
G03X195836Y151689I1502J0D01*
G01X195860Y151642D01*
X195856Y151539D01*
X195650Y151203D01*
G02X195480Y151108I-170J105D01*
G01X186162D01*
G02X186034Y151155I1J200D01*
G01X185201Y151988D01*
X184896Y152292D01*
G03X183481Y152878I-1415J-1415D01*
G01X177121D01*
G03X175706Y152292I0J-2001D01*
G01X172369Y148955D01*
G03X171846Y148042I1414J-1416D01*
G03X171782Y147540I1938J-502D01*
G03X173780Y145538I2002J0D01*
G01X173784D01*
G03X174286Y145602I0J2002D01*
G03X175199Y146125I-503J1937D01*
G01X177891Y148817D01*
G02X178033Y148876I142J-141D01*
G01X180511D01*
G02X180660Y148809I0J-200D01*
G01X180859Y148588D01*
G02X180909Y148437I-149J-133D01*
G01Y148434D01*
G03X180901Y148277I1494J-155D01*
G03X182403Y146775I1502J0D01*
G03X183592Y147359I0J1502D01*
G01X183616Y147390D01*
X183649Y147410D01*
G02X183719Y147435I101J-173D01*
G01X183988Y147479D01*
G02X184132Y147447I32J-198D01*
G01X184133Y147446D01*
G03X184597Y147214I1120J1659D01*
G03X185252Y147104I654J1892D01*
G01X208480D01*
G02X208621Y147045I-1J-200D01*
G02X208680Y146904I-141J-142D01*
G01Y124540D01*
X208677Y124524D01*
G03X208658Y124283I1483J-238D01*
G03X208677Y124042I1502J-3D01*
G01X208680Y124026D01*
Y120792D01*
G02X208666Y120718I-200J0D01*
G01X208628Y120621D01*
X208604Y120594D01*
G03Y118594I1122J-1000D01*
G01X208628Y118567D01*
X208666Y118470D01*
G02X208680Y118396I-186J-74D01*
G01Y117752D01*
X208626Y117618D01*
X208603Y117592D01*
G03X208224Y116594I1124J-998D01*
G01Y116592D01*
G03X208528Y115687I1503J1D01*
G02X208568Y115567I-160J-120D01*
G01Y114421D01*
G02X208528Y114301I-200J0D01*
G03Y112487I1199J-907D01*
G02X208568Y112367I-160J-120D01*
G01Y111756D01*
G03X208588Y111669I200J0D01*
G02X208607Y111598I-180J-86D01*
G01X208615Y111495D01*
G02X208596Y111392I-199J-16D01*
G01X208586Y111373D01*
X208571Y111354D01*
G03X208224Y110415I1155J-960D01*
G01Y110393D01*
G03X208449Y109603I1502J1D01*
G02X208407Y109378I-182J-82D01*
G01X207679Y108650D01*
G02X207662Y108635I-141J142D01*
G01X207661Y108634D01*
G02X207536Y108590I-125J156D01*
G01X170864D01*
G02X170700Y108676I0J200D01*
G03X167736I-1482J-1027D01*
G02X167572Y108590I-164J114D01*
G01X151271D01*
G02X151149Y108649I21J199D01*
G01X150090Y109708D01*
X150065Y109753D01*
X150058Y109780D01*
G03X148972Y110866I-1456J-370D01*
G01X148945Y110873D01*
X148900Y110898D01*
X148838Y110960D01*
G02X148779Y111102I141J142D01*
G01Y114907D01*
X148866Y115016D01*
X148935Y115031D01*
G03Y117961I-333J1465D01*
G01X148866Y117976D01*
X148779Y118085D01*
Y122963D01*
X148879Y123076D01*
X148955Y123085D01*
G03Y126067I-181J1491D01*
G01X148879Y126076D01*
X148779Y126189D01*
Y159263D01*
G02X148838Y159405I200J0D01*
G01X149701Y160268D01*
G02X149843Y160327I142J-141D01*
G01X185360D01*
G03X185502Y160386I0J200D01*
G01X189207Y164091D01*
G03X189266Y164233I-141J142D01*
G01Y201567D01*
G02X189288Y201657I200J-1D01*
G01X189297Y201676D01*
X189318Y201702D01*
X189893Y202277D01*
G02X190035Y202336I142J-141D01*
G01X199735D01*
G02X199912Y202229I0J-200D01*
G01X200076Y201916D01*
G02X200065Y201711I-177J-93D01*
G01X200064Y201710D01*
G03X199803Y200873I1241J-846D01*
G01Y200845D01*
G03X202807I1502J19D01*
G01Y200865D01*
G03X202546Y201711I-1502J0D01*
G01X202514Y201757D01*
X202508Y201867D01*
X202698Y202229D01*
G02X202875Y202336I177J-93D01*
G37*
G36*
G01X240020Y54588D02*
X268877D01*
X269414Y54051D01*
Y53128D01*
X268877Y52591D01*
X240020D01*
G03X234083Y46654I0J-5937D01*
G01Y7874D01*
G02X228209Y2000I-5874J0D01*
G01X180965D01*
G02X175091Y7874I0J5874D01*
G01Y46167D01*
X177088D01*
Y7874D01*
G03X180963Y3998I3876J0D01*
G01X228209D01*
G03X232086Y7874I0J3877D01*
G01Y46654D01*
G02X240020Y54588I7934J0D01*
G37*
G36*
G01X185672Y275932D02*
X207607D01*
X207681Y275902D01*
X207709Y275873D01*
X208320Y275262D01*
G02X208379Y275120I-141J-142D01*
G01Y205020D01*
X208349Y204946D01*
X208320Y204918D01*
X206799Y203397D01*
G02X206657Y203338I-142J141D01*
G01X185790D01*
X185716Y203368D01*
X185688Y203397D01*
X185530Y203555D01*
G02X185472Y203696I142J141D01*
G01Y204858D01*
G02X185532Y205001I200J0D01*
G01X185766Y205230D01*
X185840Y205259D01*
X185880Y205258D01*
X185914D01*
G03Y208262I0J1502D01*
G01X185880D01*
X185840Y208261D01*
X185766Y208290D01*
X185532Y208519D01*
G02X185472Y208661I140J143D01*
G01Y255107D01*
G02X185590Y255289I200J0D01*
G01X185914Y255436D01*
G02X186085Y255432I81J-183D01*
G01X186135Y255407D01*
X186154Y255392D01*
G03X187128Y255033I975J1143D01*
G03Y258037I0J1502D01*
G03X186154Y257678I1J-1502D01*
G01X186135Y257663D01*
X186085Y257638D01*
G02X185914Y257634I-90J179D01*
G01X185590Y257781D01*
G02X185472Y257963I82J182D01*
G01Y275732D01*
G02X185672Y275932I200J0D01*
G37*
G36*
G01X354560Y1311759D02*
X366073D01*
G02X366215Y1311700I0J-200D01*
G01X366243Y1311672D01*
X366411Y1311414D01*
G02X366431Y1311375I-167J-110D01*
G02X366442Y1311329I-187J-69D01*
G02X366444Y1311304I-198J-28D01*
G01Y1311245D01*
X366431Y1311182D01*
X366423Y1311153D01*
X366419Y1311143D01*
G03X366312Y1310586I1396J-557D01*
G03X367816Y1309082I1504J0D01*
G03X369013Y1309676I0J1503D01*
G02X369127Y1309750I160J-121D01*
G01X369244Y1309777D01*
G02X369380Y1309760I45J-195D01*
G03X370202Y1309562I821J1604D01*
G03X370657Y1309620I0J1814D01*
G01X370709Y1309633D01*
X370811Y1309606D01*
X373732Y1306685D01*
G02X373791Y1306543I-141J-142D01*
G01Y1298989D01*
G03X373850Y1298847I200J0D01*
G01X391310Y1281387D01*
G03X391452Y1281328I142J141D01*
G01X394618D01*
X394662Y1281322D01*
X394749Y1281284D01*
X394763Y1281275D01*
X394802Y1281250D01*
X394821Y1281234D01*
X394824Y1281231D01*
G03X396771Y1281224I978J1142D01*
G01X396803Y1281251D01*
X396841Y1281275D01*
X396855Y1281284D01*
X396917Y1281311D01*
G02X396997Y1281328I81J-183D01*
G01X398361D01*
X398429Y1281320D01*
X398440Y1281317D01*
X398490Y1281309D01*
X398572Y1281235D01*
X398600Y1281219D01*
X398644Y1281196D01*
G03X399340Y1281024I698J1330D01*
G01X399344D01*
G03X400176Y1281276I-1J1502D01*
G01X400200Y1281292D01*
X400279Y1281318D01*
G02X400341Y1281328I62J-190D01*
G01X410774D01*
X410799Y1281322D01*
G03X411174Y1281274I377J1454D01*
G03X411549Y1281322I-2J1502D01*
G01X411574Y1281328D01*
X454561D01*
G02X454703Y1281269I0J-200D01*
G01X457564Y1278408D01*
G02X457623Y1278266I-141J-142D01*
G01Y1274834D01*
X457600Y1274811D01*
Y1262703D01*
G03X457615Y1262628I200J1D01*
G01X457645Y1262555D01*
G02X457659Y1262480I-186J-74D01*
G01Y1216282D01*
G02X457600Y1216140I-200J0D01*
G01X455903Y1214443D01*
G02X455761Y1214384I-142J141D01*
G01X406267D01*
G03X406125Y1214325I0J-200D01*
G01X389367Y1197567D01*
G03X389308Y1197425I141J-142D01*
G01Y1173894D01*
X389278Y1173820D01*
X389249Y1173792D01*
X366939Y1151481D01*
G03X366880Y1151339I141J-142D01*
G01Y1145430D01*
G02X366821Y1145288I-200J0D01*
G01X364860Y1143327D01*
G02X364718Y1143268I-142J141D01*
G01X354102D01*
G02X354000Y1143296I0J200D01*
G01X353924Y1143341D01*
X353902Y1143354D01*
X353863Y1143393D01*
X353850Y1143416D01*
G03X353706Y1143622I-1301J-756D01*
G03X351618Y1143850I-1161J-955D01*
G03X351252Y1143435I926J-1185D01*
G01X351239Y1143413D01*
X351170Y1143344D01*
X351135Y1143322D01*
X351091Y1143297D01*
X351067Y1143283D01*
X351031Y1143274D01*
G02X350982Y1143268I-49J194D01*
G01X338975D01*
G02X338832Y1143328I0J200D01*
G01X338632Y1143532D01*
G02X338575Y1143672I143J140D01*
G01Y1143707D01*
G03X337073Y1145209I-1502J0D01*
G03X336099Y1144851I0J-1504D01*
G01X336093Y1144846D01*
X336054Y1144817D01*
X336042Y1144811D01*
G03X335253Y1143489I713J-1322D01*
G01Y1143468D01*
G02X335053Y1143268I-200J0D01*
G01X328017D01*
G02X327847Y1143362I0J200D01*
G01X327747Y1143521D01*
X327667Y1143648D01*
Y1143650D01*
X327640Y1143693D01*
X327633Y1143795D01*
X327655Y1143841D01*
G03X327778Y1144389I-1178J552D01*
G03X325174I-1302J0D01*
G03X325288Y1143856I1302J0D01*
G01X325297Y1143836D01*
X325305Y1143796D01*
X325315Y1143758D01*
X325299Y1143669D01*
X325277Y1143635D01*
X325205Y1143522D01*
Y1143520D01*
X325167Y1143459D01*
G03X325145Y1143411I169J-106D01*
G01X325126Y1143347D01*
X325021Y1143268D01*
X324277D01*
G02X324107Y1143362I0J200D01*
G01X324007Y1143521D01*
X323927Y1143648D01*
Y1143650D01*
X323900Y1143693D01*
X323893Y1143795D01*
X323915Y1143841D01*
G03X324038Y1144389I-1178J552D01*
G03X321434I-1302J0D01*
G03X321548Y1143856I1302J0D01*
G01X321557Y1143836D01*
X321565Y1143796D01*
X321575Y1143758D01*
X321559Y1143669D01*
X321537Y1143635D01*
X321465Y1143522D01*
Y1143520D01*
X321427Y1143459D01*
G03X321405Y1143411I169J-106D01*
G01X321386Y1143347D01*
X321281Y1143268D01*
X320537D01*
G02X320367Y1143362I0J200D01*
G01X320267Y1143521D01*
X320187Y1143648D01*
Y1143650D01*
X320160Y1143693D01*
X320153Y1143795D01*
X320175Y1143841D01*
G03X320298Y1144389I-1178J552D01*
G03X317694I-1302J0D01*
G03X317808Y1143856I1302J0D01*
G01X317817Y1143836D01*
X317825Y1143796D01*
X317835Y1143758D01*
X317819Y1143669D01*
X317797Y1143635D01*
X317725Y1143522D01*
Y1143520D01*
X317687Y1143459D01*
G03X317665Y1143411I169J-106D01*
G01X317646Y1143347D01*
X317541Y1143268D01*
X316796D01*
G02X316626Y1143362I0J200D01*
G01X316526Y1143521D01*
X316446Y1143648D01*
Y1143650D01*
X316419Y1143693D01*
X316412Y1143795D01*
X316434Y1143841D01*
G03X316557Y1144389I-1178J552D01*
G03X313953I-1302J0D01*
G03X314067Y1143856I1302J0D01*
G01X314076Y1143836D01*
X314084Y1143796D01*
X314094Y1143758D01*
X314078Y1143669D01*
X314056Y1143635D01*
X313984Y1143522D01*
Y1143520D01*
X313946Y1143459D01*
G03X313924Y1143411I169J-106D01*
G01X313905Y1143347D01*
X313800Y1143268D01*
X313056D01*
G02X312886Y1143362I0J200D01*
G01X312786Y1143521D01*
X312706Y1143648D01*
Y1143650D01*
X312679Y1143693D01*
X312672Y1143795D01*
X312694Y1143841D01*
G03X312817Y1144389I-1178J552D01*
G03X310213I-1302J0D01*
G03X310327Y1143856I1302J0D01*
G01X310336Y1143836D01*
X310344Y1143796D01*
X310354Y1143758D01*
X310338Y1143669D01*
X310316Y1143635D01*
X310244Y1143522D01*
Y1143520D01*
X310206Y1143459D01*
G03X310184Y1143411I169J-106D01*
G01X310165Y1143347D01*
X310060Y1143268D01*
X309316D01*
G02X309146Y1143362I0J200D01*
G01X309046Y1143521D01*
X308966Y1143648D01*
Y1143650D01*
X308939Y1143693D01*
X308932Y1143795D01*
X308954Y1143841D01*
G03X309077Y1144389I-1178J552D01*
G03X306473I-1302J0D01*
G03X306587Y1143856I1302J0D01*
G01X306596Y1143836D01*
X306604Y1143796D01*
X306614Y1143758D01*
X306598Y1143669D01*
X306576Y1143635D01*
X306504Y1143522D01*
Y1143520D01*
X306466Y1143459D01*
G03X306444Y1143411I169J-106D01*
G01X306425Y1143347D01*
X306320Y1143268D01*
X305576D01*
G02X305406Y1143362I0J200D01*
G01X305306Y1143521D01*
X305226Y1143648D01*
Y1143650D01*
X305199Y1143693D01*
X305192Y1143795D01*
X305214Y1143841D01*
G03X305337Y1144389I-1178J552D01*
G03X302733I-1302J0D01*
G03X302847Y1143856I1302J0D01*
G01X302856Y1143836D01*
X302864Y1143796D01*
X302874Y1143758D01*
X302858Y1143669D01*
X302836Y1143635D01*
X302764Y1143522D01*
Y1143520D01*
X302726Y1143459D01*
G03X302704Y1143411I169J-106D01*
G01X302685Y1143347D01*
X302580Y1143268D01*
X301836D01*
G02X301666Y1143362I0J200D01*
G01X301566Y1143521D01*
X301486Y1143648D01*
Y1143650D01*
X301459Y1143693D01*
X301452Y1143795D01*
X301474Y1143841D01*
G03X301597Y1144389I-1178J552D01*
G03X298993I-1302J0D01*
G03X299107Y1143856I1302J0D01*
G01X299116Y1143836D01*
X299124Y1143796D01*
X299134Y1143758D01*
X299118Y1143669D01*
X299096Y1143635D01*
X299024Y1143522D01*
Y1143520D01*
X298986Y1143459D01*
G03X298964Y1143411I169J-106D01*
G01X298945Y1143347D01*
X298840Y1143268D01*
X298096D01*
G02X297926Y1143362I0J200D01*
G01X297826Y1143521D01*
X297746Y1143648D01*
Y1143650D01*
X297719Y1143693D01*
X297712Y1143795D01*
X297734Y1143841D01*
G03X297857Y1144389I-1178J552D01*
G03X295253I-1302J0D01*
G03X295367Y1143856I1302J0D01*
G01X295376Y1143836D01*
X295384Y1143796D01*
X295394Y1143758D01*
X295378Y1143669D01*
X295356Y1143635D01*
X295284Y1143522D01*
Y1143520D01*
X295246Y1143459D01*
G03X295224Y1143411I169J-106D01*
G01X295205Y1143347D01*
X295100Y1143268D01*
X294355D01*
G02X294185Y1143362I0J200D01*
G01X294085Y1143521D01*
X294005Y1143648D01*
Y1143650D01*
X293978Y1143693D01*
X293971Y1143795D01*
X293993Y1143841D01*
G03X294116Y1144389I-1178J552D01*
G03X291512I-1302J0D01*
G03X291626Y1143856I1302J0D01*
G01X291635Y1143836D01*
X291643Y1143796D01*
X291653Y1143758D01*
X291637Y1143669D01*
X291615Y1143635D01*
X291543Y1143522D01*
Y1143520D01*
X291505Y1143459D01*
G03X291483Y1143411I169J-106D01*
G01X291464Y1143347D01*
X291359Y1143268D01*
X290615D01*
G02X290445Y1143362I0J200D01*
G01X290345Y1143521D01*
X290265Y1143648D01*
Y1143650D01*
X290238Y1143693D01*
X290231Y1143795D01*
X290253Y1143841D01*
G03X290376Y1144389I-1178J552D01*
G03X287772I-1302J0D01*
G03X287886Y1143856I1302J0D01*
G01X287895Y1143836D01*
X287903Y1143796D01*
X287913Y1143758D01*
X287897Y1143669D01*
X287875Y1143635D01*
X287803Y1143522D01*
Y1143520D01*
X287765Y1143459D01*
G03X287743Y1143411I169J-106D01*
G01X287724Y1143347D01*
X287619Y1143268D01*
X286875D01*
G02X286705Y1143362I0J200D01*
G01X286605Y1143521D01*
X286525Y1143648D01*
Y1143650D01*
X286498Y1143693D01*
X286491Y1143795D01*
X286513Y1143841D01*
G03X286636Y1144389I-1178J552D01*
G03X284032I-1302J0D01*
G03X284146Y1143856I1302J0D01*
G01X284155Y1143836D01*
X284163Y1143796D01*
X284173Y1143758D01*
X284157Y1143669D01*
X284135Y1143635D01*
X284063Y1143522D01*
Y1143520D01*
X284025Y1143459D01*
G03X284003Y1143411I169J-106D01*
G01X283984Y1143347D01*
X283879Y1143268D01*
X283135D01*
G02X282965Y1143362I0J200D01*
G01X282865Y1143521D01*
X282785Y1143648D01*
Y1143650D01*
X282758Y1143693D01*
X282751Y1143795D01*
X282773Y1143841D01*
G03X282896Y1144389I-1178J552D01*
G03X280292I-1302J0D01*
G03X280406Y1143856I1302J0D01*
G01X280415Y1143836D01*
X280423Y1143796D01*
X280433Y1143758D01*
X280417Y1143669D01*
X280395Y1143635D01*
X280323Y1143522D01*
Y1143520D01*
X280285Y1143459D01*
G03X280263Y1143411I169J-106D01*
G01X280244Y1143347D01*
X280139Y1143268D01*
X279395D01*
G02X279225Y1143362I0J200D01*
G01X279125Y1143521D01*
X279045Y1143648D01*
Y1143650D01*
X279018Y1143693D01*
X279011Y1143795D01*
X279033Y1143841D01*
G03X279156Y1144389I-1178J552D01*
G03X276552I-1302J0D01*
G03X276666Y1143856I1302J0D01*
G01X276675Y1143836D01*
X276683Y1143796D01*
X276693Y1143758D01*
X276677Y1143669D01*
X276655Y1143635D01*
X276583Y1143522D01*
Y1143520D01*
X276545Y1143459D01*
G03X276523Y1143411I169J-106D01*
G01X276504Y1143347D01*
X276399Y1143268D01*
X275655D01*
G02X275485Y1143362I0J200D01*
G01X275385Y1143521D01*
X275305Y1143648D01*
Y1143650D01*
X275278Y1143693D01*
X275271Y1143795D01*
X275293Y1143841D01*
G03X275416Y1144389I-1178J552D01*
G03X272812I-1302J0D01*
G03X272926Y1143856I1302J0D01*
G01X272935Y1143836D01*
X272943Y1143796D01*
X272953Y1143758D01*
X272937Y1143669D01*
X272915Y1143635D01*
X272843Y1143522D01*
Y1143520D01*
X272805Y1143459D01*
G03X272783Y1143411I169J-106D01*
G01X272764Y1143347D01*
X272659Y1143268D01*
X271914D01*
G02X271744Y1143362I0J200D01*
G01X271644Y1143521D01*
X271564Y1143648D01*
Y1143650D01*
X271537Y1143693D01*
X271530Y1143795D01*
X271552Y1143841D01*
G03X271675Y1144389I-1178J552D01*
G03X269071I-1302J0D01*
G03X269185Y1143856I1302J0D01*
G01X269194Y1143836D01*
X269202Y1143796D01*
X269212Y1143758D01*
X269196Y1143669D01*
X269174Y1143635D01*
X269102Y1143522D01*
Y1143520D01*
X269064Y1143459D01*
G03X269042Y1143411I169J-106D01*
G01X269023Y1143347D01*
X268918Y1143268D01*
X197111D01*
G02X196941Y1143362I0J200D01*
G01X196841Y1143521D01*
X196761Y1143648D01*
Y1143650D01*
X196734Y1143693D01*
X196727Y1143795D01*
X196749Y1143841D01*
G03X196872Y1144389I-1178J552D01*
G03X194268I-1302J0D01*
G03X194382Y1143856I1302J0D01*
G01X194391Y1143836D01*
X194399Y1143796D01*
X194409Y1143758D01*
X194393Y1143669D01*
X194371Y1143635D01*
X194299Y1143522D01*
Y1143520D01*
X194261Y1143459D01*
G03X194239Y1143411I169J-106D01*
G01X194220Y1143347D01*
X194115Y1143268D01*
X193469D01*
G02X193327Y1143327I0J200D01*
G01X193048Y1143606D01*
G02X192991Y1143771I142J141D01*
G01X192995Y1143804D01*
X193009Y1143834D01*
G03X193132Y1144393I-1179J553D01*
G01Y1144409D01*
G03X192149Y1145651I-1302J-21D01*
G01X192145Y1145652D01*
X192135Y1145655D01*
X192112Y1145663D01*
G02X191978Y1145852I66J189D01*
G01Y1146738D01*
X192064Y1146846D01*
X192132Y1146862D01*
G03X192149Y1149391I-303J1267D01*
G01X192145Y1149392D01*
X192135Y1149395D01*
X192112Y1149403D01*
G02X191978Y1149592I66J189D01*
G01Y1150478D01*
X192064Y1150586D01*
X192132Y1150602D01*
G03X192149Y1153131I-303J1267D01*
G01X192145Y1153132D01*
X192135Y1153135D01*
X192112Y1153143D01*
G02X191978Y1153332I66J189D01*
G01Y1154219D01*
X192064Y1154327D01*
X192132Y1154343D01*
G03X192149Y1156872I-303J1267D01*
G01X192145Y1156873D01*
X192135Y1156876D01*
X192112Y1156884D01*
G02X191978Y1157073I66J189D01*
G01Y1157959D01*
X192064Y1158067D01*
X192132Y1158083D01*
G03X192149Y1160612I-303J1267D01*
G01X192145Y1160613D01*
X192135Y1160616D01*
X192112Y1160624D01*
G02X191978Y1160813I66J189D01*
G01Y1161224D01*
G02X192178Y1161424I200J0D01*
G01X230501D01*
G03X231563Y1161863I1J1501D01*
G01X235062Y1165363D01*
G03X235385Y1165844I-1062J1062D01*
G01X235407Y1165896D01*
X235495Y1165961D01*
X235702Y1165980D01*
X235704D01*
X235738Y1165983D01*
X235770Y1165986D01*
X235809Y1165978D01*
G02X235879Y1165948I-42J-195D01*
G01X235907Y1165930D01*
X235916Y1165922D01*
G03X236711Y1165622I797J908D01*
G01X236712D01*
G03X237920Y1166830I0J1208D01*
G03X236713Y1168038I-1208J0D01*
G01X236712D01*
G03X236243Y1167939I10J-1207D01*
G01X236205Y1167922D01*
X236086D01*
G02X235978Y1167953I-1J200D01*
G01X235725Y1168115D01*
G02X235633Y1168283I108J168D01*
G01Y1169118D01*
G02X235692Y1169260I200J0D01*
G01X235701Y1169269D01*
X235719Y1169283D01*
X235852Y1169369D01*
X235854D01*
X235974Y1169448D01*
G02X236084Y1169481I110J-167D01*
G01X236163D01*
X236210Y1169471D01*
X236230Y1169463D01*
X236233Y1169462D01*
G03X236712Y1169362I481J1108D01*
G03X237920Y1170570I0J1208D01*
G03X236713Y1171778I-1208J0D01*
G01X236712D01*
G03X236243Y1171679I10J-1207D01*
G01X236205Y1171662D01*
X236086D01*
G02X235978Y1171693I-1J200D01*
G01X235725Y1171855D01*
G02X235633Y1172023I108J168D01*
G01Y1172858D01*
G02X235692Y1173000I200J0D01*
G01X235701Y1173009D01*
X235719Y1173023D01*
X235852Y1173109D01*
X235854D01*
X235974Y1173188D01*
G02X236084Y1173221I110J-167D01*
G01X236163D01*
X236210Y1173211D01*
X236230Y1173203D01*
X236233Y1173202D01*
G03X236712Y1173102I481J1108D01*
G03X237920Y1174310I0J1208D01*
G03X236713Y1175518I-1208J0D01*
G01X236712D01*
G03X236243Y1175419I10J-1207D01*
G01X236205Y1175402D01*
X236086D01*
G02X235978Y1175433I-1J200D01*
G01X235725Y1175595D01*
G02X235633Y1175763I108J168D01*
G01Y1180339D01*
G02X235692Y1180481I200J0D01*
G01X235701Y1180490D01*
X235719Y1180504D01*
X235852Y1180590D01*
X235854D01*
X235974Y1180669D01*
G02X236084Y1180702I110J-167D01*
G01X236163D01*
X236210Y1180692D01*
X236230Y1180684D01*
X236233Y1180683D01*
G03X236712Y1180583I481J1108D01*
G03X237920Y1181791I0J1208D01*
G03X236713Y1182999I-1208J0D01*
G01X236712D01*
G03X236243Y1182900I10J-1207D01*
G01X236205Y1182883D01*
X236086D01*
G02X235978Y1182914I-1J200D01*
G01X235725Y1183076D01*
G02X235633Y1183244I108J168D01*
G01Y1187570D01*
G02X235833Y1187770I200J0D01*
G01X236712D01*
X236751D01*
G03X238214Y1189259I-39J1501D01*
G01X238213Y1189264D01*
Y1189269D01*
G03X237873Y1190223I-1501J3D01*
G01X237854Y1190246D01*
G03X237340Y1190635I-1142J-975D01*
G01X237339Y1190636D01*
X237322Y1190643D01*
G03X237317Y1190645I-560J-1393D01*
G01X237294Y1190655D01*
X237257Y1190684D01*
X237188Y1190769D01*
X237169Y1190792D01*
X237146Y1190845D01*
X237142Y1190866D01*
X237125Y1190947D01*
G02X237121Y1190988I196J40D01*
G01Y1191213D01*
G02X237178Y1191353I200J0D01*
G01X237179Y1191354D01*
X237774Y1191949D01*
G03X238203Y1192835I-1062J1061D01*
G01X238207Y1192867D01*
G03X237061Y1194472I-1495J144D01*
G01X237034Y1194478D01*
X236989Y1194503D01*
X236931Y1194559D01*
G02X236870Y1194701I139J144D01*
G01Y1194741D01*
X236900Y1194815D01*
X237774Y1195689D01*
G03X238213Y1196749I-1062J1061D01*
G01Y1196751D01*
G03X236712Y1198252I-1501J0D01*
G01X236710D01*
G03X235650Y1197813I1J-1501D01*
G01X233070Y1195233D01*
G03X232631Y1194173I1062J-1061D01*
G01Y1194056D01*
G02X232630Y1194042I-199J7D01*
G01Y1194033D01*
G02X232500Y1193860I-199J14D01*
G01X232445Y1193839D01*
X232331Y1193864D01*
X232229Y1193966D01*
X232228D01*
X232122Y1194073D01*
G03X231062Y1194512I-1061J-1062D01*
G01X229232D01*
G03Y1191510I0J-1501D01*
G01X230375D01*
G02X230485Y1191462I-22J-199D01*
G01X230783Y1191164D01*
G02X230831Y1191054I-151J-132D01*
G01Y1190334D01*
G02X230702Y1190147I-200J0D01*
G01X230352Y1190014D01*
G02X230132Y1190068I-71J187D01*
G01X230131Y1190069D01*
G03X229232Y1190473I-899J-798D01*
G03Y1188069I0J-1202D01*
G01X229234D01*
G03X230108Y1188445I0J1204D01*
G01X230135Y1188474D01*
X230220Y1188513D01*
X230222D01*
X230258Y1188530D01*
X230339Y1188533D01*
X230602Y1188432D01*
X230604D01*
X230701Y1188395D01*
G02X230712Y1188390I-77J-184D01*
G02X230830Y1188208I-82J-182D01*
G01Y1182854D01*
G02X230701Y1182667I-200J0D01*
G01X230293Y1182512D01*
X230173Y1182541D01*
X230131Y1182589D01*
G03X229232Y1182993I-899J-798D01*
G03Y1180589I0J-1202D01*
G01X229234D01*
G03X230108Y1180965I0J1204D01*
G01X230135Y1180994D01*
X230220Y1181033D01*
X230222D01*
X230258Y1181050D01*
X230339Y1181053D01*
X230602Y1180952D01*
X230604D01*
X230701Y1180915D01*
G02X230712Y1180910I-77J-184D01*
G02X230830Y1180728I-82J-182D01*
G01Y1175373D01*
G02X230701Y1175186I-200J0D01*
G01X230293Y1175031D01*
X230173Y1175060D01*
X230131Y1175108D01*
G03X229232Y1175512I-899J-798D01*
G03Y1173108I0J-1202D01*
G01X229234D01*
G03X230108Y1173484I0J1204D01*
G01X230135Y1173513D01*
X230220Y1173552D01*
X230222D01*
X230258Y1173569D01*
X230339Y1173572D01*
X230602Y1173471D01*
X230604D01*
X230701Y1173434D01*
G02X230712Y1173429I-77J-184D01*
G02X230830Y1173247I-82J-182D01*
G01Y1171633D01*
G02X230701Y1171446I-200J0D01*
G01X230293Y1171291D01*
X230173Y1171320D01*
X230131Y1171368D01*
G03X229232Y1171772I-899J-798D01*
G03Y1169368I0J-1202D01*
G01X229234D01*
G03X230108Y1169744I0J1204D01*
G01X230135Y1169773D01*
X230220Y1169812D01*
X230222D01*
X230258Y1169829D01*
X230339Y1169832D01*
X230602Y1169731D01*
X230604D01*
X230701Y1169694D01*
G02X230712Y1169689I-77J-184D01*
G02X230830Y1169507I-82J-182D01*
G01Y1168243D01*
G02X230772Y1168102I-200J0D01*
G01X230674Y1168003D01*
X230415Y1167745D01*
G02X230274Y1167687I-141J142D01*
G01X230153D01*
G02X230023Y1167735I0J200D01*
G01X230022Y1167736D01*
G03X229232Y1168032I-790J-906D01*
G03X228030Y1166830I0J-1202D01*
G03X228040Y1166678I1202J3D01*
G01X228045Y1166635D01*
X228020Y1166553D01*
X227792Y1166294D01*
G02X227642Y1166226I-150J132D01*
G01X227081D01*
G02X226940Y1166285I1J200D01*
G01X226930Y1166295D01*
X226736Y1166516D01*
X226711Y1166544D01*
X226698Y1166579D01*
G02X226685Y1166650I187J71D01*
G01Y1166683D01*
X226686Y1166694D01*
G03X226694Y1166826I-1194J139D01*
G01Y1166827D01*
Y1166830D01*
G03X224290I-1202J0D01*
G01Y1166827D01*
G03X224297Y1166699I1202J2D01*
G01X224298Y1166694D01*
X224300Y1166668D01*
G02X224247Y1166518I-200J-14D01*
G01X224248Y1166517D01*
X224055Y1166296D01*
X224048Y1166290D01*
X224043Y1166285D01*
G02X223902Y1166226I-142J141D01*
G01X223341D01*
G02X223200Y1166285I1J200D01*
G01X223190Y1166295D01*
X222996Y1166516D01*
X222971Y1166544D01*
X222958Y1166579D01*
G02X222945Y1166650I187J71D01*
G01Y1166683D01*
X222946Y1166694D01*
G03X222954Y1166826I-1194J139D01*
G01Y1166827D01*
Y1166830D01*
G03X220550I-1202J0D01*
G01Y1166827D01*
G03X220557Y1166699I1202J2D01*
G01X220558Y1166694D01*
X220560Y1166668D01*
G02X220507Y1166518I-200J-14D01*
G01X220508Y1166517D01*
X220315Y1166296D01*
X220308Y1166290D01*
X220303Y1166285D01*
G02X220162Y1166226I-142J141D01*
G01X219600D01*
G02X219459Y1166285I1J200D01*
G01X219449Y1166295D01*
X219255Y1166516D01*
X219230Y1166544D01*
X219217Y1166579D01*
G02X219204Y1166650I187J71D01*
G01Y1166683D01*
X219205Y1166694D01*
G03X219213Y1166826I-1194J139D01*
G01Y1166827D01*
Y1166830D01*
G03X216809I-1202J0D01*
G01Y1166827D01*
G03X216816Y1166699I1202J2D01*
G01X216817Y1166694D01*
X216819Y1166668D01*
G02X216766Y1166518I-200J-14D01*
G01X216767Y1166517D01*
X216574Y1166296D01*
X216567Y1166290D01*
X216562Y1166285D01*
G02X216421Y1166226I-142J141D01*
G01X215860D01*
G02X215719Y1166285I1J200D01*
G01X215709Y1166295D01*
X215515Y1166516D01*
X215490Y1166544D01*
X215477Y1166579D01*
G02X215464Y1166650I187J71D01*
G01Y1166683D01*
X215465Y1166694D01*
G03X215473Y1166826I-1194J139D01*
G01Y1166827D01*
Y1166830D01*
G03X213069I-1202J0D01*
G01Y1166827D01*
G03X213076Y1166699I1202J2D01*
G01X213077Y1166694D01*
X213079Y1166668D01*
G02X213026Y1166518I-200J-14D01*
G01X213027Y1166517D01*
X212834Y1166296D01*
X212827Y1166290D01*
X212822Y1166285D01*
G02X212681Y1166226I-142J141D01*
G01X212120D01*
G02X211979Y1166285I1J200D01*
G01X211969Y1166295D01*
X211775Y1166516D01*
X211750Y1166544D01*
X211737Y1166579D01*
G02X211724Y1166650I187J71D01*
G01Y1166683D01*
X211725Y1166694D01*
G03X211733Y1166826I-1194J139D01*
G01Y1166827D01*
Y1166830D01*
G03X209329I-1202J0D01*
G01Y1166827D01*
G03X209336Y1166699I1202J2D01*
G01X209337Y1166694D01*
X209339Y1166668D01*
G02X209286Y1166518I-200J-14D01*
G01X209287Y1166517D01*
X209094Y1166296D01*
X209087Y1166290D01*
X209082Y1166285D01*
G02X208941Y1166226I-142J141D01*
G01X208380D01*
G02X208239Y1166285I1J200D01*
G01X208229Y1166295D01*
X208035Y1166516D01*
X208010Y1166544D01*
X207997Y1166579D01*
G02X207984Y1166650I187J71D01*
G01Y1166683D01*
X207985Y1166694D01*
G03X207993Y1166826I-1194J139D01*
G01Y1166827D01*
Y1166830D01*
G03X205589I-1202J0D01*
G01Y1166827D01*
G03X205596Y1166699I1202J2D01*
G01X205597Y1166694D01*
X205599Y1166668D01*
G02X205546Y1166518I-200J-14D01*
G01X205547Y1166517D01*
X205354Y1166296D01*
X205347Y1166290D01*
X205342Y1166285D01*
G02X205201Y1166226I-142J141D01*
G01X204640D01*
G02X204499Y1166285I1J200D01*
G01X204489Y1166295D01*
X204295Y1166516D01*
X204270Y1166544D01*
X204257Y1166579D01*
G02X204244Y1166650I187J71D01*
G01Y1166683D01*
X204245Y1166694D01*
G03X204253Y1166826I-1194J139D01*
G01Y1166827D01*
Y1166830D01*
G03X201849I-1202J0D01*
G01Y1166827D01*
G03X201856Y1166699I1202J2D01*
G01X201857Y1166694D01*
X201859Y1166668D01*
G02X201806Y1166518I-200J-14D01*
G01X201807Y1166517D01*
X201614Y1166296D01*
X201607Y1166290D01*
X201602Y1166285D01*
G02X201461Y1166226I-142J141D01*
G01X200900D01*
G02X200759Y1166285I1J200D01*
G01X200749Y1166295D01*
X200555Y1166516D01*
X200530Y1166544D01*
X200517Y1166579D01*
G02X200504Y1166650I187J71D01*
G01Y1166683D01*
X200505Y1166694D01*
G03X200513Y1166826I-1194J139D01*
G01Y1166827D01*
Y1166830D01*
G03X198109I-1202J0D01*
G01Y1166827D01*
G03X198116Y1166699I1202J2D01*
G01X198117Y1166694D01*
X198119Y1166668D01*
G02X198066Y1166518I-200J-14D01*
G01X198067Y1166517D01*
X197874Y1166296D01*
X197867Y1166290D01*
X197862Y1166285D01*
G02X197721Y1166226I-142J141D01*
G01X197661D01*
G02X197475Y1166426I15J200D01*
G01Y1182503D01*
G03X197416Y1182645I-200J0D01*
G01X197000Y1183061D01*
G03X196858Y1183120I-142J-141D01*
G01X193011D01*
G02X192869Y1183179I0J200D01*
G01X192318Y1183730D01*
G02X192262Y1183902I142J141D01*
G01X192309Y1184203D01*
G02X192365Y1184314I198J-30D01*
G01X192398Y1184347D01*
G02X192445Y1184382I142J-141D01*
G03X192968Y1186163I-616J1148D01*
G03X192260Y1186760I-1139J-632D01*
G01X192229Y1186771D01*
X192149Y1186833D01*
X192122Y1186854D01*
X192039Y1186980D01*
X192023Y1187044D01*
X192026Y1187078D01*
G03X192030Y1187185I-1250J100D01*
G01Y1191523D01*
G02X192089Y1191665I200J0D01*
G01X192090Y1191666D01*
X192160Y1191734D01*
X192184Y1191747D01*
X192224Y1191769D01*
X192242Y1191775D01*
G03X192226Y1194252I-412J1236D01*
G01X192183Y1194266D01*
X192094Y1194348D01*
G02X192030Y1194495I136J147D01*
G01Y1195089D01*
G02X192054Y1195185I200J1D01*
G01X192067Y1195208D01*
X192100Y1195244D01*
X192121Y1195257D01*
X192142Y1195271D01*
X192180Y1195365D01*
G02X192302Y1195480I186J-75D01*
G01X192339Y1195495D01*
G03X192178Y1198059I-510J1255D01*
G01X192112Y1198077D01*
X192030Y1198183D01*
Y1198829D01*
G02X192054Y1198925I200J1D01*
G01X192067Y1198948D01*
X192100Y1198984D01*
X192121Y1198997D01*
X192142Y1199011D01*
X192180Y1199105D01*
G02X192302Y1199220I186J-75D01*
G01X192339Y1199235D01*
G03X192178Y1201799I-510J1255D01*
G01X192112Y1201817D01*
X192030Y1201923D01*
Y1202621D01*
X192079Y1202711D01*
X192121Y1202738D01*
X192142Y1202752D01*
X192180Y1202846D01*
G02X192302Y1202961I186J-75D01*
G01X192339Y1202976D01*
G03X192178Y1205540I-510J1255D01*
G01X192112Y1205558D01*
X192030Y1205664D01*
Y1206361D01*
X192079Y1206451D01*
X192121Y1206478D01*
X192142Y1206492D01*
X192180Y1206586D01*
G02X192302Y1206701I186J-75D01*
G01X192339Y1206716D01*
G03X193167Y1208183I-510J1255D01*
G01X193160Y1208229D01*
X193187Y1208317D01*
X193465Y1208616D01*
X193550Y1208648D01*
X193597Y1208644D01*
G03X193700Y1208640I98J1198D01*
G03X193922Y1208661I-2J1202D01*
G01X193971Y1208670D01*
X194064Y1208641D01*
X194369Y1208336D01*
X194398Y1208243D01*
X194389Y1208194D01*
G03X194368Y1207972I1181J-224D01*
G03X196772I1202J0D01*
G03X196751Y1208194I-1202J-2D01*
G01X196742Y1208243D01*
X196771Y1208336D01*
X197076Y1208641D01*
X197169Y1208670D01*
X197218Y1208661D01*
G03X197440Y1208640I224J1181D01*
G03X197663Y1208661I-1J1202D01*
G01X197711Y1208670D01*
X197806Y1208641D01*
X198110Y1208337D01*
X198139Y1208243D01*
X198130Y1208194D01*
G03X198109Y1207972I1181J-224D01*
G03X199311Y1209174I1202J0D01*
G03X199088Y1209153I1J-1202D01*
G01X199040Y1209144D01*
X198945Y1209173D01*
X198641Y1209477D01*
X198612Y1209571D01*
X198621Y1209620D01*
G03X198642Y1209842I-1181J224D01*
G03X196238I-1202J0D01*
G03X196259Y1209620I1202J2D01*
G01X196268Y1209571D01*
X196239Y1209478D01*
X195934Y1209173D01*
X195841Y1209144D01*
X195792Y1209153D01*
G03X195570Y1209174I-224J-1181D01*
G03X195348Y1209153I2J-1202D01*
G01X195299Y1209144D01*
X195206Y1209173D01*
X194901Y1209478D01*
X194872Y1209571D01*
X194881Y1209620D01*
G03X194902Y1209842I-1181J224D01*
G03X193700Y1211044I-1202J0D01*
G03X193597Y1211040I-5J-1202D01*
G01X193551Y1211036D01*
X193465Y1211069D01*
X193187Y1211367D01*
X193160Y1211454D01*
X193167Y1211500D01*
G03Y1211923I-1338J211D01*
G01X193160Y1211969D01*
X193187Y1212057D01*
X193465Y1212356D01*
X193550Y1212388D01*
X193597Y1212384D01*
G03X193700Y1212380I98J1198D01*
G03X194902Y1213582I0J1202D01*
G03X194881Y1213804I-1202J-2D01*
G01X194872Y1213853D01*
X194901Y1213946D01*
X195206Y1214251D01*
X195299Y1214280D01*
X195348Y1214271D01*
G03X195570Y1214250I224J1181D01*
G03X196772Y1215452I0J1202D01*
G03X196751Y1215674I-1202J-2D01*
G01X196742Y1215723D01*
X196771Y1215816D01*
X197076Y1216121D01*
X197169Y1216150D01*
X197218Y1216141D01*
G03X197440Y1216120I224J1181D01*
G03X196238Y1217322I0J1202D01*
G03X196259Y1217100I1202J2D01*
G01X196268Y1217051D01*
X196239Y1216958D01*
X195934Y1216653D01*
X195841Y1216624D01*
X195792Y1216633D01*
G03X195570Y1216654I-224J-1181D01*
G03X194368Y1215452I0J-1202D01*
G03X194389Y1215230I1202J2D01*
G01X194398Y1215181D01*
X194369Y1215088D01*
X194064Y1214783D01*
X193971Y1214754D01*
X193922Y1214763D01*
G03X193700Y1214784I-224J-1181D01*
G03X193557Y1214775I4J-1202D01*
G01X193509Y1214770D01*
X193422Y1214801D01*
X193134Y1215102D01*
X193107Y1215191D01*
X193115Y1215238D01*
G03X192226Y1216693I-1285J214D01*
G01X192183Y1216707D01*
X192094Y1216789D01*
G02X192030Y1216936I136J147D01*
G01Y1217581D01*
X192079Y1217671D01*
X192121Y1217698D01*
X192142Y1217712D01*
X192180Y1217806D01*
G02X192302Y1217921I186J-75D01*
G01X192339Y1217936D01*
G03X193167Y1219403I-510J1255D01*
G01X193160Y1219449D01*
X193187Y1219537D01*
X193465Y1219836D01*
X193550Y1219868D01*
X193597Y1219864D01*
G03X193700Y1219860I98J1198D01*
G03Y1222264I0J1202D01*
G03X193557Y1222255I4J-1202D01*
G01X193509Y1222250D01*
X193421Y1222281D01*
X193134Y1222582D01*
X193106Y1222671D01*
X193114Y1222718D01*
G03X193132Y1222932I-1285J216D01*
G01Y1223210D01*
G02X193198Y1223359I200J0D01*
G01X193451Y1223586D01*
X193531Y1223612D01*
X193574Y1223608D01*
G03X193700Y1223601I130J1195D01*
G03Y1226005I0J1202D01*
G03X193574Y1225998I4J-1202D01*
G01X193531Y1225994D01*
X193451Y1226020D01*
X193198Y1226247D01*
G02X193132Y1226396I134J149D01*
G01Y1226673D01*
G03X193114Y1226887I-1304J-2D01*
G01X193106Y1226934D01*
X193134Y1227023D01*
X193421Y1227324D01*
X193509Y1227355D01*
X193557Y1227350D01*
G03X193700Y1227341I147J1193D01*
G03Y1229745I0J1202D01*
G03X193597Y1229741I-5J-1202D01*
G01X193551Y1229737D01*
X193465Y1229770D01*
X193187Y1230068D01*
X193160Y1230155D01*
X193167Y1230201D01*
G03Y1230624I-1338J211D01*
G01X193160Y1230670D01*
X193187Y1230758D01*
X193465Y1231057D01*
X193550Y1231089D01*
X193597Y1231085D01*
G03X193700Y1231081I98J1198D01*
G03X194902Y1232283I0J1202D01*
G03X194894Y1232425I-1202J3D01*
G01X194888Y1232472D01*
X194919Y1232560D01*
X195220Y1232847D01*
X195309Y1232874D01*
X195356Y1232867D01*
G03X195570Y1232849I216J1286D01*
G03X195784Y1232867I-2J1304D01*
G01X195831Y1232874D01*
X195920Y1232847D01*
X196221Y1232560D01*
X196252Y1232472D01*
X196246Y1232425D01*
G03X196238Y1232283I1194J-139D01*
G03X197440Y1233485I1202J0D01*
G03X197298Y1233477I-3J-1202D01*
G01X197251Y1233471D01*
X197163Y1233502D01*
X196876Y1233803D01*
X196849Y1233892D01*
X196856Y1233939D01*
G03X196874Y1234153I-1286J216D01*
G01Y1234430D01*
G02X196940Y1234578I200J0D01*
G01X197193Y1234806D01*
X197273Y1234832D01*
X197315Y1234827D01*
G03X197440Y1234821I120J1196D01*
G03X198642Y1236023I0J1202D01*
G03X198638Y1236126I-1202J5D01*
G01X198634Y1236172D01*
X198667Y1236257D01*
X198965Y1236535D01*
X199053Y1236562D01*
X199099Y1236555D01*
G03X199311Y1236538I214J1338D01*
G03X199522Y1236555I-3J1354D01*
G01X199568Y1236562D01*
X199656Y1236535D01*
X199954Y1236257D01*
X199987Y1236172D01*
X199983Y1236125D01*
G03X199979Y1236023I1198J-98D01*
G03X201181Y1234821I1202J0D01*
G03X201305Y1234827I4J1202D01*
G01X201348Y1234832D01*
X201427Y1234806D01*
X201680Y1234578D01*
G02X201746Y1234430I-134J-148D01*
G01Y1234153D01*
G03X201764Y1233939I1304J2D01*
G01X201771Y1233892D01*
X201744Y1233803D01*
X201457Y1233503D01*
X201370Y1233471D01*
X201322Y1233477D01*
G03X201181Y1233485I-138J-1194D01*
G03X202383Y1232283I0J-1202D01*
G03X202375Y1232425I-1202J3D01*
G01X202369Y1232472D01*
X202400Y1232560D01*
X202701Y1232847D01*
X202790Y1232874D01*
X202837Y1232866D01*
G03X203050Y1232849I210J1287D01*
G03X203264Y1232867I-2J1304D01*
G01X203312Y1232875D01*
X203401Y1232847D01*
X203702Y1232560D01*
X203733Y1232473D01*
X203727Y1232425D01*
G03X203719Y1232283I1194J-139D01*
G03X204921Y1233485I1202J0D01*
G03X204778Y1233477I-4J-1202D01*
G01X204731Y1233471D01*
X204643Y1233502D01*
X204356Y1233803D01*
X204328Y1233892D01*
X204336Y1233939D01*
G03X204354Y1234153I-1286J216D01*
G01Y1234430D01*
G02X204420Y1234578I200J0D01*
G01X204673Y1234806D01*
X204753Y1234832D01*
X204796Y1234828D01*
G03X204921Y1234821I130J1195D01*
G03X206123Y1236023I0J1202D01*
G03X206119Y1236125I-1202J4D01*
G01X206115Y1236172D01*
X206148Y1236257D01*
X206446Y1236535D01*
X206534Y1236562D01*
X206580Y1236555D01*
G03X206791Y1236538I214J1338D01*
G03X207002Y1236555I-3J1354D01*
G01X207048Y1236562D01*
X207136Y1236535D01*
X207434Y1236257D01*
X207467Y1236172D01*
X207463Y1236125D01*
G03X207459Y1236023I1198J-98D01*
G03X208661Y1234821I1202J0D01*
G03X208785Y1234827I4J1202D01*
G01X208828Y1234832D01*
X208907Y1234806D01*
X209160Y1234578D01*
G02X209226Y1234430I-134J-148D01*
G01Y1234153D01*
G03X209244Y1233939I1304J2D01*
G01X209251Y1233892D01*
X209224Y1233803D01*
X208937Y1233503D01*
X208850Y1233471D01*
X208802Y1233477D01*
G03X208661Y1233485I-138J-1194D01*
G03X209863Y1232283I0J-1202D01*
G03X209855Y1232425I-1202J3D01*
G01X209849Y1232472D01*
X209880Y1232560D01*
X210181Y1232847D01*
X210270Y1232874D01*
X210317Y1232866D01*
G03X210530Y1232849I210J1287D01*
G03X210744Y1232867I-2J1304D01*
G01X210792Y1232875D01*
X210881Y1232847D01*
X211182Y1232560D01*
X211213Y1232473D01*
X211207Y1232425D01*
G03X211199Y1232283I1194J-139D01*
G03X212401Y1233485I1202J0D01*
G03X212258Y1233477I-4J-1202D01*
G01X212211Y1233471D01*
X212123Y1233502D01*
X211836Y1233803D01*
X211808Y1233892D01*
X211816Y1233939D01*
G03X211834Y1234153I-1286J216D01*
G01Y1234430D01*
G02X211900Y1234578I200J0D01*
G01X212153Y1234806D01*
X212233Y1234832D01*
X212276Y1234828D01*
G03X212401Y1234821I130J1195D01*
G03X213603Y1236023I0J1202D01*
G03X213599Y1236125I-1202J4D01*
G01X213595Y1236172D01*
X213628Y1236257D01*
X213926Y1236535D01*
X214014Y1236562D01*
X214060Y1236555D01*
G03X214271Y1236538I214J1338D01*
G03X214482Y1236555I-3J1354D01*
G01X214528Y1236562D01*
X214616Y1236535D01*
X214914Y1236257D01*
X214947Y1236172D01*
X214943Y1236125D01*
G03X214939Y1236023I1198J-98D01*
G03X216141Y1234821I1202J0D01*
G03X216266Y1234828I-5J1202D01*
G01X216309Y1234832D01*
X216389Y1234806D01*
X216642Y1234578D01*
G02X216708Y1234430I-134J-148D01*
G01Y1234153D01*
G03X216726Y1233939I1303J2D01*
G01X216734Y1233892D01*
X216706Y1233803D01*
X216419Y1233502D01*
X216331Y1233471D01*
X216284Y1233477D01*
G03X216141Y1233485I-139J-1194D01*
G03X217343Y1232283I0J-1202D01*
G03X217335Y1232426I-1202J4D01*
G01X217329Y1232473D01*
X217360Y1232561D01*
X217661Y1232848D01*
X217750Y1232876D01*
X217797Y1232868D01*
G03X218011Y1232850I216J1285D01*
G03X218225Y1232868I-2J1303D01*
G01X218272Y1232876D01*
X218361Y1232848D01*
X218662Y1232561D01*
X218693Y1232473D01*
X218687Y1232426D01*
G03X218679Y1232283I1194J-139D01*
G03X219881Y1233485I1202J0D01*
G03X219738Y1233477I-4J-1202D01*
G01X219691Y1233471D01*
X219603Y1233502D01*
X219316Y1233803D01*
X219288Y1233892D01*
X219296Y1233939D01*
G03X219314Y1234153I-1285J216D01*
G01Y1234430D01*
G02X219380Y1234578I200J0D01*
G01X219633Y1234806D01*
X219713Y1234832D01*
X219756Y1234828D01*
G03X219881Y1234821I130J1195D01*
G03X221083Y1236023I0J1202D01*
G03X221074Y1236166I-1202J-4D01*
G01X221069Y1236214D01*
X221100Y1236302D01*
X221401Y1236589D01*
X221490Y1236617D01*
X221537Y1236609D01*
G03X221751Y1236591I216J1284D01*
G03X221966Y1236609I-1J1302D01*
G01X222013Y1236617D01*
X222102Y1236589D01*
X222403Y1236302D01*
X222434Y1236214D01*
X222429Y1236167D01*
G03X222420Y1236023I1193J-147D01*
G03X223622Y1234821I1202J0D01*
G03X223747Y1234828I-5J1202D01*
G01X223790Y1234832D01*
X223870Y1234806D01*
X224123Y1234578D01*
G02X224189Y1234430I-134J-148D01*
G01Y1234153D01*
G03X224207Y1233939I1303J2D01*
G01X224215Y1233892D01*
X224187Y1233803D01*
X223900Y1233502D01*
X223812Y1233471D01*
X223765Y1233477D01*
G03X223622Y1233485I-139J-1194D01*
G03X224824Y1232283I0J-1202D01*
G03X224816Y1232426I-1202J4D01*
G01X224810Y1232473D01*
X224841Y1232561D01*
X225142Y1232848D01*
X225231Y1232876D01*
X225278Y1232868D01*
G03X225492Y1232850I216J1285D01*
G03X225706Y1232868I-2J1303D01*
G01X225753Y1232876D01*
X225842Y1232848D01*
X226143Y1232561D01*
X226174Y1232473D01*
X226168Y1232426D01*
G03X226160Y1232283I1194J-139D01*
G03X227362Y1233485I1202J0D01*
G03X227219Y1233477I-4J-1202D01*
G01X227172Y1233471D01*
X227084Y1233502D01*
X226797Y1233803D01*
X226769Y1233892D01*
X226777Y1233939D01*
G03X226795Y1234153I-1285J216D01*
G01Y1234430D01*
G02X226861Y1234578I200J0D01*
G01X227114Y1234806D01*
X227194Y1234832D01*
X227237Y1234828D01*
G03X227362Y1234821I130J1195D01*
G03Y1237225I0J1202D01*
G03X227237Y1237218I5J-1202D01*
G01X227194Y1237214D01*
X227114Y1237240D01*
X226861Y1237468D01*
G02X226795Y1237616I134J148D01*
G01Y1237893D01*
G03X226777Y1238107I-1303J-2D01*
G01X226769Y1238154D01*
X226797Y1238243D01*
X227084Y1238544D01*
X227172Y1238575D01*
X227219Y1238569D01*
G03X227362Y1238561I139J1194D01*
G03X228564Y1239763I0J1202D01*
G03X228494Y1240166I-1202J-1D01*
G02X228756Y1240419I189J67D01*
G03X228872Y1240380I473J1214D01*
G02X228931Y1240352I-55J-192D01*
G03X229770Y1239916I2170J3151D01*
G02X229900Y1239733I-70J-187D01*
G03X232304I1202J30D01*
G02X232434Y1239916I200J-4D01*
G03X233040Y1240204I-1333J3587D01*
G01X233089Y1240232D01*
X233198Y1240231D01*
X233595Y1239988D01*
X233646Y1239891D01*
X233642Y1239835D01*
G03X233640Y1239763I1200J-69D01*
G03X236044I1202J0D01*
G03X235974Y1240166I-1202J-1D01*
G02X236236Y1240420I188J68D01*
G03X236352Y1240380I482J1210D01*
G02X236410Y1240353I-54J-193D01*
G03X237250Y1239916I2172J3150D01*
G02X237380Y1239733I-70J-187D01*
G03X239784I1202J30D01*
G02X239914Y1239916I200J-4D01*
G03X240753Y1240352I-1331J3587D01*
G02X240811Y1240379I112J-165D01*
G03X240928Y1240419I-362J1251D01*
G02X241189Y1240166I73J-186D01*
G03X241120Y1239763I1133J-401D01*
G03X243524I1202J0D01*
G03X243454Y1240166I-1202J-1D01*
G02X243716Y1240420I188J68D01*
G03X243832Y1240380I482J1210D01*
G02X243890Y1240353I-54J-193D01*
G03X244730Y1239916I2172J3150D01*
G02X244860Y1239733I-70J-187D01*
G03X247264I1202J30D01*
G02X247394Y1239916I200J-4D01*
G03X248232Y1240351I-1330J3588D01*
G02X248291Y1240379I114J-164D01*
G03X248409Y1240419I-359J1252D01*
G02X248670Y1240166I73J-186D01*
G03X248601Y1239763I1133J-401D01*
G03X251005I1202J0D01*
G03X250935Y1240166I-1202J-1D01*
G02X251197Y1240420I188J68D01*
G03X251313Y1240380I482J1210D01*
G02X251371Y1240353I-54J-193D01*
G03X252211Y1239916I2172J3150D01*
G02X252341Y1239733I-70J-187D01*
G03X254745I1202J30D01*
G02X254875Y1239916I200J-4D01*
G03X255718Y1240354I-1329J3588D01*
G02X255775Y1240382I115J-163D01*
G03X255890Y1240421I-360J1251D01*
G02X256151Y1240167I73J-186D01*
G03X256081Y1239763I1131J-404D01*
G03X258485I1202J0D01*
G03X258464Y1239985I-1202J-2D01*
G01X258455Y1240034D01*
X258484Y1240127D01*
X258789Y1240432D01*
X258882Y1240461D01*
X258931Y1240452D01*
G03X259153Y1240431I224J1181D01*
G03X259375Y1240452I-2J1202D01*
G01X259424Y1240461D01*
X259517Y1240432D01*
X259822Y1240127D01*
X259851Y1240034D01*
X259842Y1239985D01*
G03X259821Y1239763I1181J-224D01*
G03X261023Y1240965I1202J0D01*
G03X260801Y1240944I2J-1202D01*
G01X260752Y1240935D01*
X260659Y1240964D01*
X260354Y1241269D01*
X260325Y1241362D01*
X260334Y1241411D01*
G03X260355Y1241633I-1181J224D01*
G03X260345Y1241788I-1202J0D01*
G01X260339Y1241835D01*
X260370Y1241924D01*
X260671Y1242214D01*
X260761Y1242241D01*
X260808Y1242234D01*
G03X261023Y1242216I214J1269D01*
G03X262310Y1243503I0J1287D01*
G03X262303Y1243639I-1287J2D01*
G01X262298Y1243684D01*
X262329Y1243769D01*
X262615Y1244054D01*
X262700Y1244083D01*
X262746Y1244078D01*
G03X262893Y1244070I144J1295D01*
G03X263107Y1244088I-2J1303D01*
G01X263154Y1244096D01*
X263243Y1244068D01*
X263544Y1243781D01*
X263575Y1243693D01*
X263569Y1243646D01*
G03X263561Y1243503I1194J-139D01*
G03X264763Y1244705I1202J0D01*
G03X264620Y1244697I-4J-1202D01*
G01X264573Y1244691D01*
X264485Y1244722D01*
X264198Y1245023D01*
X264170Y1245112D01*
X264178Y1245159D01*
G03X264196Y1245373I-1285J216D01*
G01Y1245650D01*
G02X264262Y1245798I200J0D01*
G01X264515Y1246026D01*
X264595Y1246052D01*
X264638Y1246048D01*
G03X264763Y1246041I130J1195D01*
G03X265965Y1247243I0J1202D01*
G03X265944Y1247466I-1202J-1D01*
G01X265935Y1247514D01*
X265964Y1247609D01*
X266268Y1247913D01*
X266362Y1247942D01*
X266411Y1247933D01*
G03X266633Y1247912I224J1181D01*
G03X266788Y1247922I0J1202D01*
G01X266835Y1247928D01*
X266925Y1247897D01*
X267214Y1247596D01*
X267242Y1247506D01*
X267234Y1247458D01*
G03X267216Y1247243I1269J-214D01*
G03X268503Y1248530I1287J0D01*
G03X268288Y1248512I-1J-1287D01*
G01X268241Y1248504D01*
X268151Y1248532D01*
X267850Y1248822D01*
X267819Y1248911D01*
X267825Y1248959D01*
G03X267835Y1249114I-1192J155D01*
G03X267814Y1249335I-1202J-3D01*
G01X267805Y1249384D01*
X267834Y1249479D01*
X268138Y1249783D01*
X268232Y1249812D01*
X268281Y1249803D01*
G03X268503Y1249782I224J1181D01*
G03X269705Y1250984I0J1202D01*
G03X269684Y1251206I-1202J-2D01*
G01X269675Y1251255D01*
X269704Y1251348D01*
X270009Y1251653D01*
X270102Y1251682D01*
X270151Y1251673D01*
G03X270372Y1251652I224J1182D01*
G01X270373D01*
G03X270528Y1251662I0J1202D01*
G01X270576Y1251668D01*
X270665Y1251637D01*
X270955Y1251336D01*
X270983Y1251246D01*
X270975Y1251199D01*
G03X270956Y1250984I1269J-220D01*
G03X273532I1288J0D01*
G03X273524Y1251120I-1288J-8D01*
G01X273519Y1251166D01*
X273550Y1251251D01*
X273836Y1251536D01*
X273921Y1251566D01*
X273967Y1251560D01*
G03X274114Y1251552I144J1294D01*
G03X274328Y1251570I-2J1302D01*
G01X274375Y1251578D01*
X274464Y1251550D01*
X274765Y1251263D01*
X274796Y1251175D01*
X274791Y1251127D01*
G03X274782Y1250984I1193J-147D01*
G03X275984Y1252186I1202J0D01*
G03X275841Y1252177I4J-1202D01*
G01X275793Y1252172D01*
X275705Y1252203D01*
X275418Y1252504D01*
X275390Y1252593D01*
X275398Y1252640D01*
G03X275416Y1252854I-1284J216D01*
G01Y1253131D01*
G02X275482Y1253280I200J0D01*
G01X275735Y1253507D01*
X275815Y1253533D01*
X275858Y1253529D01*
G03X275984Y1253522I130J1195D01*
G03X277186Y1254724I0J1202D01*
G03X277165Y1254946I-1202J-2D01*
G01X277156Y1254995D01*
X277185Y1255088D01*
X277490Y1255393D01*
X277583Y1255422D01*
X277632Y1255413D01*
G03X277854Y1255392I224J1181D01*
G03X278009Y1255402I0J1202D01*
G01X278056Y1255408D01*
X278145Y1255377D01*
X278435Y1255076D01*
X278462Y1254986D01*
X278455Y1254939D01*
G03X278436Y1254724I1269J-220D01*
G03X279724Y1253436I1288J0D01*
G03X279852Y1253443I-6J1288D01*
G01X279895Y1253447D01*
X279975Y1253421D01*
X280226Y1253193D01*
G02X280292Y1253045I-134J-148D01*
G01Y1252854D01*
G03X280300Y1252707I1302J-3D01*
G01X280306Y1252661D01*
X280276Y1252576D01*
X279991Y1252290D01*
X279906Y1252259D01*
X279860Y1252264D01*
G03X279724Y1252272I-144J-1280D01*
G03X281012Y1250984I0J-1288D01*
G03X281004Y1251120I-1288J-8D01*
G01X280999Y1251166D01*
X281030Y1251251D01*
X281316Y1251536D01*
X281401Y1251566D01*
X281447Y1251560D01*
G03X281594Y1251552I144J1294D01*
G03X281808Y1251570I-2J1302D01*
G01X281855Y1251578D01*
X281944Y1251550D01*
X282245Y1251263D01*
X282276Y1251175D01*
X282271Y1251127D01*
G03X282262Y1250984I1193J-147D01*
G03X283464Y1252186I1202J0D01*
G03X283321Y1252177I4J-1202D01*
G01X283273Y1252172D01*
X283185Y1252203D01*
X282898Y1252504D01*
X282870Y1252593D01*
X282878Y1252640D01*
G03X282896Y1252854I-1284J216D01*
G01Y1253131D01*
G02X282962Y1253280I200J0D01*
G01X283215Y1253507D01*
X283295Y1253533D01*
X283338Y1253529D01*
G03X283464Y1253522I130J1195D01*
G03Y1255926I0J1202D01*
G03X283339Y1255919I5J-1202D01*
G01X283296Y1255915D01*
X283216Y1255941D01*
X282963Y1256169D01*
G02X282897Y1256317I134J148D01*
G01Y1256595D01*
G03X282481Y1257549I-1303J0D01*
G01X282467Y1257562D01*
X282450Y1257577D01*
X282423Y1257610D01*
X282408Y1257628D01*
X282367Y1257710D01*
G02X282346Y1257793I179J89D01*
G01X282339Y1258025D01*
G02X282363Y1258126I200J6D01*
G01X282403Y1258200D01*
X282426Y1258222D01*
G03X282799Y1259094I-833J872D01*
G03X282198Y1260137I-1206J0D01*
G02X282098Y1260299I100J173D01*
G01X282083Y1260563D01*
Y1260639D01*
G02X282140Y1260779I200J0D01*
G01X282141Y1260780D01*
X282165Y1260804D01*
X354445Y1311723D01*
G02X354560Y1311759I114J-164D01*
G37*
G36*
G01X310882Y95111D02*
G03X311215Y95148I2J1502D01*
G01X311237Y95153D01*
X311259D01*
G02X311459Y94953I0J-200D01*
G01Y94863D01*
X311445Y94828D01*
G03X311342Y94296I1399J-547D01*
G01Y94282D01*
G03X311445Y93731I1502J-4D01*
G01X311459Y93696D01*
Y87625D01*
Y87622D01*
G02X311426Y87515I-200J3D01*
G01X311424Y87514D01*
Y87513D01*
X311334Y87441D01*
X311308Y87430D01*
G03Y84662I584J-1384D01*
G01X311334Y84651D01*
X311424Y84579D01*
Y84578D01*
X311426Y84577D01*
G02X311459Y84470I-167J-110D01*
G01Y62279D01*
G02X311457Y62251I-200J0D01*
G02X311393Y62131I-198J29D01*
G01X311391Y62129D01*
X311162Y61927D01*
G02X311091Y61889I-128J154D01*
G01X311053Y61878D01*
X311009Y61883D01*
G03X310817Y61896I-197J-1490D01*
G03X309717Y61417I0J-1503D01*
G01X309716Y61416D01*
G02X309645Y61366I-148J135D01*
G01X309607Y61350D01*
X309376Y61361D01*
X309374D01*
X309250Y61366D01*
G02X309171Y61389I15J200D01*
G01X309134Y61409D01*
X309107Y61444D01*
G03X307916Y62031I-1191J-915D01*
G03X306414Y60529I0J-1502D01*
G03X307740Y59037I1502J0D01*
G01X307794Y59031D01*
G03X307916Y59026I122J1498D01*
G03X309016Y59505I0J1503D01*
G01X309017Y59506D01*
G02X309088Y59556I148J-135D01*
G01X309126Y59572D01*
X309357Y59561D01*
X309359D01*
X309483Y59556D01*
G02X309562Y59533I-15J-200D01*
G01X309599Y59513D01*
X309626Y59478D01*
G03X310817Y58891I1191J915D01*
G03X310820I1J1502D01*
G03X311009Y58903I0J1502D01*
G01X311054Y58908D01*
X311092Y58897D01*
G02X311165Y58856I-59J-191D01*
G01X311189Y58835D01*
X311337Y58705D01*
G02X311339Y58703I-140J-142D01*
G01X311396Y58652D01*
G02X311418Y58628I-136J-147D01*
G01X311425Y58619D01*
G02X311459Y58520I-166J-112D01*
G01Y54040D01*
G02X311437Y53949I-200J0D01*
G02X311401Y53899I-178J90D01*
G01X310197Y52695D01*
G02X310147Y52659I-140J142D01*
G02X310056Y52637I-91J178D01*
G01X291526D01*
G02X291435Y52659I0J200D01*
G02X291385Y52695I90J178D01*
G01X286243Y57837D01*
G03X286146Y57891I-142J-141D01*
G01X286136Y57893D01*
G02X286029Y57968I55J193D01*
G01X285827Y58269D01*
G02X285799Y58352I171J104D01*
G01X285794Y58400D01*
X285813Y58446D01*
G03X286433Y61613I-7782J3168D01*
G01Y61614D01*
G03X269629I-8402J0D01*
G03X270249Y58447I8402J1D01*
G01Y58446D01*
G02X270263Y58351I-185J-76D01*
G01X270258Y58302D01*
X270044Y57984D01*
G02X269879Y57896I-166J112D01*
G01X262732D01*
G02X262698Y57899I1J200D01*
G02X262637Y57920I34J197D01*
G01Y57921D01*
G02X262555Y58005I96J175D01*
G01X262394Y58323D01*
G02X262372Y58429I177J92D01*
G01X262375Y58458D01*
X262393Y58508D01*
X262410Y58531D01*
G03X263118Y60709I-2993J2177D01*
G01Y60710D01*
G03X262689Y62439I-3701J-1D01*
G01X262688Y62441D01*
G02X262666Y62535I178J91D01*
G01Y62583D01*
X262849Y62922D01*
G02X262851Y62925I167J-109D01*
G02X262883Y62968I175J-97D01*
G02X262916Y62995I143J-141D01*
G01X262955Y63020D01*
X263006Y63025D01*
G03X264933Y69857I-349J3786D01*
G03X259313Y65001I-2276J-3046D01*
G01Y65000D01*
X259314D01*
X259319Y64990D01*
G02X259337Y64902I-182J-83D01*
G01X259336Y64849D01*
X259133Y64508D01*
G02X259091Y64458I-172J102D01*
G02X258961Y64410I-130J152D01*
G01X252117D01*
G03X248416Y60709I0J-3701D01*
G01Y60707D01*
G03X249124Y58531I3701J1D01*
G01X249141Y58508D01*
X249159Y58458D01*
X249162Y58429D01*
G02X249140Y58323I-199J-14D01*
G01X249118Y58280D01*
X248972Y57992D01*
G02X248910Y57930I-169J107D01*
G01X248887Y57917D01*
G02X248799Y57896I-89J179D01*
G01X212104D01*
G02X212013Y57918I0J200D01*
G02X211963Y57954I90J178D01*
G01X211169Y58748D01*
G02X211158Y58760I142J141D01*
G02X211114Y58918I154J128D01*
G02X211121Y58949I198J-28D01*
G01X211184Y59126D01*
X211244Y59295D01*
G02X211254Y59319I189J-65D01*
G02X211310Y59387I179J-90D01*
G01X211332Y59404D01*
X211384Y59425D01*
X211413Y59428D01*
G03X212764Y60922I-151J1494D01*
G03X211271Y62424I-1502J0D01*
G01X211260D01*
G03X210805Y62353I1J-1502D01*
G01X210788Y62348D01*
X210741Y62356D01*
G02X210722Y62360I32J198D01*
G01X210706Y62365D01*
G02X210660Y62389I69J188D01*
G01X210591Y62441D01*
X210399Y62584D01*
G02X210318Y62744I119J161D01*
G01Y84612D01*
Y84620D01*
G02X210337Y84697I200J-8D01*
G01X210381Y84783D01*
G02X210434Y84848I178J-91D01*
G01X210436Y84849D01*
G03X210460Y84867I-889J1210D01*
G03X210462Y84869I-139J141D01*
G03Y87223I-932J1177D01*
G03X210460Y87225I-141J-139D01*
G03X210436Y87243I-913J-1192D01*
G01X210434Y87244D01*
G02X210381Y87309I125J156D01*
G01X210337Y87395D01*
G02X210318Y87472I181J85D01*
G01Y92503D01*
G02X210344Y92596I200J-6D01*
G02X210349Y92604I172J-102D01*
G02X210375Y92636I167J-109D01*
G01X210436Y92697D01*
G02X210490Y92735I140J-142D01*
G01X210586Y92780D01*
X210621Y92783D01*
G03X211984Y94279I-139J1496D01*
G03X210536Y95781I-1503J0D01*
G01X210520D01*
G02X210515Y95782I37J196D01*
G01X210494Y95786D01*
G02X210441Y95808I50J194D01*
G02X210424Y95819I100J173D01*
G02X210404Y95837I124J157D01*
G01X210319Y95922D01*
G02X210259Y96064I140J143D01*
G01Y108858D01*
G02X210278Y108943I200J0D01*
G01X210373Y109038D01*
X210402Y109052D01*
G03X210927Y109492I-677J1341D01*
G01X210951Y109524D01*
X210984Y109544D01*
G02X211047Y109568I102J-172D01*
G01X211326Y109609D01*
X211377Y109617D01*
X211452Y109598D01*
X211485Y109574D01*
G03X212375Y109282I890J1210D01*
G03X213676Y110033I0J1502D01*
G01X213682Y110044D01*
G02X213708Y110075I166J-113D01*
G01X213726Y110093D01*
X213756Y110110D01*
G02X213835Y110132I92J-177D01*
G02X213849Y110133I21J-198D01*
G01X214195D01*
G02X214207Y110132I-11J-199D01*
G01X214211D01*
G02X214288Y110110I-15J-199D01*
G01X214318Y110093D01*
X214354Y110056D01*
X214368Y110033D01*
X214369Y110031D01*
G03X215669Y109282I1300J754D01*
G03Y112286I0J1502D01*
G03X214360Y111522I0J-1503D01*
G02X214206Y111435I-165J113D01*
G01X213838D01*
G02X213684Y111522I11J200D01*
G03X212375Y112286I-1309J-739D01*
G03X211182Y111696I0J-1501D01*
G01X211180Y111693D01*
G02X211168Y111680I-153J129D01*
G01X211134Y111646D01*
G02X211043Y111608I-120J160D01*
G01X210782Y111569D01*
X210780D01*
X210762Y111566D01*
G02X210687Y111571I-24J198D01*
G01X210686D01*
X210649Y111580D01*
X210616Y111604D01*
G03X210606Y111611I-866J-1226D01*
G03X210602Y111615I-142J-138D01*
G03X210579Y111630I-832J-1251D01*
G02X210571Y111636I116J163D01*
G03X210567Y111639I-903J-1199D01*
G01X210545Y111654D01*
X210532Y111668D01*
G02X210510Y111698I150J133D01*
G01X210457Y111796D01*
G02X210436Y111883I179J89D01*
G01Y111905D01*
G02X210457Y111993I200J-1D01*
G01X210509Y112090D01*
G02X210532Y112120I170J-106D01*
G01X210547Y112136D01*
X210548D01*
X210573Y112153D01*
G03X211133Y112867I-847J1241D01*
G03X211218Y113218I-1407J527D01*
G01X211223Y113266D01*
G03X211229Y113394I-1497J134D01*
G03X210373Y114751I-1504J0D01*
G01X210345Y114764D01*
X210304Y114802D01*
X210290Y114823D01*
G02X210259Y114930I169J107D01*
G01Y115058D01*
G02X210290Y115165I200J0D01*
G01X210305Y115188D01*
X210346Y115225D01*
X210373Y115238D01*
G03X210980Y117421I-648J1356D01*
G03X210671Y117762I-1255J-826D01*
G01X210648Y117780D01*
X210582Y117874D01*
Y117875D01*
G02X210572Y117937I190J62D01*
G01Y118254D01*
G02X210574Y118281I200J-1D01*
G02X210649Y118409I198J-30D01*
G03X210755Y118500I-924J1184D01*
G02X210757Y118502I142J-140D01*
G01X210784Y118527D01*
G03X210796Y118538I-129J153D01*
G01X210831Y118576D01*
G03X211218Y119417I-1105J1018D01*
G01X211223Y119466D01*
G03X211229Y119594I-1497J134D01*
G03X210373Y120951I-1504J0D01*
G01X210345Y120964D01*
X210304Y121002D01*
X210290Y121023D01*
G02X210259Y121130I169J107D01*
G01Y122608D01*
G02X210414Y122802I200J-1D01*
G02X210416Y122803I88J-173D01*
G01X210424Y122804D01*
G03X211662Y124283I-264J1479D01*
G03X210425Y125762I-1503J0D01*
G01X210424D01*
G02X210259Y125953I35J197D01*
G01Y131919D01*
G02X210292Y132029I200J0D01*
G02X210380Y132103I167J-110D01*
G01X210718Y132248D01*
G02X210832Y132261I79J-184D01*
G01X210860Y132256D01*
X210912Y132230D01*
X210934Y132209D01*
G03X211969Y131796I1035J1090D01*
G03X213397Y132831I0J1503D01*
G01X213399Y132836D01*
Y132837D01*
G02X213473Y132934I188J-67D01*
G01X213725Y133084D01*
G02X213777Y133102I91J-178D01*
G01X213810Y133108D01*
X213827Y133105D01*
X213848Y133101D01*
G03X214116Y133077I267J1478D01*
G01X214124D01*
G03X215618Y134579I-8J1502D01*
G03X214116Y136081I-1502J0D01*
G03X212688Y135046I0J-1503D01*
G01X212686Y135041D01*
Y135040D01*
G02X212612Y134943I-188J67D01*
G01X212360Y134793D01*
G02X212308Y134775I-91J178D01*
G01X212275Y134769D01*
X212258Y134772D01*
X212237Y134776D01*
G03X211970Y134800I-267J-1478D01*
G01X211969D01*
G03X210934Y134387I0J-1503D01*
G01X210931Y134384D01*
G02X210831Y134334I-136J147D01*
G01X210803Y134329D01*
X210774Y134333D01*
G02X210719Y134347I21J199D01*
G01X210380Y134493D01*
G02X210259Y134676I79J184D01*
G01Y167057D01*
G02X210296Y167173I200J0D01*
G01X210314Y167199D01*
X210363Y167235D01*
X210394Y167246D01*
G03Y170084I-492J1419D01*
G01X210392Y170085D01*
G02X210296Y170157I66J189D01*
G01X210278Y170183D01*
X210269Y170211D01*
G02X210259Y170273I190J62D01*
G01Y171057D01*
G02X210296Y171173I200J0D01*
G01X210314Y171199D01*
X210363Y171235D01*
X210394Y171246D01*
G03Y174084I-492J1419D01*
G01X210392Y174085D01*
G02X210296Y174157I66J189D01*
G01X210278Y174183D01*
X210269Y174211D01*
G02X210259Y174273I190J62D01*
G01Y175057D01*
G02X210296Y175173I200J0D01*
G01X210314Y175199D01*
X210363Y175235D01*
X210394Y175246D01*
G03Y178084I-492J1419D01*
G01X210392Y178085D01*
G02X210296Y178157I66J189D01*
G01X210278Y178183D01*
X210269Y178211D01*
G02X210259Y178273I190J62D01*
G01Y179057D01*
G02X210296Y179173I200J0D01*
G01X210314Y179199D01*
X210363Y179235D01*
X210394Y179246D01*
G03Y182084I-492J1419D01*
G01X210392Y182085D01*
G02X210296Y182157I66J189D01*
G01X210278Y182183D01*
X210269Y182211D01*
G02X210259Y182273I190J62D01*
G01Y185140D01*
G02X210314Y185273I200J-5D01*
G01X210404Y185297D01*
G03Y188259I-388J1481D01*
G01X210314Y188283D01*
G02X210259Y188416I145J138D01*
G01Y191057D01*
G02X210296Y191173I200J0D01*
G01X210314Y191199D01*
X210363Y191235D01*
X210394Y191246D01*
G03Y194084I-492J1419D01*
G01X210392Y194085D01*
G02X210296Y194157I66J189D01*
G01X210278Y194183D01*
X210269Y194211D01*
G02X210259Y194273I190J62D01*
G01Y195057D01*
G02X210296Y195173I200J0D01*
G01X210314Y195199D01*
X210363Y195235D01*
X210394Y195246D01*
G03Y198084I-492J1419D01*
G01X210392Y198085D01*
G02X210296Y198157I66J189D01*
G01X210278Y198183D01*
X210269Y198211D01*
G02X210259Y198273I190J62D01*
G01Y199245D01*
G02X210294Y199358I200J0D01*
G01X210316Y199388D01*
X210366Y199425D01*
X210397Y199435D01*
G03Y202293I-463J1429D01*
G01X210366Y202303D01*
X210316Y202340D01*
X210294Y202370D01*
G02X210259Y202483I165J113D01*
G01Y203245D01*
G02X210294Y203358I200J0D01*
G01X210316Y203388D01*
X210366Y203425D01*
X210397Y203435D01*
G03Y206293I-463J1429D01*
G01X210366Y206303D01*
X210316Y206340D01*
X210294Y206370D01*
G02X210259Y206483I165J113D01*
G01Y207245D01*
G02X210294Y207358I200J0D01*
G01X210316Y207388D01*
X210366Y207425D01*
X210397Y207435D01*
G03Y210293I-463J1429D01*
G01X210366Y210303D01*
X210316Y210340D01*
X210294Y210370D01*
G02X210259Y210483I165J113D01*
G01Y211245D01*
G02X210294Y211358I200J0D01*
G01X210316Y211388D01*
X210366Y211425D01*
X210397Y211435D01*
G03Y214293I-463J1429D01*
G01X210366Y214303D01*
X210316Y214340D01*
X210294Y214370D01*
G02X210259Y214483I165J113D01*
G01Y215245D01*
G02X210294Y215358I200J0D01*
G01X210316Y215388D01*
X210366Y215425D01*
X210397Y215435D01*
G03Y218293I-463J1429D01*
G01X210366Y218303D01*
X210316Y218340D01*
X210294Y218370D01*
G02X210259Y218483I165J113D01*
G01Y220245D01*
G02X210294Y220358I200J0D01*
G01X210316Y220388D01*
X210366Y220425D01*
X210397Y220435D01*
G03Y223293I-463J1429D01*
G01X210366Y223303D01*
X210316Y223340D01*
X210294Y223370D01*
G02X210259Y223483I165J113D01*
G01Y241449D01*
G02X210263Y241486I200J-3D01*
G01Y241488D01*
G02X210316Y241589I196J-39D01*
G01X211077Y242350D01*
G02X211218Y242408I141J-142D01*
G01X221188D01*
G03X221218Y242409I-25J1201D01*
G01X224648D01*
G03X224672Y242408I62J1200D01*
G01X229148D01*
G02X229287Y242352I0J-200D01*
G01X229353Y242289D01*
X229492Y242155D01*
G02X229531Y242098I-143J-140D01*
G01X229547Y242063D01*
X229548Y242022D01*
G03X232550I1501J56D01*
G01Y242023D01*
X232552Y242064D01*
X232567Y242098D01*
G02X232605Y242154I182J-83D01*
G01X232780Y242322D01*
X232811Y242352D01*
G02X232950Y242408I139J-144D01*
G01X247084D01*
G02X247225Y242349I-1J-200D01*
G01X249691Y239883D01*
G02X249750Y239742I-141J-142D01*
G01Y153134D01*
G02X249745Y153090I-200J0D01*
G02X249696Y152997I-195J44D01*
G03Y147397I2423J-2800D01*
G02X249745Y147304I-146J-137D01*
G02X249750Y147260I-195J-44D01*
G01Y125156D01*
X249736Y125121D01*
G03X249634Y124576I1400J-544D01*
G03X249736Y124031I1502J-1D01*
G01X249750Y123996D01*
Y122966D01*
G03X249765Y122890I200J0D01*
G01X249785Y122842D01*
G02X249800Y122766I-185J-76D01*
G01Y117514D01*
G02X249760Y117394I-200J0D01*
G03Y115598I1203J-898D01*
G02X249800Y115478I-160J-120D01*
G01Y110661D01*
G03X249808Y110603I200J-2D01*
G02X249816Y110523I-191J-59D01*
G01X249803Y110412D01*
G02X249764Y110314I-199J22D01*
G03X249462Y109410I1202J-904D01*
G03X250964Y107908I1502J0D01*
G03X251896Y108232I0J1502D01*
G02X252161Y108217I124J-157D01*
G01X252730Y107648D01*
G03X252872Y107589I142J141D01*
G01X253621D01*
G03X253651Y107588I55J1200D01*
G01X269578D01*
G02X269778Y107388I0J-200D01*
G01Y104249D01*
G03X269811Y103902I1802J-4D01*
G01Y103900D01*
G03X269812Y103896I1748J435D01*
G02X269814Y103887I-194J-48D01*
G01X269816Y103879D01*
G02X269812Y103797I-198J-31D01*
G02X269804Y103772I-194J48D01*
G01X269782Y103719D01*
X269748Y103695D01*
X269715Y103672D01*
G02X269692Y103658I-115J164D01*
G01X269653Y103649D01*
G03X268822Y103888I-831J-1325D01*
G03X270387Y102323I0J-1565D01*
G03X270351Y102654I-1565J-3D01*
G02X270397Y102698I160J-121D01*
G01X270419Y102713D01*
G02X270523Y102746I110J-167D01*
G01X270580Y102747D01*
X270632Y102715D01*
G03X271614Y102446I948J1534D01*
G01X271627Y102447D01*
G03X273382Y104247I-47J1801D01*
G01Y107388D01*
G02X273582Y107588I200J0D01*
G01X309825D01*
G02X309863Y107584I-2J-200D01*
G02X309965Y107531I-37J-196D01*
G01X311402Y106094D01*
G02X311455Y105993I-143J-140D01*
G01Y105991D01*
G02X311459Y105954I-196J-40D01*
G01Y98506D01*
G02X311394Y98359I-200J1D01*
G01X311175Y98159D01*
G02X311022Y98108I-134J148D01*
G03X310882Y98115I-145J-1495D01*
G03X309380Y96613I0J-1502D01*
G03X309408Y96326I1502J2D01*
G02X309362Y96155I-196J-39D01*
G01X309153Y95917D01*
G02X308990Y95850I-150J133D01*
G03X308895Y95853I-95J-1499D01*
G03X310397Y94351I0J-1502D01*
G03X310369Y94638I-1502J-2D01*
G02X310415Y94809I196J39D01*
G01X310624Y95047D01*
G02X310787Y95114I150J-133D01*
G03X310882Y95111I95J1499D01*
G37*
G36*
G01X210373Y276294D02*
X285347D01*
G02X285489Y276235I0J-200D01*
G01X286773Y274951D01*
G02X286775Y274949I-140J-142D01*
G02X286832Y274809I-143J-140D01*
G01Y267385D01*
G02X286719Y267205I-200J0D01*
G01X286342Y267023D01*
X286229Y267036D01*
X286183Y267072D01*
G03X285249Y267398I-934J-1175D01*
G03Y264394I0J-1502D01*
G03X286183Y264720I0J1501D01*
G01X286229Y264756D01*
X286342Y264769D01*
X286719Y264587D01*
G02X286832Y264407I-87J-180D01*
G01Y257901D01*
X286778Y257809D01*
X286733Y257782D01*
X286731D01*
X286443Y257613D01*
G02X286369Y257588I-100J174D01*
G01X286328Y257583D01*
X286235Y257608D01*
X286213Y257620D01*
G03X285491Y257805I-723J-1319D01*
G01X285490D01*
G03Y254801I0J-1502D01*
G01X285491D01*
G03X286213Y254986I-1J1504D01*
G01X286235Y254998D01*
X286289Y255013D01*
G02X286369Y255018I52J-193D01*
G01X286408Y255013D01*
X286732Y254824D01*
G02X286735Y254822I-109J-167D01*
G02X286832Y254651I-103J-171D01*
G01Y207215D01*
G02X286830Y207189I-200J2D01*
G01X286825Y207148D01*
X286822Y207137D01*
G03X286774Y206760I1454J-377D01*
G01Y206691D01*
G03X286775Y206670I200J-1D01*
G01X286782Y206603D01*
G03X286787Y206560I1494J152D01*
G01X286796Y206495D01*
G03X286800Y206476I197J32D01*
G01Y206475D01*
X286816Y206407D01*
G03X286821Y206388I1455J373D01*
G01Y206384D01*
G03X286825Y206371I1437J435D01*
G01X286832Y206345D01*
Y202582D01*
G03X286891Y202440I200J0D01*
G01X287312Y202019D01*
G03X287454Y201960I142J141D01*
G01X290172D01*
G02X290205Y201957I-2J-200D01*
G02X290312Y201903I-32J-197D01*
G01X290627Y201588D01*
G03X290626Y201569I1198J-73D01*
G01Y193725D01*
G02X290540Y193561I-200J0D01*
G01X290290Y193386D01*
G02X290176Y193350I-114J164D01*
G01X290089D01*
X290058Y193361D01*
G03X289568Y193443I-490J-1420D01*
G01X289552D01*
G03X288066Y191941I16J-1502D01*
G03X289568Y190439I1502J0D01*
G01X289571D01*
G03X290089Y190532I-2J1502D01*
G01X290135Y190549D01*
X290232Y190537D01*
X290540Y190321D01*
G02X290626Y190157I-114J-164D01*
G01Y165175D01*
G02X290567Y165033I-200J0D01*
G01X287101Y161567D01*
X287073Y161538D01*
X286999Y161508D01*
X279985D01*
G02X279814Y161604I0J200D01*
G01X279637Y161896D01*
G02X279621Y161930I172J102D01*
G02X279632Y162094I188J70D01*
G01X279635Y162100D01*
X279652Y162135D01*
G03X279804Y162788I-1350J658D01*
G01Y162790D01*
Y162815D01*
G03X279401Y163817I-1502J-22D01*
G01X279400Y163818D01*
G02X279344Y163957I144J139D01*
G01Y164268D01*
X279371Y164338D01*
X279398Y164366D01*
G03Y166420I-1096J1027D01*
G01X279371Y166448D01*
X279344Y166518D01*
Y166868D01*
X279371Y166938D01*
X279398Y166966D01*
G03X279804Y167993I-1096J1027D01*
G03X279434Y168980I-1501J0D01*
G01X279410Y169008D01*
X279385Y169074D01*
Y169412D01*
X279410Y169478D01*
X279434Y169506D01*
G03X279804Y170493I-1131J987D01*
G03X276800I-1502J0D01*
G03X277170Y169506I1501J0D01*
G01X277194Y169478D01*
X277219Y169412D01*
Y169074D01*
X277194Y169008D01*
X277170Y168980D01*
G03X276800Y167993I1131J-987D01*
G03X277206Y166966I1502J0D01*
G01X277233Y166938D01*
X277260Y166868D01*
Y166518D01*
X277233Y166448D01*
X277206Y166420D01*
G03Y164366I1096J-1027D01*
G01X277233Y164338D01*
X277260Y164268D01*
Y163918D01*
X277233Y163849D01*
X277206Y163820D01*
G03X276800Y162821I1096J-1027D01*
G01Y162793D01*
G03X276952Y162134I1502J-1D01*
G01X276981Y162073D01*
G02X276983Y161930I-186J-74D01*
G02X276967Y161896I-188J68D01*
G01X276790Y161605D01*
X276763Y161559D01*
X276672Y161508D01*
X273048D01*
G02X272890Y161585I0J200D01*
G01X272667Y161870D01*
X272648Y161959D01*
X272659Y162005D01*
G03X272704Y162368I-1457J365D01*
G03X271202Y163870I-1502J0D01*
G03X270175Y163464I0J-1502D01*
G01X270147Y163437D01*
X270077Y163410D01*
X269727D01*
X269657Y163437D01*
X269629Y163464D01*
G03X268602Y163870I-1027J-1096D01*
G03X267100Y162368I0J-1502D01*
G03X267145Y162005I1502J2D01*
G01X267156Y161959D01*
X267137Y161870D01*
X266914Y161585D01*
G02X266756Y161508I-158J123D01*
G01X251608D01*
G02X251466Y161567I0J200D01*
G01X250810Y162223D01*
G02X250752Y162364I142J141D01*
G01Y240157D01*
G03X250693Y240298I-200J-1D01*
G01X247639Y243352D01*
G03X247499Y243410I-141J-142D01*
G01X240464D01*
G02X240306Y243488I0J200D01*
G01X240114Y243739D01*
G02X240074Y243886I159J122D01*
G01X240078Y243912D01*
X240081Y243924D01*
G03X240128Y244294I-1455J373D01*
G01Y244309D01*
G03X238826Y245786I-1502J-12D01*
G03X238626Y245799I-197J-1489D01*
G03X238259Y245753I2J-1502D01*
G01X238203Y245739D01*
X238096Y245773D01*
X237788Y246131D01*
X237770Y246242D01*
X237792Y246295D01*
G03X237908Y246874I-1387J579D01*
G03X236406Y248376I-1502J0D01*
G03X235377Y247968I0J-1502D01*
G01X235343Y247936D01*
X235257Y247909D01*
X234903Y247958D01*
G02X234895Y247959I21J199D01*
G02X234758Y248055I36J197D01*
G03X233464Y248794I-1294J-763D01*
G03Y245790I0J-1502D01*
G03X234493Y246198I0J1502D01*
G01X234527Y246230D01*
X234613Y246257D01*
X234967Y246208D01*
G02X234975Y246207I-21J-199D01*
G02X235112Y246111I-36J-197D01*
G03X236406Y245372I1294J763D01*
G03X236773Y245418I-2J1502D01*
G01X236829Y245432D01*
X236936Y245398D01*
X237244Y245040D01*
X237262Y244929D01*
X237240Y244876D01*
G03X237124Y244309I1387J-579D01*
G01Y244294D01*
G03X237171Y243924I1502J3D01*
G01X237174Y243912D01*
X237178Y243886D01*
G02X237138Y243739I-199J-25D01*
G01X236946Y243488D01*
G02X236788Y243410I-158J122D01*
G01X231767D01*
X231721Y243422D01*
X231702Y243431D01*
X231700Y243432D01*
G03X231458Y243523I-648J-1355D01*
G03X230798Y243559I-410J-1445D01*
G03X230394Y243430I250J-1481D01*
G01X230374Y243420D01*
X230330Y243410D01*
X224674D01*
G02X224506Y243501I0J200D01*
G01X224295Y243824D01*
X224291Y243875D01*
X224287Y243924D01*
X224299Y243952D01*
Y243953D01*
X224308Y243973D01*
G03X224432Y244571I-1378J598D01*
G01Y244590D01*
G03X221428I-1502J-19D01*
G01Y244570D01*
G03X221553Y243971I1502J1D01*
G01X221573Y243925D01*
X221569Y243875D01*
X221565Y243824D01*
X221354Y243501D01*
X221326Y243458D01*
X221238Y243410D01*
X211249D01*
X211175Y243440D01*
X211147Y243469D01*
X209538Y245078D01*
X209509Y245106D01*
X209479Y245180D01*
Y275400D01*
G02X209536Y275540I200J0D01*
G01X209537Y275541D01*
X210231Y276235D01*
G02X210233Y276237I142J-140D01*
G02X210373Y276294I140J-143D01*
G37*
G36*
G01X205033Y1242007D02*
G03X205105Y1241971I1734J3378D01*
G02X205197Y1241876I-90J-179D01*
G03X205513Y1241327I3463J1628D01*
G02X205540Y1241269I-165J-112D01*
G03X206427Y1240382I1251J364D01*
G02X206485Y1240355I-54J-192D01*
G03X207234Y1239952I2176J3148D01*
G02X207359Y1239767I-75J-185D01*
G01Y1239763D01*
G03X207665Y1238925I1302J0D01*
G01X207635Y1238901D01*
G03X207427Y1238679I766J-926D01*
G03X207425Y1238676I166J-113D01*
G02X207421Y1238670I-168J108D01*
G03X207414Y1238661I154J-127D01*
G03X207408Y1238652I164J-116D01*
G01X207407Y1238650D01*
X207137Y1238229D01*
G03X207106Y1238133I169J-107D01*
G01X207091Y1237875D01*
Y1237873D01*
G02X206791Y1237592I-300J20D01*
G02X206490Y1237893I0J301D01*
G01Y1237931D01*
G03X205740Y1239043I-1201J-1D01*
G02X205536Y1239136I1056J2588D01*
G01X205521Y1239144D01*
X205511Y1239150D01*
G03X205490Y1239162I-110J-167D01*
G01X205487Y1239164D01*
G02X205468Y1239173I1187J2529D01*
G01X205442Y1239186D01*
X205417Y1239200D01*
X205319Y1239255D01*
X205317D01*
X205197Y1239321D01*
G03X205096Y1239346I-97J-175D01*
G01X204826Y1239341D01*
G03X204228Y1239168I23J-1201D01*
G02X204215Y1239161I-101J173D01*
G01X203945Y1238993D01*
G02X203850Y1238968I-97J175D01*
G01X203817D01*
X203765Y1238982D01*
X203762Y1238984D01*
X203740Y1238998D01*
G03X203050Y1239196I-690J-1105D01*
G03X202580Y1239108I1J-1303D01*
G03X202404Y1239024I471J-1214D01*
G01X202376Y1239008D01*
X202357Y1238996D01*
G02X202215Y1238971I-103J171D01*
G03X202483Y1239763I-1036J792D01*
G01Y1239767D01*
G02X202608Y1239952I200J0D01*
G03X204645Y1241876I-1427J3551D01*
G02X204762Y1241981I181J-84D01*
G01X204877Y1242019D01*
G02X205033Y1242007I64J-189D01*
G37*
G36*
G01X212513D02*
G03X212585Y1241971I1734J3378D01*
G02X212677Y1241876I-90J-179D01*
G03X212993Y1241327I3463J1628D01*
G02X213020Y1241269I-165J-112D01*
G03X213907Y1240382I1251J364D01*
G02X213965Y1240355I-54J-192D01*
G03X214714Y1239952I2176J3148D01*
G02X214839Y1239767I-75J-185D01*
G01Y1239763D01*
G03X215145Y1238925I1302J0D01*
G01X215115Y1238901D01*
G03X214907Y1238679I766J-926D01*
G03X214905Y1238676I166J-113D01*
G02X214901Y1238670I-168J108D01*
G03X214894Y1238661I154J-127D01*
G03X214888Y1238652I164J-116D01*
G01X214887Y1238650D01*
X214617Y1238229D01*
G03X214586Y1238133I169J-107D01*
G01X214571Y1237875D01*
Y1237873D01*
G02X214271Y1237592I-300J20D01*
G02X213970Y1237893I0J301D01*
G01Y1237931D01*
G03X213220Y1239043I-1201J-1D01*
G02X213016Y1239136I1056J2588D01*
G01X213001Y1239144D01*
X212991Y1239150D01*
G03X212970Y1239162I-110J-167D01*
G01X212967Y1239164D01*
G02X212948Y1239173I1187J2529D01*
G01X212922Y1239186D01*
X212897Y1239200D01*
X212799Y1239255D01*
X212797D01*
X212677Y1239321D01*
G03X212576Y1239346I-97J-175D01*
G01X212306Y1239341D01*
G03X211708Y1239168I23J-1201D01*
G02X211695Y1239161I-101J173D01*
G01X211425Y1238993D01*
G02X211330Y1238968I-97J175D01*
G01X211297D01*
X211245Y1238982D01*
X211242Y1238984D01*
X211220Y1238998D01*
G03X210530Y1239196I-690J-1105D01*
G03X210060Y1239108I1J-1303D01*
G03X209884Y1239024I471J-1214D01*
G01X209856Y1239008D01*
X209837Y1238996D01*
G02X209695Y1238971I-103J171D01*
G03X209963Y1239763I-1036J792D01*
G01Y1239767D01*
G02X210088Y1239952I200J0D01*
G03X212125Y1241876I-1427J3551D01*
G02X212242Y1241981I181J-84D01*
G01X212357Y1242019D01*
G02X212513Y1242007I64J-189D01*
G37*
G36*
G01X305237Y202336D02*
X308749D01*
G02X308890Y202278I0J-200D01*
G01X310930Y200238D01*
X310945Y200207D01*
G03X310984Y200132I1352J655D01*
G01X310985Y200131D01*
G03X311000Y200105I1308J738D01*
G01X311013Y200083D01*
X311029Y200027D01*
X311042Y199981D01*
Y197600D01*
G02X311009Y197490I-200J0D01*
G03Y195840I1254J-825D01*
G02X311042Y195730I-167J-110D01*
G01Y193600D01*
G02X311009Y193490I-200J0D01*
G03Y191840I1254J-825D01*
G02X311042Y191730I-167J-110D01*
G01Y187518D01*
X311032Y187475D01*
X311021Y187453D01*
G03Y186103I1355J-675D01*
G01X311032Y186081D01*
X311042Y186038D01*
Y181600D01*
G02X311009Y181490I-200J0D01*
G03Y179840I1254J-825D01*
G02X311042Y179730I-167J-110D01*
G01Y177600D01*
G02X311009Y177490I-200J0D01*
G03Y175840I1254J-825D01*
G02X311042Y175730I-167J-110D01*
G01Y173600D01*
G02X311009Y173490I-200J0D01*
G03Y171840I1254J-825D01*
G02X311042Y171730I-167J-110D01*
G01Y169600D01*
G02X311009Y169490I-200J0D01*
G03Y167840I1254J-825D01*
G02X311042Y167730I-167J-110D01*
G01Y163086D01*
G02X310987Y162947I-200J-1D01*
G01X310905Y162862D01*
X310872Y162846D01*
X310780Y162801D01*
X310747Y162797D01*
G03Y159815I182J-1491D01*
G01X310780Y159811D01*
X310873Y159766D01*
G02X310930Y159724I-88J-180D01*
G01X310987Y159665D01*
G02X311042Y159526I-145J-138D01*
G01Y151308D01*
G02X310842Y151108I-200J0D01*
G01X304268D01*
G02X304092Y151213I0J200D01*
G01X303926Y151523D01*
G02X303902Y151625I176J95D01*
G01X303904Y151682D01*
X303935Y151729D01*
G03X304187Y152562I-1251J833D01*
G03X302685Y154064I-1502J0D01*
G03X301391Y153325I0J-1502D01*
G01X301365Y153281D01*
X301281Y153229D01*
X301102Y153219D01*
X300849Y153204D01*
X300759Y153245D01*
X300729Y153285D01*
G03X299535Y153875I-1194J-913D01*
G03X298033Y152373I0J-1502D01*
G03X298198Y151689I1502J0D01*
G01X298222Y151642D01*
X298218Y151539D01*
X298012Y151203D01*
G02X297842Y151108I-170J105D01*
G01X288524D01*
G02X288396Y151155I1J200D01*
G01X287563Y151988D01*
X287258Y152292D01*
G03X285843Y152878I-1415J-1415D01*
G01X279483D01*
G03X278068Y152292I0J-2001D01*
G01X274731Y148955D01*
G03X274208Y148042I1414J-1416D01*
G03X274144Y147540I1938J-502D01*
G03X276142Y145538I2002J0D01*
G01X276146D01*
G03X276648Y145602I0J2002D01*
G03X277561Y146125I-503J1937D01*
G01X280253Y148817D01*
G02X280395Y148876I142J-141D01*
G01X282873D01*
G02X283022Y148809I0J-200D01*
G01X283221Y148588D01*
G02X283271Y148437I-149J-133D01*
G01Y148434D01*
G03X283263Y148277I1494J-155D01*
G03X284765Y146775I1502J0D01*
G03X285954Y147359I0J1502D01*
G01X285978Y147390D01*
X286011Y147410D01*
G02X286081Y147435I101J-173D01*
G01X286350Y147479D01*
G02X286494Y147447I32J-198D01*
G01X286495Y147446D01*
G03X286959Y147214I1120J1659D01*
G03X287614Y147104I654J1892D01*
G01X310842D01*
G02X311042Y146904I0J-200D01*
G01Y124540D01*
X311039Y124524D01*
G03X311020Y124283I1483J-238D01*
G03X311039Y124042I1502J-3D01*
G01X311042Y124026D01*
Y120752D01*
X310988Y120618D01*
X310965Y120592D01*
G03Y118596I1124J-998D01*
G01X310988Y118570D01*
X311042Y118436D01*
Y117752D01*
X310988Y117618D01*
X310965Y117592D01*
G03X310586Y116594I1124J-998D01*
G01Y116592D01*
G03X310890Y115687I1503J1D01*
G02X310930Y115567I-160J-120D01*
G01Y114421D01*
G02X310890Y114301I-200J0D01*
G03Y112487I1199J-907D01*
G02X310930Y112367I-160J-120D01*
G01Y111745D01*
G03X310960Y111640I200J0D01*
G01X311011Y111560D01*
G02X311042Y111453I-169J-107D01*
G01Y109734D01*
G02X310983Y109592I-200J0D01*
G01X310040Y108649D01*
G02X309898Y108590I-142J141D01*
G01X273226D01*
G02X273062Y108676I0J200D01*
G03X270098I-1482J-1027D01*
G02X269934Y108590I-164J114D01*
G01X253653D01*
G02X253511Y108649I0J200D01*
G01X252452Y109708D01*
X252427Y109753D01*
X252420Y109780D01*
G03X251334Y110866I-1456J-370D01*
G01X251307Y110873D01*
X251262Y110898D01*
X251200Y110960D01*
G02X251141Y111102I141J142D01*
G01Y114907D01*
X251228Y115016D01*
X251297Y115031D01*
G03Y117961I-333J1465D01*
G01X251228Y117976D01*
X251141Y118085D01*
Y122963D01*
X251241Y123076D01*
X251317Y123085D01*
G03Y126067I-181J1491D01*
G01X251241Y126076D01*
X251141Y126189D01*
Y159263D01*
G02X251200Y159405I200J0D01*
G01X252063Y160268D01*
G02X252205Y160327I142J-141D01*
G01X287722D01*
G03X287864Y160386I0J200D01*
G01X291569Y164091D01*
G03X291628Y164233I-141J142D01*
G01Y201543D01*
Y201555D01*
X291630Y201580D01*
G02X291688Y201710I200J-11D01*
G01X292255Y202277D01*
G02X292397Y202336I142J-141D01*
G01X302097D01*
G02X302274Y202229I0J-200D01*
G01X302438Y201916D01*
G02X302427Y201711I-177J-93D01*
G01X302426Y201710D01*
G03X302165Y200873I1241J-846D01*
G01Y200845D01*
G03X305169I1502J19D01*
G01Y200865D01*
G03X304908Y201711I-1502J0D01*
G01X304876Y201757D01*
X304870Y201867D01*
X305060Y202229D01*
G02X305237Y202336I177J-93D01*
G37*
G36*
G01X342382Y54588D02*
X371080D01*
X371204Y54464D01*
Y52932D01*
X370863Y52591D01*
X342382D01*
G03X336445Y46654I0J-5937D01*
G01Y7874D01*
G02X330571Y2000I-5874J0D01*
G01X283327D01*
G02X277453Y7874I0J5874D01*
G01Y46126D01*
X279450D01*
Y7874D01*
G03X283325Y3998I3876J0D01*
G01X330571D01*
G03X334448Y7874I0J3877D01*
G01Y46654D01*
G02X342382Y54588I7934J0D01*
G37*
G36*
G01X288034Y275932D02*
X309969D01*
X310043Y275902D01*
X310071Y275873D01*
X310682Y275262D01*
G02X310741Y275120I-141J-142D01*
G01Y205020D01*
X310711Y204946D01*
X310682Y204918D01*
X309161Y203397D01*
G02X309019Y203338I-142J141D01*
G01X288152D01*
X288078Y203368D01*
X288050Y203397D01*
X287892Y203555D01*
G02X287834Y203696I142J141D01*
G01Y204858D01*
G02X287894Y205001I200J0D01*
G01X288128Y205230D01*
X288202Y205259D01*
X288242Y205258D01*
X288276D01*
G03Y208262I0J1502D01*
G01X288242D01*
X288202Y208261D01*
X288128Y208290D01*
X287894Y208519D01*
G02X287834Y208661I140J143D01*
G01Y255107D01*
G02X287952Y255289I200J0D01*
G01X288276Y255436D01*
G02X288447Y255432I81J-183D01*
G01X288497Y255407D01*
X288516Y255392D01*
G03X289490Y255033I975J1143D01*
G03Y258037I0J1502D01*
G03X288516Y257678I1J-1502D01*
G01X288497Y257663D01*
X288447Y257638D01*
G02X288276Y257634I-90J179D01*
G01X287952Y257781D01*
G02X287834Y257963I82J182D01*
G01Y275732D01*
G02X288034Y275932I200J0D01*
G37*
G36*
G01X352123Y117395D02*
G03Y115597I1202J-899D01*
G02X352163Y115477I-160J-120D01*
G01Y110661D01*
G03X352171Y110604I200J-1D01*
G02X352179Y110524I-191J-59D01*
G01X352166Y110413D01*
G02X352127Y110315I-199J22D01*
G03X351824Y109410I1200J-905D01*
G03X353326Y107908I1502J0D01*
G03X354258Y108232I0J1502D01*
G02X354524Y108217I125J-156D01*
G01X355093Y107648D01*
G03X355235Y107589I142J141D01*
G01X355984D01*
G03X356014Y107588I55J1200D01*
G01X371940D01*
G02X372140Y107388I0J-200D01*
G01Y104249D01*
G03X372173Y103903I1802J-3D01*
G01Y103900D01*
G03X372176Y103888I1749J431D01*
G01Y103886D01*
G02X372166Y103773I-196J-40D01*
G01X372155Y103746D01*
X372119Y103701D01*
X372107Y103693D01*
X372078Y103672D01*
G02X371890Y103650I-114J164D01*
G01X371874Y103658D01*
G03X371869Y103660I-77J-184D01*
G03X371185Y103825I-684J-1335D01*
G01X371184D01*
G03Y100821I0J-1502D01*
G01X371185D01*
G03X372687Y102323I0J1502D01*
G03X372675Y102508I-1502J-5D01*
G01Y102512D01*
G02X372759Y102697I199J21D01*
G01X372777Y102709D01*
G02X372884Y102745I115J-164D01*
G01X372913Y102746D01*
X372969Y102731D01*
X372995Y102715D01*
G03X373942Y102446I947J1534D01*
G03X375744Y104247I0J1802D01*
G01Y107388D01*
G02X375944Y107588I200J0D01*
G01X412188D01*
G02X412226Y107584I-2J-200D01*
G02X412328Y107531I-37J-196D01*
G01X413765Y106094D01*
G02X413818Y105993I-143J-140D01*
G01Y105991D01*
G02X413822Y105954I-196J-40D01*
G01Y78371D01*
G02X413813Y78313I-200J1D01*
G03X412428Y70866I19317J-7445D01*
G03X413813Y63419I20702J-2D01*
G02X413822Y63361I-191J-59D01*
G01Y34247D01*
G02X413774Y34117I-200J0D01*
G01X413751Y34090D01*
X413693Y34057D01*
X413655Y34050D01*
G03X413654Y31088I249J-1481D01*
G01X413655D01*
X413670Y31086D01*
G02X413775Y31021I-48J-195D01*
G01X413797Y30994D01*
X413809Y30961D01*
G02X413822Y30891I-187J-71D01*
G01Y29105D01*
G02X413783Y28987I-200J1D01*
G01X413765Y28962D01*
X413716Y28926D01*
X413683Y28915D01*
G03X413682Y26057I462J-1429D01*
G01X413684D01*
X413685Y26056D01*
G02X413784Y25984I-62J-190D01*
G01X413803Y25959D01*
X413813Y25928D01*
G02X413822Y25868I-191J-59D01*
G01Y24964D01*
G02X413800Y24873I-200J0D01*
G02X413764Y24823I-178J90D01*
G01X412519Y23578D01*
G02X412383Y23520I-141J142D01*
G01X412295Y23523D01*
X412293D01*
X412064Y23532D01*
G02X412005Y23548I22J198D01*
G01X411959Y23570D01*
X411933Y23600D01*
X411932Y23601D01*
G03X410789Y24129I-1143J-973D01*
G03X409287Y22627I0J-1502D01*
G01Y22626D01*
G03X409505Y21847I1502J0D01*
G01X409516Y21829D01*
G02X409535Y21747I-181J-85D01*
G01X409536Y21694D01*
X409424Y21494D01*
Y21492D01*
X409338Y21341D01*
G02X409164Y21239I-174J98D01*
G01X384175D01*
G02X384084Y21261I0J200D01*
G02X384034Y21297I90J178D01*
G01X382995Y22336D01*
G02X382959Y22386I142J140D01*
G02X382937Y22477I178J91D01*
G01Y28749D01*
G02X382997Y28879I200J-13D01*
G01X383068Y28942D01*
X383070D01*
X383236Y29086D01*
G02X383311Y29126I129J-152D01*
G01X383319Y29128D01*
X383352Y29138D01*
X383395Y29132D01*
G03X383612Y29116I219J1486D01*
G03Y32120I0J1502D01*
G03X383395Y32104I2J-1502D01*
G01X383352Y32098D01*
X383319Y32108D01*
X383311Y32110D01*
G02X383236Y32150I54J192D01*
G01X383070Y32294D01*
X383068D01*
X382997Y32357D01*
G02X382937Y32487I140J143D01*
G01Y53461D01*
G02X382939Y53489I200J0D01*
G02X383060Y53646I198J-28D01*
G03X388796Y61614I-2666J7968D01*
G03X371992I-8402J0D01*
G03X372612Y58447I8402J1D01*
G01Y58446D01*
G02X372626Y58351I-185J-76D01*
G01X372621Y58302D01*
X372407Y57984D01*
G02X372242Y57896I-166J112D01*
G01X365095D01*
G02X365061Y57899I1J200D01*
G02X365000Y57920I34J197D01*
G01Y57921D01*
G02X364919Y58002I95J176D01*
G01X364841Y58155D01*
Y58157D01*
X364753Y58331D01*
G02X364735Y58429I181J84D01*
G01X364738Y58459D01*
X364740Y58465D01*
G03X365494Y60709I-2961J2244D01*
G03X365030Y62509I-3715J2D01*
G02X365028Y62534I198J28D01*
G01Y62581D01*
X365132Y62774D01*
X365212Y62922D01*
G02X365245Y62966I175J-97D01*
G02X365279Y62995I146J-137D01*
G01X365318Y63020D01*
X365369Y63025D01*
G03X368303Y68727I-350J3786D01*
G03X361675Y65000I-3285J-1916D01*
G01X361684Y64983D01*
G02X361700Y64900I-184J-79D01*
G01X361699Y64850D01*
X361579Y64648D01*
X361496Y64508D01*
X361495Y64507D01*
G03X361493Y64503I177J-91D01*
G02X361397Y64424I-169J107D01*
G01X354479D01*
G03X350764Y60709I0J-3715D01*
G01Y60707D01*
G03X351521Y58461I3715J2D01*
G01X351522Y58457D01*
X351524Y58429D01*
G02X351503Y58323I-199J-16D01*
G01X351440Y58199D01*
Y58197D01*
X351336Y57995D01*
G02X351270Y57927I-172J101D01*
G01X351254Y57919D01*
G02X351162Y57896I-93J177D01*
G01X314467D01*
G02X314376Y57918I0J200D01*
G02X314326Y57954I90J178D01*
G01X313533Y58747D01*
G02X313483Y58945I142J141D01*
G01X313599Y59271D01*
X313609Y59300D01*
G02X313672Y59387I188J-70D01*
G01X313694Y59404D01*
X313746Y59425D01*
X313776Y59428D01*
G03X315126Y60922I-152J1494D01*
G03X313624Y62424I-1502J0D01*
G01X313622D01*
G03X313196Y62362I1J-1502D01*
G01X313157Y62350D01*
X313149Y62348D01*
X313104Y62356D01*
G02X313029Y62386I35J197D01*
G01X313009Y62400D01*
X312762Y62583D01*
G02X312736Y62606I119J161D01*
G02X312684Y62710I145J138D01*
G02X312681Y62744I197J35D01*
G01Y84661D01*
G02X312682Y84674I199J-9D01*
G01Y84678D01*
G02X312754Y84816I199J-16D01*
G03Y87276I-862J1230D01*
G02X312682Y87414I127J154D01*
G01Y87418D01*
G02X312681Y87431I198J22D01*
G01Y92476D01*
G02X312684Y92509I200J-2D01*
G01X312696Y92572D01*
X312698Y92576D01*
G02X312735Y92633I184J-79D01*
G01X312747Y92645D01*
X312797Y92696D01*
G02X312854Y92736I142J-141D01*
G01X312948Y92780D01*
X312983Y92783D01*
G03X314346Y94279I-139J1496D01*
G03X312903Y95781I-1503J0D01*
G01X312890D01*
X312854Y95787D01*
X312848Y95789D01*
G02X312824Y95798I58J191D01*
G02X312774Y95831I84J181D01*
G01X312679Y95924D01*
G02X312666Y95939I144J138D01*
G02X312622Y96060I156J125D01*
G01Y108858D01*
G02X312653Y108965I200J0D01*
G01X312668Y108988D01*
X312709Y109025D01*
X312736Y109038D01*
G03X313281Y109480I-648J1355D01*
G01X313288Y109489D01*
G02X313296Y109498I153J-128D01*
G01X313330Y109532D01*
G02X313421Y109570I120J-160D01*
G01X313666Y109606D01*
X313668D01*
X313699Y109611D01*
G02X313778Y109607I30J-198D01*
G01X313814Y109598D01*
X313847Y109574D01*
G03X314737Y109282I890J1210D01*
G01X314768D01*
G03X316038Y110033I-31J1502D01*
G02X316071Y110075I172J-102D01*
G01X316081Y110085D01*
X316101Y110100D01*
X316112Y110106D01*
G02X316212Y110133I100J-173D01*
G01X316504D01*
G02X316603Y110106I-1J-200D01*
G01X316684Y110060D01*
G02X316724Y110029I-102J-172D01*
G01X316742Y110012D01*
X316755Y109990D01*
G03X318031Y109281I1276J794D01*
G01X318044D01*
X318091Y109283D01*
G03Y112285I-59J1501D01*
G01X318044Y112287D01*
X318031D01*
G03X316755Y111578I0J-1503D01*
G01X316742Y111556D01*
X316724Y111539D01*
G02X316684Y111508I-142J141D01*
G01X316603Y111462D01*
G02X316504Y111435I-100J173D01*
G01X316201D01*
G02X316042Y111529I11J200D01*
G03X314738Y112286I-1304J-745D01*
G01X314737D01*
G03X313527Y111674I0J-1502D01*
G02X313420Y111611I-150J132D01*
G02X313406Y111608I-49J194D01*
G01X313127Y111567D01*
G02X312987Y111598I-30J198D01*
G01X312980Y111603D01*
G03X312958Y111619I-894J-1207D01*
G02X312954Y111621I86J178D01*
G03X312931Y111638I-904J-1199D01*
G01X312909Y111653D01*
X312897Y111667D01*
G02X312874Y111697I146J136D01*
G01X312819Y111797D01*
G02X312799Y111883I180J87D01*
G01Y111905D01*
G02X312819Y111991I200J-1D01*
G01X312870Y112083D01*
G02X312897Y112122I177J-94D01*
G01X312911Y112137D01*
X312917Y112141D01*
X312933Y112152D01*
G03X312957Y112169I-856J1234D01*
G02X312959Y112171I141J-139D01*
G03X313591Y113394I-867J1223D01*
G03X312736Y114750I-1503J0D01*
G01X312735Y114751D01*
G02X312652Y114824I85J181D01*
G01X312637Y114847D01*
X312629Y114875D01*
G02X312622Y114928I193J52D01*
G01Y115058D01*
G02X312653Y115165I200J0D01*
G01X312668Y115188D01*
X312709Y115225D01*
X312736Y115238D01*
G03X313591Y116594I-648J1356D01*
G03X313012Y117779I-1502J0D01*
G02X312937Y117907I123J158D01*
G02X312935Y117934I198J28D01*
G01Y118254D01*
G02X312937Y118281I200J-1D01*
G02X313012Y118409I198J-30D01*
G03X313591Y119594I-923J1185D01*
G03X312736Y120950I-1503J0D01*
G01X312735Y120951D01*
G02X312652Y121024I85J181D01*
G01X312637Y121047D01*
X312629Y121075D01*
G02X312622Y121128I193J52D01*
G01Y122608D01*
G02X312623Y122623I200J-6D01*
G01Y122625D01*
G02X312770Y122801I199J-17D01*
G01X312771D01*
G03X312787Y125762I-248J1482D01*
G01X312773Y125765D01*
G02X312623Y125941I49J194D01*
G01Y125943D01*
G02X312622Y125958I199J21D01*
G01Y131919D01*
G02X312655Y132029I200J0D01*
G02X312739Y132101I167J-110D01*
G01X312911Y132176D01*
X312913D01*
X313081Y132248D01*
G02X313195Y132261I79J-184D01*
G01X313223Y132256D01*
X313275Y132230D01*
X313297Y132209D01*
G03X313417Y132106I1038J1088D01*
G01X313441Y132087D01*
X313447Y132083D01*
X313464Y132056D01*
G02X313489Y131993I-171J-104D01*
G01X313514Y131879D01*
X313547Y131729D01*
G02X313548Y131668I-197J-34D01*
G01Y131664D01*
X313543Y131633D01*
X313533Y131614D01*
X313526Y131601D01*
G03X313352Y130899I1328J-702D01*
G01Y130876D01*
G03X314854Y129396I1502J22D01*
G03X316356Y130898I0J1502D01*
G03X315769Y132089I-1502J0D01*
G01X315739Y132112D01*
X315721Y132141D01*
G02X315698Y132194I170J105D01*
G01X315692Y132221D01*
X315640Y132457D01*
G02X315637Y132529I195J44D01*
G01X315642Y132562D01*
X315659Y132594D01*
G03X315760Y132831I-1326J705D01*
G01X315772Y132867D01*
X315794Y132894D01*
G02X315847Y132940I155J-125D01*
G01X316076Y133078D01*
X316105Y133095D01*
X316175Y133107D01*
X316211Y133101D01*
G03X316468Y133077I268J1478D01*
G01X316477D01*
G03X316481I2J1502D01*
G01X316482D01*
G03X317981Y134579I-3J1502D01*
G03X316528Y136080I-1502J0D01*
G01X316526D01*
G03X316496Y136081I-65J-1500D01*
G01X316493D01*
X316478Y136082D01*
G03X315051Y135050I0J-1503D01*
G01X315039Y135009D01*
X315017Y134982D01*
G02X314974Y134943I-155J127D01*
G01X314730Y134797D01*
G02X314670Y134775I-98J174D01*
G01X314638Y134769D01*
X314621Y134772D01*
X314600Y134776D01*
G03X314333Y134800I-267J-1478D01*
G01X314332D01*
G03X313297Y134387I0J-1503D01*
G01X313294Y134384D01*
G02X313194Y134334I-136J147D01*
G01X313166Y134329D01*
X313137Y134333D01*
G02X313082Y134347I21J199D01*
G01X312743Y134493D01*
G02X312622Y134676I79J184D01*
G01Y166995D01*
G02X312657Y167108I200J0D01*
G01X312748Y167241D01*
X312788Y167257D01*
G03X312769Y170080I-523J1408D01*
G02X312745Y170090I65J189D01*
G01X312710Y170108D01*
G02X312622Y170273I112J166D01*
G01Y170995D01*
G02X312657Y171108I200J0D01*
G01X312748Y171241D01*
X312788Y171257D01*
G03X312769Y174080I-523J1408D01*
G02X312745Y174090I65J189D01*
G01X312710Y174108D01*
G02X312622Y174273I112J166D01*
G01Y174995D01*
G02X312657Y175108I200J0D01*
G01X312748Y175241D01*
X312788Y175257D01*
G03X312769Y178080I-523J1408D01*
G02X312745Y178090I65J189D01*
G01X312710Y178108D01*
G02X312622Y178273I112J166D01*
G01Y178995D01*
G02X312657Y179108I200J0D01*
G01X312748Y179241D01*
X312788Y179257D01*
G03X312769Y182080I-523J1408D01*
G02X312745Y182090I65J189D01*
G01X312710Y182108D01*
G02X312622Y182273I112J166D01*
G01Y185149D01*
G02X312691Y185287I200J-14D01*
G01X312770Y185308D01*
G03Y188248I-392J1470D01*
G01X312691Y188269D01*
G02X312622Y188407I131J152D01*
G01Y190995D01*
G02X312657Y191108I200J0D01*
G01X312748Y191241D01*
X312788Y191257D01*
G03X312769Y194080I-523J1408D01*
G02X312745Y194090I65J189D01*
G01X312710Y194108D01*
G02X312622Y194273I112J166D01*
G01Y194995D01*
G02X312657Y195108I200J0D01*
G01X312748Y195241D01*
X312788Y195257D01*
G03X312769Y198080I-523J1408D01*
G02X312745Y198090I65J189D01*
G01X312710Y198108D01*
G02X312622Y198273I112J166D01*
G01Y199245D01*
G02X312657Y199358I200J0D01*
G01X312679Y199388D01*
X312729Y199425D01*
X312760Y199435D01*
G03Y202293I-463J1429D01*
G01X312729Y202303D01*
X312679Y202340D01*
X312657Y202370D01*
G02X312622Y202483I165J113D01*
G01Y203245D01*
G02X312657Y203358I200J0D01*
G01X312679Y203388D01*
X312729Y203425D01*
X312760Y203435D01*
G03Y206293I-463J1429D01*
G01X312729Y206303D01*
X312679Y206340D01*
X312657Y206370D01*
G02X312622Y206483I165J113D01*
G01Y207245D01*
G02X312657Y207358I200J0D01*
G01X312679Y207388D01*
X312729Y207425D01*
X312760Y207435D01*
G03Y210293I-463J1429D01*
G01X312729Y210303D01*
X312679Y210340D01*
X312657Y210370D01*
G02X312622Y210483I165J113D01*
G01Y211245D01*
G02X312657Y211358I200J0D01*
G01X312679Y211388D01*
X312729Y211425D01*
X312760Y211435D01*
G03Y214293I-463J1429D01*
G01X312729Y214303D01*
X312679Y214340D01*
X312657Y214370D01*
G02X312622Y214483I165J113D01*
G01Y215245D01*
G02X312657Y215358I200J0D01*
G01X312679Y215388D01*
X312729Y215425D01*
X312760Y215435D01*
G03Y218293I-463J1429D01*
G01X312729Y218303D01*
X312679Y218340D01*
X312657Y218370D01*
G02X312622Y218483I165J113D01*
G01Y220245D01*
G02X312657Y220358I200J0D01*
G01X312679Y220388D01*
X312729Y220425D01*
X312760Y220435D01*
G03Y223293I-463J1429D01*
G01X312729Y223303D01*
X312679Y223340D01*
X312657Y223370D01*
G02X312622Y223483I165J113D01*
G01Y241449D01*
G02X312626Y241486I200J-3D01*
G01Y241488D01*
G02X312679Y241589I196J-39D01*
G01X313440Y242350D01*
G02X313581Y242408I141J-142D01*
G01X323550D01*
G03X323580Y242409I-25J1201D01*
G01X327012D01*
G03X327035Y242408I64J1200D01*
G01X331511D01*
G02X331650Y242352I0J-200D01*
G01X331724Y242281D01*
X331855Y242155D01*
G02X331893Y242099I-144J-139D01*
G01X331908Y242065D01*
X331910Y242024D01*
G03X333411Y240576I1501J54D01*
G01X333412D01*
G03X334913Y242022I0J1502D01*
G01Y242023D01*
X334915Y242064D01*
X334930Y242098D01*
G02X334968Y242154I182J-83D01*
G01X335143Y242322D01*
X335174Y242352D01*
G02X335313Y242408I139J-144D01*
G01X349446D01*
G02X349587Y242349I-1J-200D01*
G01X352061Y239875D01*
G02X352112Y239755I-148J-134D01*
G01Y162363D01*
G03X352113Y162332I1201J23D01*
G01Y153135D01*
G02X352106Y153083I-200J0D01*
G02X352059Y153000I-192J54D01*
G03X351371Y152207I2424J-2798D01*
G03X350778Y150197I3108J-2010D01*
G03X351371Y148187I3701J0D01*
G03X352059Y147394I3112J2005D01*
G02X352106Y147311I-145J-137D01*
G02X352113Y147259I-193J-52D01*
G01Y125158D01*
X352099Y125123D01*
G03X351996Y124576I1399J-547D01*
G03X352099Y124029I1502J0D01*
G01X352113Y123994D01*
Y122966D01*
G03X352128Y122890I200J0D01*
G01X352148Y122842D01*
G02X352163Y122766I-185J-76D01*
G01Y117515D01*
G02X352123Y117395I-200J0D01*
G37*
G36*
G01X312735Y276294D02*
X387709D01*
G02X387851Y276235I0J-200D01*
G01X389135Y274951D01*
G02X389137Y274949I-140J-142D01*
G02X389194Y274809I-143J-140D01*
G01Y267385D01*
G02X389081Y267205I-200J0D01*
G01X388704Y267023D01*
X388591Y267036D01*
X388545Y267072D01*
G03X387611Y267398I-934J-1175D01*
G03Y264394I0J-1502D01*
G03X388545Y264720I0J1501D01*
G01X388591Y264756D01*
X388704Y264769D01*
X389081Y264587D01*
G02X389194Y264407I-87J-180D01*
G01Y257901D01*
X389140Y257809D01*
X389095Y257782D01*
X389093D01*
X388805Y257613D01*
G02X388731Y257588I-100J174D01*
G01X388690Y257583D01*
X388597Y257608D01*
X388575Y257620D01*
G03X387853Y257805I-723J-1319D01*
G01X387852D01*
G03Y254801I0J-1502D01*
G01X387853D01*
G03X388575Y254986I-1J1504D01*
G01X388597Y254998D01*
X388651Y255013D01*
G02X388731Y255018I52J-193D01*
G01X388770Y255013D01*
X389094Y254824D01*
G02X389097Y254822I-109J-167D01*
G02X389194Y254651I-103J-171D01*
G01Y207215D01*
G02X389192Y207189I-200J2D01*
G01X389187Y207148D01*
X389184Y207137D01*
G03X389136Y206760I1454J-377D01*
G01Y206691D01*
G03X389137Y206670I200J-1D01*
G01X389144Y206603D01*
G03X389149Y206560I1494J152D01*
G01X389158Y206495D01*
G03X389162Y206476I197J32D01*
G01Y206475D01*
X389178Y206407D01*
G03X389183Y206388I1455J373D01*
G01Y206384D01*
G03X389187Y206371I1437J435D01*
G01X389194Y206345D01*
Y202582D01*
G03X389253Y202440I200J0D01*
G01X389674Y202019D01*
G03X389816Y201960I142J141D01*
G01X392534D01*
G02X392567Y201957I-2J-200D01*
G02X392674Y201903I-32J-197D01*
G01X392930Y201647D01*
G02X392989Y201505I-141J-142D01*
G01Y193725D01*
G02X392927Y193580I-200J0D01*
G01X392914Y193568D01*
X392636Y193373D01*
G02X392534Y193338I-114J165D01*
G01X392491Y193335D01*
X392446Y193352D01*
X392420Y193361D01*
G03X391930Y193443I-490J-1420D01*
G01X391914D01*
G03X390428Y191941I16J-1502D01*
G03X391930Y190439I1502J0D01*
G01X391933D01*
G03X392420Y190521I-3J1502D01*
G01X392451Y190532D01*
X392539D01*
G02X392654Y190496I1J-200D01*
G01X392902Y190323D01*
G02X392925Y190304I-116J-163D01*
G01X392927Y190302D01*
G02X392989Y190157I-138J-145D01*
G01Y165176D01*
G02X392930Y165034I-200J0D01*
G01X389463Y161567D01*
X389435Y161538D01*
X389361Y161508D01*
X382347D01*
G02X382176Y161604I0J200D01*
G01X381999Y161896D01*
G02X381983Y161930I172J102D01*
G02X381994Y162094I188J70D01*
G01X381997Y162100D01*
X382014Y162135D01*
G03X382166Y162788I-1350J658D01*
G01Y162790D01*
Y162815D01*
G03X381763Y163817I-1502J-22D01*
G01X381762Y163818D01*
G02X381706Y163957I144J139D01*
G01Y164268D01*
X381733Y164338D01*
X381760Y164366D01*
G03Y166420I-1096J1027D01*
G01X381733Y166448D01*
X381706Y166518D01*
Y166868D01*
X381733Y166938D01*
X381760Y166966D01*
G03X382166Y167993I-1096J1027D01*
G03X381796Y168980I-1501J0D01*
G01X381772Y169008D01*
X381747Y169074D01*
Y169412D01*
X381772Y169478D01*
X381796Y169506D01*
G03X382166Y170493I-1131J987D01*
G03X379162I-1502J0D01*
G03X379532Y169506I1501J0D01*
G01X379556Y169478D01*
X379581Y169412D01*
Y169074D01*
X379556Y169008D01*
X379532Y168980D01*
G03X379162Y167993I1131J-987D01*
G03X379568Y166966I1502J0D01*
G01X379595Y166938D01*
X379622Y166868D01*
Y166518D01*
X379595Y166448D01*
X379568Y166420D01*
G03Y164366I1096J-1027D01*
G01X379595Y164338D01*
X379622Y164268D01*
Y163918D01*
X379595Y163849D01*
X379568Y163820D01*
G03X379162Y162821I1096J-1027D01*
G01Y162793D01*
G03X379314Y162134I1502J-1D01*
G01X379343Y162073D01*
G02X379345Y161930I-186J-74D01*
G02X379329Y161896I-188J68D01*
G01X379152Y161605D01*
X379125Y161559D01*
X379034Y161508D01*
X375410D01*
G02X375252Y161585I0J200D01*
G01X375029Y161870D01*
X375010Y161959D01*
X375021Y162005D01*
G03X375066Y162368I-1457J365D01*
G03X373564Y163870I-1502J0D01*
G03X372537Y163464I0J-1502D01*
G01X372509Y163437D01*
X372439Y163410D01*
X372089D01*
X372019Y163437D01*
X371991Y163464D01*
G03X370964Y163870I-1027J-1096D01*
G03X369462Y162368I0J-1502D01*
G03X369507Y162005I1502J2D01*
G01X369518Y161959D01*
X369499Y161870D01*
X369276Y161585D01*
G02X369118Y161508I-158J123D01*
G01X353970D01*
G02X353828Y161567I0J200D01*
G01X353172Y162223D01*
G02X353114Y162364I142J141D01*
G01Y240157D01*
G03X353055Y240298I-200J-1D01*
G01X350001Y243352D01*
G03X349861Y243410I-141J-142D01*
G01X342826D01*
G02X342668Y243488I0J200D01*
G01X342476Y243739D01*
G02X342436Y243886I159J122D01*
G01X342440Y243912D01*
X342443Y243924D01*
G03X342490Y244294I-1455J373D01*
G01Y244309D01*
G03X340988Y245799I-1502J-12D01*
G03X340621Y245753I2J-1502D01*
G01X340565Y245739D01*
X340458Y245773D01*
X340150Y246131D01*
X340132Y246242D01*
X340154Y246295D01*
G03X340270Y246874I-1387J579D01*
G03X338768Y248376I-1502J0D01*
G03X337739Y247968I0J-1502D01*
G01X337705Y247936D01*
X337619Y247909D01*
X337265Y247958D01*
G02X337257Y247959I21J199D01*
G02X337120Y248055I36J197D01*
G03X335826Y248794I-1294J-763D01*
G03Y245790I0J-1502D01*
G03X336855Y246198I0J1502D01*
G01X336889Y246230D01*
X336975Y246257D01*
X337329Y246208D01*
G02X337337Y246207I-21J-199D01*
G02X337474Y246111I-36J-197D01*
G03X338768Y245372I1294J763D01*
G03X339135Y245418I-2J1502D01*
G01X339191Y245432D01*
X339298Y245398D01*
X339606Y245040D01*
X339624Y244929D01*
X339602Y244876D01*
G03X339486Y244309I1387J-579D01*
G01Y244294D01*
G03X339533Y243924I1502J3D01*
G01X339536Y243912D01*
X339540Y243886D01*
G02X339500Y243739I-199J-25D01*
G01X339308Y243488D01*
G02X339150Y243410I-158J122D01*
G01X334129D01*
X334083Y243422D01*
X334064Y243431D01*
X334062Y243432D01*
G03X333820Y243523I-648J-1355D01*
G03X333160Y243559I-410J-1445D01*
G03X332756Y243430I250J-1481D01*
G01X332736Y243420D01*
X332692Y243410D01*
X327036D01*
G02X326868Y243501I0J200D01*
G01X326657Y243824D01*
X326653Y243875D01*
X326649Y243924D01*
X326661Y243952D01*
Y243953D01*
X326670Y243973D01*
G03X326794Y244571I-1378J598D01*
G01Y244590D01*
G03X323790I-1502J-19D01*
G01Y244570D01*
G03X323915Y243971I1502J1D01*
G01X323935Y243925D01*
X323931Y243875D01*
X323927Y243824D01*
X323716Y243501D01*
X323688Y243458D01*
X323600Y243410D01*
X313611D01*
X313537Y243440D01*
X313509Y243469D01*
X311900Y245078D01*
X311871Y245106D01*
X311841Y245180D01*
Y275400D01*
G02X311898Y275540I200J0D01*
G01X311899Y275541D01*
X312593Y276235D01*
G02X312595Y276237I142J-140D01*
G02X312735Y276294I140J-143D01*
G37*
G36*
G01X407601Y202336D02*
X411112D01*
G02X411253Y202278I0J-200D01*
G01X413291Y200240D01*
X413305Y200210D01*
G03X413329Y200163I1350J660D01*
G02X413331Y200161I-134J-136D01*
G03X413364Y200101I1332J694D01*
G01X413377Y200079D01*
X413397Y200008D01*
G02X413405Y199953I-192J-56D01*
G01Y197600D01*
X413372Y197493D01*
X413357Y197470D01*
G03Y195860I1268J-805D01*
G01X413372Y195837D01*
X413405Y195730D01*
Y193600D01*
X413372Y193493D01*
X413357Y193470D01*
G03Y191860I1268J-805D01*
G01X413372Y191837D01*
X413405Y191730D01*
Y187493D01*
X413395Y187450D01*
X413385Y187429D01*
G03X413238Y186835I1354J-650D01*
G01X413237Y186804D01*
Y186778D01*
G03X413385Y186129I1502J1D01*
G01X413393Y186110D01*
X413405Y186064D01*
Y181600D01*
X413372Y181493D01*
X413357Y181470D01*
G03Y179860I1268J-805D01*
G01X413372Y179837D01*
X413405Y179730D01*
Y177600D01*
X413372Y177493D01*
X413357Y177470D01*
G03Y175860I1268J-805D01*
G01X413372Y175837D01*
X413405Y175730D01*
Y173600D01*
X413372Y173493D01*
X413357Y173470D01*
G03Y171860I1268J-805D01*
G01X413372Y171837D01*
X413405Y171730D01*
Y169600D01*
X413372Y169493D01*
X413357Y169470D01*
G03Y167860I1268J-805D01*
G01X413372Y167837D01*
X413405Y167730D01*
Y117195D01*
G02X413375Y117089I-200J-1D01*
G01X413323Y117007D01*
G03X413293Y116901I170J-105D01*
G01Y111745D01*
G03X413323Y111640I200J0D01*
G01X413374Y111561D01*
G02X413397Y111509I-170J-106D01*
G01X413405Y111481D01*
Y109734D01*
G02X413346Y109592I-200J0D01*
G01X412403Y108649D01*
X412375Y108620D01*
X412301Y108590D01*
X375588D01*
G02X375423Y108676I-1J200D01*
G03X373942Y109452I-1482J-1027D01*
G03X372461Y108676I1J-1803D01*
G02X372296Y108590I-164J114D01*
G01X356016D01*
G02X355874Y108649I0J200D01*
G01X354814Y109709D01*
X354788Y109754D01*
X354781Y109781D01*
G03X353697Y110865I-1455J-371D01*
G01X353670Y110872D01*
X353625Y110898D01*
X353563Y110960D01*
X353534Y110988D01*
X353504Y111062D01*
Y114907D01*
X353591Y115016D01*
X353660Y115032D01*
G03Y117960I-334J1464D01*
G01X353591Y117976D01*
X353504Y118085D01*
Y122963D01*
X353604Y123076D01*
X353680Y123085D01*
G03Y126067I-182J1491D01*
G01X353604Y126076D01*
X353504Y126189D01*
Y159263D01*
G02X353563Y159405I200J0D01*
G01X354426Y160268D01*
G02X354568Y160327I142J-141D01*
G01X390085D01*
G03X390227Y160386I0J200D01*
G01X393932Y164091D01*
G03X393991Y164233I-141J142D01*
G01Y201567D01*
G02X394048Y201707I200J0D01*
G01X394049Y201708D01*
X394618Y202277D01*
G02X394760Y202336I142J-141D01*
G01X404459D01*
G02X404636Y202230I0J-200D01*
G01X404827Y201869D01*
X404821Y201758D01*
X404789Y201712D01*
G03X404527Y200864I1241J-848D01*
G03X406029Y199362I1502J0D01*
G01X406030D01*
G03X407532Y200864I0J1502D01*
G03X407531Y200925I-1502J6D01*
G01X407527Y200982D01*
G03X407270Y201710I-1498J-119D01*
G01X407240Y201755D01*
X407236Y201811D01*
G02X407259Y201919I200J14D01*
G01X407424Y202230D01*
G02X407601Y202336I177J-94D01*
G37*
G36*
G01X527242Y1216854D02*
X530601D01*
G02X530741Y1216797I0J-200D01*
G01X530742Y1216796D01*
X540854Y1206684D01*
G02X540896Y1206623I-141J-142D01*
G01X542281Y1203501D01*
G03X543094Y1202317I3589J1593D01*
G01X556660Y1188751D01*
G03X557679Y1188016I2777J2776D01*
G02X557789Y1187837I-90J-179D01*
G01Y1120028D01*
G02X557692Y1119857I-200J0D01*
G01X557352Y1119653D01*
X557248Y1119651D01*
X557201Y1119676D01*
G03X556493Y1119853I-707J-1325D01*
G01X556471D01*
G03X554991Y1118351I22J-1502D01*
G03X556493Y1116849I1502J0D01*
G03X557201Y1117026I1J1502D01*
G02X557398Y1117021I94J-176D01*
G01X557692Y1116845D01*
G02X557789Y1116674I-103J-171D01*
G01Y1076420D01*
G02X557760Y1076316I-200J0D01*
G03X556829Y1074592I16056J-9784D01*
G03X555159Y1068856I16989J-8057D01*
G01X555155Y1068822D01*
X555126Y1068763D01*
X542875Y1056512D01*
G03X542816Y1056370I141J-142D01*
G01Y1032273D01*
G02X542757Y1032131I-200J0D01*
G01X534830Y1024204D01*
X534800Y1024131D01*
Y1024114D01*
X533823Y1023137D01*
G03X533764Y1022995I141J-142D01*
G01Y998376D01*
G02X533705Y998234I-200J0D01*
G01X520609Y985138D01*
G02X520467Y985079I-142J141D01*
G01X513851D01*
X513736Y985187D01*
X513731Y985266D01*
G03X512232Y986674I-1499J-94D01*
G03X510732Y985240I0J-1502D01*
G01X510728Y985159D01*
X510613Y985049D01*
X508507D01*
X508392Y985159D01*
X508388Y985240D01*
G03X506888Y986673I-1500J-69D01*
G01X506883D01*
G03X505811Y986218I5J-1502D01*
G01X505810Y986217D01*
X505782Y986189D01*
X505674Y986141D01*
G02X505592Y986123I-83J182D01*
G01X505384D01*
G02X505303Y986140I0J200D01*
G01X505195Y986188D01*
X505166Y986217D01*
X505165Y986218D01*
G03X504088Y986673I-1077J-1047D01*
G01X504068D01*
X504050D01*
G03X502588Y985240I38J-1502D01*
G01X502584Y985159D01*
X502469Y985049D01*
X498732D01*
X498729Y985046D01*
X486580D01*
X486577Y985049D01*
X414375D01*
G02X414253Y985091I1J200D01*
G01X414241Y985100D01*
X414233Y985108D01*
G03X414173Y985148I-139J-144D01*
G01X414172D01*
X414135Y985164D01*
X376793D01*
X376719Y985194D01*
X376691Y985223D01*
X367843Y994071D01*
G02X367784Y994213I141J142D01*
G01Y999887D01*
G02X367818Y999999I200J0D01*
G01X392436Y1036838D01*
G03X392799Y1037517I-3265J2182D01*
G01X393235Y1038570D01*
G02X393253Y1038604I185J-76D01*
G01X394820Y1040981D01*
G03X395269Y1041910I-3248J2143D01*
G01X396373Y1045277D01*
X397555Y1048881D01*
X397556Y1048882D01*
X397742Y1049450D01*
G02X397748Y1049464I186J-72D01*
G01X398202Y1050560D01*
G03X398483Y1051693I-3628J1501D01*
G01X398485Y1051715D01*
X400893Y1059058D01*
G03X401063Y1059845I-3699J1211D01*
G01Y1059846D01*
X401064Y1059857D01*
G03X401072Y1059936I-3867J432D01*
G03X401086Y1060230I-3877J332D01*
G01X401259Y1076344D01*
Y1076347D01*
G03X401261Y1076392I-3886J195D01*
G01Y1076415D01*
G03X401262Y1076467I-3890J101D01*
G01Y1076471D01*
G03X401261Y1076604I-3892J37D01*
G01X401260Y1076607D01*
Y1076751D01*
G03X400830Y1078528I-3891J-1D01*
G01X392327Y1095066D01*
G03X392117Y1095426I-3462J-1778D01*
G01X392116Y1095427D01*
X392100Y1095452D01*
X392092Y1095478D01*
G02X392083Y1095537I191J59D01*
G01Y1096021D01*
G03X392024Y1096163I-200J0D01*
G01X368740Y1119447D01*
G02X368681Y1119589I141J142D01*
G01Y1145326D01*
X368779Y1145438D01*
X368855Y1145448D01*
G03X370159Y1146937I-198J1489D01*
G03X369411Y1148236I-1502J0D01*
G02X369311Y1148409I100J173D01*
G01Y1148615D01*
G02X369411Y1148788I200J0D01*
G03X370159Y1150087I-754J1299D01*
G03X369534Y1151307I-1503J0D01*
G01X369496Y1151333D01*
X369453Y1151414D01*
X369441Y1151674D01*
G02X369499Y1151824I200J9D01*
G01X390251Y1172576D01*
G03X390310Y1172718I-141J142D01*
G01Y1196725D01*
G02X390367Y1196865I200J0D01*
G01X390368Y1196866D01*
X406451Y1212949D01*
G02X406453Y1212951I142J-140D01*
G02X406593Y1213008I140J-143D01*
G01X460140D01*
G03X460282Y1213067I0J200D01*
G01X464010Y1216795D01*
G02X464012Y1216797I142J-140D01*
G02X464152Y1216854I140J-143D01*
G01X493882D01*
X493922Y1216835D01*
G03X494562Y1216692I640J1359D01*
G03X495202Y1216835I0J1502D01*
G01X495242Y1216854D01*
X497882D01*
X497922Y1216835D01*
G03X498562Y1216692I640J1359D01*
G03X499202Y1216835I0J1502D01*
G01X499242Y1216854D01*
X501882D01*
X501922Y1216835D01*
G03X502562Y1216692I640J1359D01*
G03X503202Y1216835I0J1502D01*
G01X503242Y1216854D01*
X505882D01*
X505922Y1216835D01*
G03X506562Y1216692I640J1359D01*
G03X507202Y1216835I0J1502D01*
G01X507242Y1216854D01*
X509882D01*
X509922Y1216835D01*
G03X510562Y1216692I640J1359D01*
G03X511202Y1216835I0J1502D01*
G01X511242Y1216854D01*
X513882D01*
X513922Y1216835D01*
G03X514562Y1216692I640J1359D01*
G03X515202Y1216835I0J1502D01*
G01X515242Y1216854D01*
X517882D01*
X517922Y1216835D01*
G03X518562Y1216692I640J1359D01*
G03X519202Y1216835I0J1502D01*
G01X519242Y1216854D01*
X521882D01*
X521922Y1216835D01*
G03X522562Y1216692I640J1359D01*
G03X523202Y1216835I0J1502D01*
G01X523242Y1216854D01*
X525882D01*
X525922Y1216835D01*
G03X526562Y1216692I640J1359D01*
G03X527202Y1216835I0J1502D01*
G01X527242Y1216854D01*
G37*
G36*
G01X396179Y1451497D02*
G02X396022Y1451732I39J196D01*
G01X396561Y1454444D01*
G03X396576Y1454521I-3846J789D01*
G01Y1454523D01*
X396632Y1454805D01*
G03X396636Y1454844I-196J40D01*
G01Y1455149D01*
Y1461000D01*
Y1461088D01*
X396189Y1481043D01*
X396220Y1481119D01*
X396250Y1481149D01*
G03X396200Y1483344I-1051J1074D01*
G01X396169Y1483371D01*
X396135Y1483446D01*
X396113Y1484402D01*
X396161Y1484493D01*
X396205Y1484521D01*
G03X396148Y1487071I-824J1257D01*
G01X396103Y1487097D01*
X396051Y1487186D01*
X395775Y1499491D01*
X395846Y1499595D01*
X395906Y1499618D01*
G03X396691Y1500305I-536J1404D01*
G02X397400Y1500291I351J-192D01*
G03X398747Y1499456I1347J669D01*
G03Y1502462I0J1503D01*
G03X397426Y1501676I0J-1503D01*
G02X396717Y1501690I-351J192D01*
G03X395897Y1502430I-1347J-668D01*
G01X395869Y1502440D01*
X395823Y1502475D01*
X395742Y1502584D01*
G02X395704Y1502698I162J117D01*
G01X395654Y1504924D01*
X395474Y1512942D01*
G02Y1512953I200J6D01*
G02X396127Y1513250I400J-12D01*
G03X397267Y1512844I1140J1397D01*
G03X399070Y1514647I0J1803D01*
G01Y1518047D01*
G03X397267Y1519850I-1803J0D01*
G01X397266D01*
G03X396038Y1519367I0J-1803D01*
G02X395367Y1519631I-272J293D01*
G02X395366Y1519646I199J21D01*
G01Y1525536D01*
Y1526317D01*
X395354Y1526344D01*
X395351Y1526354D01*
X395079Y1527011D01*
G03X395068Y1527038I-3642J-1468D01*
G01X391162Y1536471D01*
X391156Y1536532D01*
X391164Y1536563D01*
G03X391202Y1536900I-1464J336D01*
G03X390045Y1538362I-1502J0D01*
G01X390017Y1538368D01*
X389970Y1538395D01*
X383417Y1544948D01*
X383388Y1545004D01*
X383383Y1545035D01*
G03X382135Y1546283I-1483J-235D01*
G01X382104Y1546288D01*
X382048Y1546317D01*
X379668Y1548696D01*
G03X379619Y1548745I-2801J-2752D01*
G01X379618Y1548746D01*
X379116Y1549248D01*
X379090Y1549259D01*
X379084Y1549262D01*
G03X379080Y1549263I-50J-191D01*
G01X379079Y1549264D01*
X378425Y1549535D01*
X378424D01*
G03X378395Y1549548I-1620J-3575D01*
G01X370388Y1552864D01*
G02X370265Y1553049I77J185D01*
G01Y1631999D01*
G03X370206Y1632141I-200J0D01*
G01X369979Y1632368D01*
X369950Y1632396D01*
X369920Y1632470D01*
Y1644813D01*
G02X369977Y1644953I200J0D01*
G01X369978Y1644954D01*
X370215Y1645191D01*
G02X370217Y1645193I142J-140D01*
G02X370357Y1645250I140J-143D01*
G01X553437D01*
G02X553470Y1645247I-2J-200D01*
G02X553577Y1645193I-32J-197D01*
G01X554001Y1644769D01*
G02X554003Y1644767I-140J-142D01*
G02X554060Y1644627I-143J-140D01*
G01Y1618170D01*
G02X553937Y1617986I-200J1D01*
G01X553880Y1617962D01*
X553762Y1617985D01*
X538924Y1632824D01*
G03X538000Y1633206I-923J-924D01*
G01X465837D01*
G03X464913Y1632824I-1J-1306D01*
G01X456434Y1624344D01*
X456362Y1624314D01*
X456322D01*
G03X454427Y1622402I17J-1912D01*
G03X456339Y1620490I1912J0D01*
G03X458251Y1622385I0J1912D01*
G01Y1622425D01*
X458281Y1622497D01*
X464744Y1628959D01*
G02X464886Y1629018I142J-141D01*
G01X477948D01*
G02X478132Y1628895I-1J-200D01*
G01X478156Y1628838D01*
X478133Y1628720D01*
X473757Y1624344D01*
X473685Y1624314D01*
X473645D01*
G03X471750Y1622402I17J-1912D01*
G03X473662Y1620490I1912J0D01*
G03X475574Y1622385I0J1912D01*
G01Y1622425D01*
X475604Y1622497D01*
X480737Y1627629D01*
G02X480879Y1627688I142J-141D01*
G01X493941D01*
G02X494125Y1627565I-1J-200D01*
G01X494149Y1627508D01*
X494126Y1627390D01*
X491080Y1624344D01*
X491008Y1624314D01*
X490968D01*
G03X489073Y1622402I17J-1912D01*
G03X490985Y1620490I1912J0D01*
G03X492897Y1622385I0J1912D01*
G01Y1622425D01*
X492927Y1622497D01*
X496730Y1626299D01*
G02X496872Y1626358I142J-141D01*
G01X509933D01*
G02X510117Y1626235I-1J-200D01*
G01X510141Y1626178D01*
X510118Y1626060D01*
X508402Y1624344D01*
X508330Y1624314D01*
X508290D01*
G03X506395Y1622402I17J-1912D01*
G03X508307Y1620490I1912J0D01*
G03X510219Y1622385I0J1912D01*
G01Y1622425D01*
X510249Y1622497D01*
X512322Y1624569D01*
G02X512464Y1624628I142J-141D01*
G01X524111D01*
G02X524296Y1624505I0J-200D01*
G01X524320Y1624448D01*
X524296Y1624330D01*
X523999Y1624033D01*
G03X523324Y1622402I1631J-1630D01*
G03X525630Y1620096I2306J0D01*
G03X527261Y1620771I1J2306D01*
G01X528329Y1621839D01*
G02X528471Y1621898I142J-141D01*
G01X534346D01*
G02X534458Y1621849I-21J-200D01*
G01X544835Y1611472D01*
G02X544894Y1611331I-141J-142D01*
G01Y1607459D01*
G02X544770Y1607274I-200J0D01*
G01X544713Y1607251D01*
X544596Y1607274D01*
X537046Y1614824D01*
G03X536122Y1615206I-923J-924D01*
G01X536102D01*
G02X535902Y1615406I0J200D01*
G01Y1615462D01*
X535931Y1615510D01*
G03X536205Y1616496I-1639J986D01*
G01Y1616497D01*
X536203Y1616546D01*
G03X534292Y1618408I-1911J-50D01*
G03X532380Y1616496I0J-1912D01*
G03X532390Y1616296I1912J-5D01*
G01X532392Y1616276D01*
G03X532526Y1615760I1900J218D01*
G01X532546Y1615713D01*
X532537Y1615615D01*
X532324Y1615296D01*
G02X532157Y1615206I-167J110D01*
G01X529741D01*
G03X528817Y1614824I-1J-1306D01*
G01X527524Y1613531D01*
G02X527383Y1613472I-142J141D01*
G01X527071D01*
X526999Y1613502D01*
X526970Y1613530D01*
G03X525630Y1614078I-1340J-1364D01*
G03X523718Y1612166I0J-1912D01*
G03X524955Y1610377I1912J0D01*
G02X525080Y1610232I-71J-187D01*
G01X525140Y1609952D01*
G02X525145Y1609910I-195J-44D01*
G01Y1609908D01*
G02X525086Y1609766I-200J0D01*
G01X523999Y1608679D01*
G03X523324Y1607048I1631J-1630D01*
G03X525630Y1604742I2306J0D01*
G03X527261Y1605417I1J2306D01*
G01X528327Y1606483D01*
G02X528469Y1606542I142J-141D01*
G01X535409D01*
G02X535437Y1606540I0J-200D01*
G01X540535Y1601442D01*
G02X540594Y1601301I-141J-142D01*
G01Y1595937D01*
G02X540470Y1595752I-200J0D01*
G01X540413Y1595729D01*
X540296Y1595752D01*
X536624Y1599424D01*
G03X536195Y1599709I-923J-924D01*
G01X536155Y1599726D01*
X536097Y1599785D01*
X535966Y1600143D01*
X535971Y1600225D01*
X535991Y1600263D01*
G03X536204Y1601140I-1700J877D01*
G01Y1601142D01*
G03X532380I-1912J0D01*
G03X532390Y1600942I1912J-5D01*
G01X532392Y1600922D01*
G03X532543Y1600368I1900J220D01*
G01X532564Y1600321D01*
X532556Y1600221D01*
X532345Y1599897D01*
G02X532177Y1599806I-168J109D01*
G01X527319D01*
G03X526395Y1599424I-1J-1306D01*
G01X525725Y1598753D01*
X525653Y1598723D01*
X525613D01*
G03X523718Y1596811I17J-1912D01*
G03X523728Y1596611I1912J-5D01*
G03X525591Y1594899I1902J200D01*
G01X525631D01*
G03X526977Y1595454I-1J1912D01*
G01X527006Y1595483D01*
X527112Y1595528D01*
G02X527190Y1595544I78J-184D01*
G01X530684D01*
G03X531580Y1595915I0J1267D01*
G01X531680Y1596016D01*
X531712Y1596048D01*
G02X531919Y1596095I141J-142D01*
G01X532258Y1595976D01*
G02X532388Y1595825I-66J-189D01*
G01X532394Y1595795D01*
X532395Y1595789D01*
G03X532411Y1595684I1897J235D01*
G01Y1595683D01*
G03X532449Y1595513I1883J332D01*
G01X532462Y1595467D01*
X532444Y1595376D01*
X532223Y1595085D01*
G02X532064Y1595006I-159J121D01*
G01X527637D01*
G03X526713Y1594624I-1J-1306D01*
G01X525725Y1593635D01*
X525653Y1593605D01*
X525613D01*
G03X523718Y1591693I17J-1912D01*
G03X525630Y1589781I1912J0D01*
G03X527542Y1591676I0J1912D01*
G01Y1591716D01*
X527572Y1591788D01*
X527914Y1592129D01*
G02X528056Y1592188I142J-141D01*
G01X534742D01*
G02X534877Y1592135I-1J-200D01*
G01X537835Y1589176D01*
G02X537894Y1589035I-141J-142D01*
G01Y1584517D01*
G02X537770Y1584332I-200J0D01*
G01X537713Y1584309D01*
X537596Y1584332D01*
X536234Y1585693D01*
X536204Y1585765D01*
Y1585805D01*
G03X534292Y1587700I-1912J-17D01*
G03X532380Y1585788I0J-1912D01*
G03X534275Y1583876I1912J0D01*
G01X534315D01*
X534387Y1583846D01*
X535935Y1582297D01*
G02X535994Y1582156I-141J-142D01*
G01Y1582155D01*
G02X535794Y1581955I-200J0D01*
G01X535753D01*
X535680Y1581986D01*
X535651Y1582015D01*
G03X534292Y1582582I-1359J-1345D01*
G03Y1578758I0J-1912D01*
G01X534326D01*
X534367Y1578759D01*
X534442Y1578729D01*
X534614Y1578557D01*
X535935Y1577235D01*
G02X535994Y1577094I-141J-142D01*
G01Y1572157D01*
G02X535880Y1571976I-200J0D01*
G01X535710Y1571895D01*
X535708D01*
X535657Y1571870D01*
X535537Y1571885D01*
X535493Y1571923D01*
X535487Y1571927D01*
X535481Y1571932D01*
X535444Y1571960D01*
G03X534292Y1572346I-1152J-1526D01*
G01X534260D01*
G03Y1568522I32J-1912D01*
G01X534292D01*
G03X535444Y1568908I0J1912D01*
G01X535484Y1568938D01*
G03X535486Y1568940I-139J141D01*
G01X535500Y1568951D01*
G02X535708Y1568973I122J-158D01*
G01X535709D01*
X535880Y1568892D01*
G02X535994Y1568711I-86J-181D01*
G01Y1567038D01*
G02X535880Y1566857I-200J0D01*
G01X535710Y1566776D01*
X535708D01*
X535657Y1566751D01*
X535537Y1566766D01*
X535493Y1566804D01*
X535487Y1566808D01*
X535481Y1566813D01*
X535444Y1566841D01*
G03X534292Y1567227I-1152J-1526D01*
G01X534260D01*
G03Y1563403I32J-1912D01*
G01X534292D01*
G03X535444Y1563789I0J1912D01*
G01X535484Y1563819D01*
G03X535486Y1563821I-139J141D01*
G01X535500Y1563832D01*
G02X535708Y1563854I122J-158D01*
G01X535709D01*
X535880Y1563773D01*
G02X535994Y1563592I-86J-181D01*
G01Y1546599D01*
G03X536126Y1546026I1306J-1D01*
G01X536136Y1546005D01*
X536146Y1545962D01*
Y1545254D01*
G03X536537Y1544338I1268J0D01*
G01X536541Y1544335D01*
X550852Y1530024D01*
G03X551008Y1529892I893J898D01*
G03X551072Y1529849I738J1029D01*
G03X551274Y1529746I674J1072D01*
G01X551312Y1529730D01*
X552943Y1528099D01*
G03X553085Y1528040I142J141D01*
G01X563085D01*
G02X563118Y1528037I-2J-200D01*
G02X563225Y1527983I-32J-197D01*
G01X563301Y1527907D01*
X563952Y1527255D01*
G03X564848Y1526884I896J896D01*
G01X566433D01*
G02X566486Y1526877I1J-200D01*
G01X566561Y1526856D01*
X566582Y1526844D01*
G03X567322Y1526649I740J1308D01*
G01X567324D01*
G03X567524Y1526662I3J1502D01*
G03X568801Y1527877I-200J1489D01*
G01X568814Y1527949D01*
X568924Y1528040D01*
X571191D01*
G02X571219Y1528038I0J-200D01*
G01X571681Y1527576D01*
G03X572605Y1527194I923J924D01*
G01X576323D01*
G03X577247Y1527576I1J1306D01*
G01X577652Y1527981D01*
G02X577794Y1528040I142J-141D01*
G01X578136D01*
X578210D01*
X578320Y1527950D01*
X578334Y1527878D01*
G03X579809Y1526661I1475J285D01*
G03X581182Y1527550I0J1505D01*
G02X581328Y1527665I182J-82D01*
G01X581651Y1527726D01*
G02X581829Y1527671I37J-197D01*
G01X586681Y1522819D01*
G02X586683Y1522817I-140J-142D01*
G02X586740Y1522677I-143J-140D01*
G01Y1519019D01*
G02X586695Y1518892I-200J-1D01*
G03X586356Y1517942I1162J-950D01*
G03X586691Y1516996I1503J0D01*
G01X586697Y1516989D01*
X586706Y1516975D01*
G02X586740Y1516864I-166J-112D01*
G01Y1507076D01*
G02X586723Y1506995I-200J0D01*
G01X586674Y1506884D01*
X586643Y1506856D01*
G03Y1504592I1046J-1132D01*
G01X586674Y1504564D01*
X586723Y1504453D01*
G02X586740Y1504372I-183J-81D01*
G01Y1483184D01*
G02X586732Y1483128I-200J0D01*
G01X566205Y1412537D01*
G02X566013Y1412393I-192J56D01*
G01X565980D01*
G03X564578Y1411002I0J-1402D01*
G01Y1410990D01*
G03X564646Y1410560I1402J1D01*
G01X564658Y1410524D01*
G02X564630Y1410346I-190J-61D01*
G01X564442Y1410082D01*
G02X564279Y1409998I-163J116D01*
G01X561802D01*
G03X561026Y1409782I0J-1502D01*
G02X560874Y1409759I-104J171D01*
G03X560562Y1409797I-312J-1264D01*
G03Y1407193I0J-1302D01*
G03X560874Y1407231I0J1302D01*
G02X561026Y1407208I48J-194D01*
G03X561802Y1406992I776J1286D01*
G01X564059D01*
G02X564443Y1406480I0J-400D01*
G01X562045Y1398230D01*
G02X561853Y1398086I-192J56D01*
G01X561802D01*
G03X561026Y1397870I0J-1502D01*
G02X560874Y1397847I-104J171D01*
G03X560562Y1397885I-312J-1264D01*
G03X559260Y1396583I0J-1302D01*
G03X559821Y1395512I1303J0D01*
G01X559856Y1395488D01*
X559899Y1395420D01*
X559957Y1395051D01*
X559937Y1394973D01*
X559911Y1394940D01*
G03X559799Y1394769I1114J-852D01*
G01X559785Y1394744D01*
X553082Y1388041D01*
G03X553042Y1387981I143J-139D01*
G01X553028Y1387949D01*
X552990Y1387908D01*
X552977Y1387898D01*
G03X552438Y1386791I863J-1105D01*
G01Y1386771D01*
G03X552506Y1386362I1402J23D01*
G01X552518Y1386326D01*
G02X552490Y1386148I-190J-61D01*
G01X552302Y1385884D01*
G02X552139Y1385800I-163J116D01*
G01X549662D01*
G03X548859Y1385567I1J-1503D01*
G02X548694Y1385545I-107J169D01*
G03X548322Y1385599I-371J-1248D01*
G03Y1382995I0J-1302D01*
G03X548694Y1383049I1J1302D01*
G02X548859Y1383027I58J-191D01*
G03X549662Y1382794I804J1270D01*
G01X552139D01*
G02X552302Y1382710I0J-200D01*
G01X552483Y1382455D01*
G02X552493Y1382440I-161J-118D01*
G01X552495Y1382437D01*
G02X552522Y1382297I-170J-105D01*
G01X552516Y1382263D01*
X552511Y1382248D01*
G03X552438Y1381810I1329J-447D01*
G01Y1381790D01*
G03X552951Y1380717I1402J11D01*
G02X553024Y1380562I-127J-155D01*
G01Y1376120D01*
G02X552951Y1375965I-200J0D01*
G03X552438Y1374879I889J-1084D01*
G01Y1374868D01*
G03X552506Y1374450I1402J14D01*
G01X552518Y1374414D01*
G02X552490Y1374236I-190J-61D01*
G01X552302Y1373972D01*
G02X552139Y1373888I-163J116D01*
G01X549662D01*
G03X548859Y1373655I1J-1503D01*
G02X548694Y1373633I-107J169D01*
G03X548322Y1373687I-371J-1248D01*
G03Y1371083I0J-1302D01*
G03X548694Y1371137I1J1302D01*
G02X548859Y1371115I58J-191D01*
G03X549662Y1370882I804J1270D01*
G01X552139D01*
G02X552302Y1370798I0J-200D01*
G01X552483Y1370543D01*
G02X552493Y1370528I-161J-118D01*
G01X552495Y1370525D01*
G02X552522Y1370385I-170J-105D01*
G01X552516Y1370351D01*
X552511Y1370336D01*
G03X552438Y1369898I1329J-447D01*
G01Y1369878D01*
G03X552951Y1368805I1402J11D01*
G02X553024Y1368650I-127J-155D01*
G01Y1363834D01*
G02X552951Y1363679I-200J0D01*
G03X552438Y1362595I889J-1084D01*
G03X552516Y1362134I1401J0D01*
G02X552490Y1361952I-189J-66D01*
G01X552301Y1361686D01*
G02X552138Y1361602I-163J116D01*
G01X549662D01*
G03X548859Y1361369I1J-1503D01*
G02X548694Y1361347I-107J169D01*
G03X548322Y1361401I-371J-1248D01*
G03Y1358797I0J-1302D01*
G03X548694Y1358851I1J1302D01*
G02X548859Y1358829I58J-191D01*
G03X549662Y1358596I804J1270D01*
G01X552116D01*
G02X552154Y1358592I-2J-200D01*
G01X552181Y1358587D01*
G02X552247Y1358562I-37J-197D01*
G01X552283Y1358540D01*
X552479Y1358262D01*
G02X552498Y1358230I-162J-118D01*
G02X552516Y1358145I-182J-83D01*
G01Y1358097D01*
X552506Y1358036D01*
X552502Y1358023D01*
G03X552438Y1357605I1337J-419D01*
G01Y1357603D01*
G03X552951Y1356519I1402J0D01*
G02X553024Y1356364I-127J-155D01*
G01Y1351922D01*
G02X552951Y1351767I-200J0D01*
G03X552438Y1350683I889J-1084D01*
G03X552516Y1350222I1401J0D01*
G02X552490Y1350040I-189J-66D01*
G01X552301Y1349774D01*
G02X552138Y1349690I-163J116D01*
G01X549662D01*
G03X548859Y1349457I1J-1503D01*
G02X548694Y1349435I-107J169D01*
G03X548322Y1349489I-371J-1248D01*
G03Y1346885I0J-1302D01*
G03X548694Y1346939I1J1302D01*
G02X548859Y1346917I58J-191D01*
G03X549662Y1346684I804J1270D01*
G01X552168D01*
G02X552308Y1346627I0J-200D01*
G01X552309Y1346626D01*
X552325Y1346610D01*
G02X552350Y1346580I-140J-142D01*
G01X552547Y1346288D01*
X552562Y1346210D01*
X552554Y1346170D01*
X552549Y1346145D01*
X552542Y1346128D01*
G03X552438Y1345599I1298J-530D01*
G01Y1345596D01*
G03X552638Y1344875I1403J1D01*
G01X552651Y1344852D01*
X552669Y1344791D01*
G02X552660Y1344655I-192J-56D01*
G01X523462Y1278177D01*
G03X523422Y1278083I3560J-1571D01*
G03X523333Y1277843I3602J-1472D01*
G03X523217Y1277412I3694J-1225D01*
G01X522605Y1274498D01*
G03X522522Y1273699I3808J-799D01*
G01Y1270488D01*
G02X522521Y1270465I-200J-3D01*
G02X522503Y1270404I-199J25D01*
G01X522487Y1270369D01*
X518903Y1266785D01*
X518875Y1266756D01*
X518801Y1266726D01*
X460260D01*
G02X460060Y1266926I0J200D01*
G01Y1279998D01*
G03X460001Y1280140I-200J0D01*
G01X456403Y1283738D01*
G03X456261Y1283797I-142J-141D01*
G01X412400D01*
G02X412324Y1283812I0J200D01*
G01X412222Y1283854D01*
X412195Y1283878D01*
G03X410153I-1021J-1101D01*
G01X410126Y1283854D01*
X410024Y1283812D01*
G02X409948Y1283797I-76J185D01*
G01X392620D01*
X392546Y1283827D01*
X392518Y1283856D01*
X377845Y1298529D01*
X377816Y1298557D01*
X377786Y1298631D01*
Y1327748D01*
G02X377843Y1327888I200J0D01*
G01X377844Y1327889D01*
X395501Y1345546D01*
G03X395560Y1345688I-141J142D01*
G01Y1347706D01*
G02X395562Y1347738I200J4D01*
G01X395570Y1347785D01*
X395574Y1347800D01*
X395576Y1347808D01*
X395577Y1347813D01*
G03X395633Y1348174I-1245J378D01*
G01Y1348187D01*
G03X395570Y1348587I-1301J0D01*
G01X395560Y1348618D01*
Y1359618D01*
G02X395562Y1359650I200J4D01*
G01X395570Y1359697D01*
X395574Y1359712D01*
X395576Y1359720D01*
X395577Y1359725D01*
G03X395633Y1360086I-1245J378D01*
G01Y1360099D01*
G03X395570Y1360499I-1301J0D01*
G01X395560Y1360530D01*
Y1370682D01*
G02X395760Y1370882I200J0D01*
G01X397391D01*
G03Y1373888I0J1503D01*
G01X395760D01*
G02X395560Y1374088I0J200D01*
G01Y1376579D01*
G02X395630Y1376731I200J0D01*
G03Y1379019I-972J1144D01*
G02X395560Y1379171I130J152D01*
G01Y1382594D01*
G02X395760Y1382794I200J0D01*
G01X397391D01*
G03Y1385800I0J1503D01*
G01X395760D01*
G02X395560Y1386000I0J200D01*
G01Y1388032D01*
G02X395620Y1388175I200J0D01*
G01X395732Y1388285D01*
X395799Y1388314D01*
X395837Y1388316D01*
G03X397272Y1389817I-68J1501D01*
G03X395836Y1391318I-1502J0D01*
G01X395798Y1391320D01*
X395731Y1391349D01*
X395619Y1391460D01*
G02X395560Y1391602I141J142D01*
G01Y1394115D01*
G02X395612Y1394250I200J0D01*
G01X395643Y1394284D01*
X395685Y1394301D01*
G03X395684Y1397079I-573J1389D01*
G01X395628Y1397102D01*
X395560Y1397203D01*
Y1402207D01*
Y1402219D01*
X396219Y1412455D01*
X396434Y1415793D01*
G03X396442Y1416041I-3884J249D01*
G01Y1416043D01*
G03X396441Y1416103I-3891J-35D01*
G01Y1416120D01*
X396440Y1416141D01*
X396288Y1422106D01*
G02X396392Y1422286I200J5D01*
G01X396412Y1422297D01*
X396422Y1422301D01*
G03X397296Y1423600I-528J1299D01*
G03X396346Y1424928I-1403J0D01*
G01X396286Y1424948D01*
X396213Y1425049D01*
X395620Y1448316D01*
G02X395677Y1448460I200J4D01*
G01X395705Y1448489D01*
X395778Y1448520D01*
X395837D01*
G03X395886Y1448519I55J1502D01*
G01X395888D01*
G03X397391Y1450022I0J1503D01*
G03X396179Y1451497I-1504J0D01*
G37*
G36*
G01X492382Y54588D02*
X520615D01*
X520833Y54370D01*
Y52809D01*
X520615Y52591D01*
X492382D01*
G03X486445Y46654I0J-5937D01*
G01Y7874D01*
G02X480571Y2000I-5874J0D01*
G01X385689D01*
G02X379815Y7874I0J5874D01*
G01Y46160D01*
X381812D01*
Y7874D01*
G03X385687Y3998I3876J0D01*
G01X480571D01*
G03X484448Y7874I0J3877D01*
G01Y46654D01*
G02X492382Y54588I7934J0D01*
G37*
G36*
G01X413045Y204918D02*
X411524Y203397D01*
X411496Y203368D01*
X411422Y203338D01*
X390555D01*
G02X390413Y203397I0J200D01*
G01X390255Y203555D01*
G02X390197Y203696I142J141D01*
G01Y204858D01*
G02X390257Y205001I200J0D01*
G01X390491Y205230D01*
X390565Y205259D01*
X390605Y205258D01*
X390639D01*
G03Y208262I0J1502D01*
G01X390605D01*
X390565Y208261D01*
X390491Y208290D01*
X390257Y208519D01*
G02X390197Y208661I140J143D01*
G01Y255107D01*
G02X390314Y255289I200J0D01*
G01X390699Y255464D01*
X390816Y255446D01*
X390860Y255407D01*
G03X391852Y255033I992J1129D01*
G01X391853D01*
G03Y258037I0J1502D01*
G01X391852D01*
G03X390860Y257663I0J-1503D01*
G01X390816Y257624D01*
X390699Y257606D01*
X390314Y257781D01*
G02X390197Y257963I83J182D01*
G01Y275732D01*
G02X390397Y275932I200J0D01*
G01X412292D01*
G02X412434Y275873I0J-200D01*
G01X413045Y275262D01*
G02X413104Y275120I-141J-142D01*
G01Y205060D01*
G02X413045Y204918I-200J0D01*
G37*
G36*
G01X485272Y242408D02*
X499513D01*
G02X499561Y242376I-86J-180D01*
G01X499929Y242008D01*
X499930D01*
X500392Y241545D01*
X500943Y240994D01*
X502034Y239903D01*
G02X502093Y239762I-141J-142D01*
G01Y153172D01*
G02X502090Y153138I-200J1D01*
G01X502080Y153083D01*
X502047Y153024D01*
X502021Y153001D01*
G03X501793Y147651I2439J-2784D01*
G01X501794Y147650D01*
X501796Y147648D01*
G03X501922Y147521I2690J2543D01*
G03X502026Y147426I2548J2685D01*
G02X502093Y147277I-133J-149D01*
G01Y122986D01*
G03X502108Y122910I200J0D01*
G01X502143Y122827D01*
Y117487D01*
G02X502106Y117370I-200J-1D01*
G03X501825Y116496I1221J-875D01*
G03X502106Y115622I1502J1D01*
G02X502143Y115505I-163J-116D01*
G01Y110681D01*
G03X502156Y110611I200J1D01*
G02X502168Y110527I-188J-70D01*
G01X502160Y110411D01*
G02X502121Y110305I-200J13D01*
G03X501825Y109410I1205J-895D01*
G03X503327Y107908I1502J0D01*
G03X504259Y108232I0J1502D01*
G01X504319Y108280D01*
X504470Y108271D01*
X505073Y107668D01*
G03X505215Y107609I142J141D01*
G01X505792D01*
X505809Y107606D01*
G03X505889Y107595I204J1184D01*
G01X505890D01*
G03X506014Y107588I130J1195D01*
G01X521940D01*
G02X522140Y107388I0J-200D01*
G01Y104248D01*
G03X522156Y104009I1803J1D01*
G01Y104008D01*
G03X522163Y103967I1780J283D01*
G01Y103966D01*
G03X522172Y103915I1779J288D01*
G01X522183Y103856D01*
X522139Y103749D01*
X522059Y103693D01*
G02X521957Y103656I-117J162D01*
G01X521902Y103653D01*
X521852Y103678D01*
X521851Y103679D01*
G03X521165Y103845I-686J-1335D01*
G03X519663Y102343I0J-1502D01*
G03X520110Y101274I1502J0D01*
G03X521189Y100821I1075J1049D01*
G01X521209D01*
G03X522685Y102241I-24J1502D01*
G01Y102242D01*
X522688Y102291D01*
X522712Y102332D01*
G02X522779Y102401I173J-101D01*
G01X523056Y102574D01*
G02X523145Y102604I107J-169D01*
G01X523196Y102608D01*
G03X523934Y102446I747J1641D01*
G01X523943D01*
G03X525746Y104249I0J1803D01*
G01Y107389D01*
G02X525945Y107588I199J-1D01*
G01X562188D01*
G02X562328Y107531I0J-200D01*
G01X562329Y107530D01*
X563743Y106116D01*
G02X563802Y105974I-141J-142D01*
G01Y98707D01*
G02X563737Y98559I-200J0D01*
G01X563487Y98331D01*
X563407Y98304D01*
X563365Y98308D01*
G03X563224Y98315I-145J-1495D01*
G03X561722Y96813I0J-1502D01*
G03X561790Y96366I1503J0D01*
G01X561805Y96318D01*
X561787Y96221D01*
X561517Y95884D01*
X561427Y95844D01*
X561377Y95848D01*
G03X561258Y95853I-122J-1497D01*
G03X562760Y94351I0J-1502D01*
G03X562692Y94798I-1503J0D01*
G01X562677Y94846D01*
X562695Y94943D01*
X562965Y95280D01*
X563055Y95320D01*
X563105Y95316D01*
G03X563224Y95311I122J1497D01*
G03X563365Y95318I-4J1502D01*
G01X563407Y95322D01*
X563487Y95295D01*
X563737Y95067D01*
G02X563802Y94919I-135J-148D01*
G01Y94811D01*
X563791Y94779D01*
G03X563705Y94279I1416J-501D01*
G03X563791Y93779I1502J1D01*
G01X563802Y93747D01*
Y87556D01*
X563736Y87457D01*
X563679Y87433D01*
G03Y84659I576J-1387D01*
G01X563736Y84635D01*
X563802Y84536D01*
Y62339D01*
G02X563744Y62198I-200J0D01*
G01X563520Y61971D01*
X563449Y61940D01*
X563409D01*
G03X562330Y61457I25J-1502D01*
G01X562300Y61425D01*
X562221Y61392D01*
X561833Y61402D01*
X561756Y61439D01*
X561728Y61473D01*
G03X560573Y62015I-1155J-960D01*
G03Y59011I0J-1502D01*
G03X561676Y59494I0J1501D01*
G01X561706Y59526D01*
X561785Y59559D01*
X562173Y59549D01*
X562250Y59512D01*
X562278Y59478D01*
G03X563409Y58936I1155J960D01*
G01X563449D01*
X563520Y58905D01*
X563744Y58678D01*
G02X563802Y58537I-142J-141D01*
G01Y54020D01*
X563772Y53946D01*
X563743Y53918D01*
X562541Y52716D01*
G02X562399Y52657I-142J141D01*
G01X543829D01*
X543755Y52687D01*
X543727Y52716D01*
X538586Y57857D01*
G03X538489Y57911I-142J-141D01*
G01X538451Y57920D01*
X538390Y57962D01*
X538193Y58253D01*
G02X538174Y58440I166J111D01*
G03X538796Y61610I-7780J3173D01*
G01Y61614D01*
G03X536295Y67595I-8402J0D01*
G03X530374Y70036I-5921J-5961D01*
G03X521972Y61634I0J-8402D01*
G03X522591Y58468I8402J-1D01*
G01X522592Y58467D01*
X522599Y58449D01*
X522602Y58432D01*
G02X522573Y58279I-195J-42D01*
G01X522387Y58004D01*
G02X522221Y57916I-166J112D01*
G01X515077D01*
G02X514898Y58025I-1J200D01*
G01X514751Y58315D01*
G02X514730Y58423I178J91D01*
G01X514735Y58478D01*
X514768Y58524D01*
X514769Y58525D01*
G03X515482Y60708I-2989J2184D01*
G01Y60731D01*
G03X515038Y62466I-3702J-23D01*
G01Y62467D01*
G02Y62655I176J94D01*
G01X515203Y62963D01*
X515287Y63018D01*
X515338Y63022D01*
G03X517638Y69569I-318J3789D01*
G01X517636Y69571D01*
X517634Y69573D01*
G03X511652Y65029I-2634J-2742D01*
G01X511658Y65019D01*
X511666Y64999D01*
G02X511680Y64912I-186J-75D01*
G01X511677Y64863D01*
X511476Y64528D01*
X511448Y64482D01*
X511358Y64430D01*
X504460D01*
G03X500759Y60729I0J-3701D01*
G01Y60727D01*
G03X501466Y58553I3701J2D01*
G01X501467Y58552D01*
X501469Y58550D01*
G02X501484Y58345I-164J-115D01*
G01X501323Y58027D01*
G02X501303Y57994I-180J87D01*
G02X501240Y57941I-158J123D01*
G01X501238Y57940D01*
G02X501143Y57916I-95J176D01*
G01X464407D01*
X464333Y57946D01*
X464305Y57975D01*
X462720Y59560D01*
G02X462661Y59702I141J142D01*
G01Y95698D01*
G03X462632Y95802I-200J0D01*
G01X462631Y95803D01*
X462617Y95827D01*
X462610Y95852D01*
G02X462602Y95907I192J56D01*
G01Y108935D01*
X462663Y109033D01*
X462716Y109058D01*
G03X463260Y109500I-649J1354D01*
G01X463269Y109511D01*
X463292Y109534D01*
G02X463404Y109590I141J-142D01*
G01X463674Y109630D01*
G02X463824Y109592I30J-198D01*
G01X463825Y109591D01*
G03X464738Y109282I913J1194D01*
G01X464769D01*
G03X466025Y110009I-31J1502D01*
G01X466036Y110028D01*
X466053Y110046D01*
G02X466095Y110079I144J-140D01*
G01X466175Y110126D01*
G02X466207Y110141I101J-173D01*
G02X466255Y110152I68J-188D01*
G02X466276Y110153I20J-199D01*
G01X466538D01*
G02X466711Y110053I0J-200D01*
G03X466946Y109746I1301J752D01*
G01X466959Y109732D01*
X466960Y109731D01*
G03X468032Y109282I1071J1053D01*
G01X468068D01*
G03X469534Y110784I-36J1502D01*
G03X469081Y111859I-1502J0D01*
G03X468012Y112306I-1069J-1055D01*
G03X466711Y111555I0J-1502D01*
G02X466538Y111455I-173J100D01*
G01X466200D01*
G02X466028Y111553I0J200D01*
G03X465789Y111857I-1290J-769D01*
G02X465787Y111859I140J142D01*
G03X464718Y112306I-1069J-1055D01*
G03X463526Y111718I0J-1502D01*
G01X463518Y111707D01*
X463495Y111684D01*
G02X463384Y111628I-141J142D01*
G01X463107Y111587D01*
G02X463029Y111591I-29J198D01*
G01X462992Y111600D01*
X462960Y111623D01*
G03X462931Y111644I-895J-1206D01*
G01X462913Y111657D01*
X462865Y111708D01*
G02X462837Y111747I147J135D01*
G01X462804Y111809D01*
G02X462779Y111905I175J97D01*
G01Y111923D01*
G02X462804Y112019I200J-1D01*
G01X462833Y112072D01*
X462867Y112109D01*
X462889Y112123D01*
G03X463591Y113358I-800J1272D01*
G01Y113388D01*
Y113394D01*
G03X463135Y114473I-1502J1D01*
G02X463132Y114475I107J164D01*
G03X462716Y114770I-1065J-1060D01*
G01X462663Y114795D01*
X462602Y114892D01*
Y115031D01*
G02X462661Y115173I200J0D01*
G01X462717Y115229D01*
X462747Y115244D01*
G03X463591Y116594I-658J1350D01*
G03X463139Y117668I-1502J0D01*
G02X463137Y117670I140J142D01*
G03X462992Y117799I-1069J-1055D01*
G02X462915Y117957I123J158D01*
G01Y118236D01*
G02X462994Y118396I200J1D01*
G03X463591Y119598I-905J1199D01*
G01Y119609D01*
G03X463134Y120674I-1502J-14D01*
G02X463131Y120676I107J164D01*
G03X462716Y120970I-1064J-1061D01*
G01X462663Y120995D01*
X462602Y121092D01*
Y122604D01*
G02X462649Y122733I200J0D01*
G01X462673Y122761D01*
X462734Y122795D01*
X462769Y122801D01*
G03X464025Y124283I-246J1482D01*
G03X463575Y125355I-1502J0D01*
G02X463572Y125358I140J143D01*
G03X462767Y125782I-1070J-1055D01*
G01X462766D01*
G02X462602Y125979I36J197D01*
G01Y131939D01*
G02X462723Y132123I200J0D01*
G01X463117Y132292D01*
X463236Y132269D01*
X463279Y132227D01*
G03X464332Y131796I1053J1071D01*
G03X464532Y131809I3J1502D01*
G03X465771Y132867I-200J1489D01*
G01X465782Y132903D01*
X465828Y132962D01*
X466085Y133115D01*
X466118Y133121D01*
G03X466479Y133077I361J1459D01*
G03X467981Y134579I0J1502D01*
G03X467528Y135654I-1502J0D01*
G03X466459Y136101I-1069J-1055D01*
G03X465031Y135067I0J-1503D01*
G01Y135066D01*
X465019Y135031D01*
X464998Y135004D01*
G02X464943Y134956I-157J124D01*
G01X464686Y134802D01*
X464616Y134789D01*
X464580Y134796D01*
G03X464313Y134820I-267J-1478D01*
G01X464312D01*
G03X463277Y134407I0J-1503D01*
G01X463256Y134387D01*
X463204Y134361D01*
X463175Y134355D01*
G02X463059Y134368I-37J197D01*
G01X462723Y134513D01*
X462667Y134537D01*
X462602Y134636D01*
Y241469D01*
G02X462661Y241611I200J0D01*
G01X463399Y242349D01*
G02X463401Y242351I142J-140D01*
G02X463541Y242408I140J-143D01*
G01X481512D01*
G02X481649Y242354I0J-200D01*
G01X481650Y242353D01*
X481858Y242153D01*
X481890Y242083D01*
X481891Y242043D01*
G03X482337Y241029I1501J55D01*
G03X483412Y240576I1075J1049D01*
G03X484914Y242059I0J1502D01*
G01X484915Y242099D01*
X484946Y242172D01*
X485133Y242352D01*
G02X485136Y242355I143J-140D01*
G02X485272Y242408I136J-147D01*
G37*
G36*
G01X481727Y276294D02*
X537710D01*
G02X537852Y276235I0J-200D01*
G01X539136Y274951D01*
G02X539138Y274949I-140J-142D01*
G02X539195Y274809I-143J-140D01*
G01Y267385D01*
G02X539082Y267205I-200J0D01*
G01X538705Y267023D01*
X538592Y267036D01*
X538546Y267072D01*
G03X537612Y267398I-934J-1175D01*
G03Y264394I0J-1502D01*
G03X538546Y264720I0J1501D01*
G01X538592Y264756D01*
X538705Y264769D01*
X539082Y264587D01*
G02X539195Y264407I-87J-180D01*
G01Y257901D01*
X539141Y257809D01*
X539096Y257782D01*
X539094D01*
X538806Y257613D01*
G02X538732Y257588I-100J174D01*
G01X538691Y257583D01*
X538598Y257608D01*
X538576Y257620D01*
G03X537854Y257805I-723J-1319D01*
G01X537853D01*
G03Y254801I0J-1502D01*
G01X537854D01*
G03X538576Y254986I-1J1504D01*
G01X538598Y254998D01*
X538652Y255013D01*
G02X538732Y255018I52J-193D01*
G01X538771Y255013D01*
X539095Y254824D01*
G02X539098Y254822I-109J-167D01*
G02X539195Y254651I-103J-171D01*
G01Y207215D01*
G02X539193Y207189I-200J2D01*
G01X539188Y207148D01*
X539185Y207137D01*
G03X539137Y206760I1454J-377D01*
G01Y206690D01*
G03X539138Y206670I200J0D01*
G01X539145Y206603D01*
G03X539172Y206434I1495J152D01*
G01X539179Y206407D01*
X539180Y206405D01*
G03X539184Y206388I1464J335D01*
G01Y206384D01*
G03X539188Y206371I1437J435D01*
G01X539195Y206345D01*
Y202582D01*
G03X539254Y202440I200J0D01*
G01X539675Y202019D01*
G03X539817Y201960I142J141D01*
G01X542535D01*
G02X542568Y201957I-2J-200D01*
G02X542675Y201903I-32J-197D01*
G01X542990Y201588D01*
Y193725D01*
G02X542904Y193561I-200J0D01*
G01X542653Y193386D01*
G02X542539Y193350I-114J164D01*
G01X542452D01*
X542421Y193361D01*
G03X541931Y193443I-490J-1420D01*
G01X541915D01*
G03X540429Y191941I16J-1502D01*
G03X541931Y190439I1502J0D01*
G01X541934D01*
G03X542452Y190532I-2J1502D01*
G01X542498Y190549D01*
X542595Y190537D01*
X542904Y190321D01*
G02X542990Y190157I-114J-164D01*
G01Y165175D01*
G02X542931Y165034I-200J1D01*
G01X539464Y161567D01*
X539436Y161538D01*
X539362Y161508D01*
X532348D01*
G02X532177Y161604I0J200D01*
G01X532000Y161896D01*
G02X531984Y161930I172J102D01*
G02X531995Y162094I188J70D01*
G01X531998Y162100D01*
X532015Y162135D01*
G03X532167Y162788I-1350J658D01*
G01Y162790D01*
Y162815D01*
G03X531764Y163817I-1502J-22D01*
G01X531763Y163818D01*
G02X531707Y163957I144J139D01*
G01Y164268D01*
X531734Y164338D01*
X531761Y164366D01*
G03Y166420I-1096J1027D01*
G01X531734Y166448D01*
X531707Y166518D01*
Y166868D01*
X531734Y166938D01*
X531761Y166966D01*
G03X532167Y167993I-1096J1027D01*
G03X531797Y168980I-1501J0D01*
G01X531773Y169008D01*
X531748Y169074D01*
Y169412D01*
X531773Y169478D01*
X531797Y169506D01*
G03X532167Y170493I-1131J987D01*
G03X529163I-1502J0D01*
G03X529533Y169506I1501J0D01*
G01X529557Y169478D01*
X529582Y169412D01*
Y169074D01*
X529557Y169008D01*
X529533Y168980D01*
G03X529163Y167993I1131J-987D01*
G03X529569Y166966I1502J0D01*
G01X529596Y166938D01*
X529623Y166868D01*
Y166518D01*
X529596Y166448D01*
X529569Y166420D01*
G03Y164366I1096J-1027D01*
G01X529596Y164338D01*
X529623Y164268D01*
Y163918D01*
X529596Y163849D01*
X529569Y163820D01*
G03X529163Y162821I1096J-1027D01*
G01Y162812D01*
Y162793D01*
G03X529315Y162135I1502J0D01*
G01X529343Y162077D01*
G02X529346Y161930I-185J-77D01*
G02X529330Y161896I-188J68D01*
G01X529153Y161605D01*
X529126Y161559D01*
X529035Y161508D01*
X525411D01*
G02X525253Y161585I0J200D01*
G01X525030Y161870D01*
X525011Y161959D01*
X525022Y162005D01*
G03X525067Y162368I-1457J365D01*
G03X523565Y163870I-1502J0D01*
G03X522538Y163464I0J-1502D01*
G01X522510Y163437D01*
X522440Y163410D01*
X522090D01*
X522020Y163437D01*
X521992Y163464D01*
G03X520965Y163870I-1027J-1096D01*
G03X519463Y162368I0J-1502D01*
G03X519508Y162005I1502J2D01*
G01X519519Y161959D01*
X519500Y161870D01*
X519277Y161585D01*
G02X519119Y161508I-158J123D01*
G01X503971D01*
G02X503829Y161567I0J200D01*
G01X503173Y162223D01*
G02X503115Y162364I142J141D01*
G01Y240157D01*
G03X503056Y240298I-200J-1D01*
G01X500002Y243352D01*
G03X499862Y243410I-141J-142D01*
G01X492827D01*
G02X492669Y243488I0J200D01*
G01X492477Y243739D01*
G02X492437Y243886I159J122D01*
G01X492441Y243912D01*
X492444Y243924D01*
G03X492491Y244294I-1455J373D01*
G01Y244309D01*
G03X490989Y245799I-1502J-12D01*
G03X490622Y245753I2J-1502D01*
G01X490566Y245739D01*
X490459Y245773D01*
X490151Y246131D01*
X490133Y246242D01*
X490155Y246295D01*
G03X490271Y246874I-1387J579D01*
G03X488769Y248376I-1502J0D01*
G03X487740Y247968I0J-1502D01*
G01X487706Y247936D01*
X487620Y247909D01*
X487266Y247958D01*
G02X487258Y247959I21J199D01*
G02X487121Y248055I36J197D01*
G03X485827Y248794I-1294J-763D01*
G03Y245790I0J-1502D01*
G03X486856Y246198I0J1502D01*
G01X486890Y246230D01*
X486976Y246257D01*
X487330Y246208D01*
G02X487338Y246207I-21J-199D01*
G02X487475Y246111I-36J-197D01*
G03X488769Y245372I1294J763D01*
G03X489136Y245418I-2J1502D01*
G01X489192Y245432D01*
X489299Y245398D01*
X489607Y245040D01*
X489625Y244929D01*
X489603Y244876D01*
G03X489487Y244309I1387J-579D01*
G01Y244294D01*
G03X489534Y243924I1502J3D01*
G01X489537Y243912D01*
X489541Y243886D01*
G02X489501Y243739I-199J-25D01*
G01X489309Y243488D01*
G02X489151Y243410I-158J122D01*
G01X484130D01*
X484084Y243422D01*
X484065Y243431D01*
X484063Y243432D01*
G03X483821Y243523I-648J-1355D01*
G03X483161Y243559I-410J-1445D01*
G03X482757Y243430I250J-1481D01*
G01X482737Y243420D01*
X482693Y243410D01*
X477037D01*
G02X476869Y243501I0J200D01*
G01X476658Y243824D01*
X476654Y243875D01*
X476650Y243924D01*
X476662Y243952D01*
Y243953D01*
X476671Y243973D01*
G03X476795Y244571I-1378J598D01*
G01Y244590D01*
G03X473791I-1502J-19D01*
G01Y244570D01*
G03X473916Y243971I1502J1D01*
G01X473936Y243925D01*
X473932Y243875D01*
X473928Y243824D01*
X473717Y243501D01*
X473689Y243458D01*
X473601Y243410D01*
X463612D01*
X463538Y243440D01*
X463510Y243469D01*
X461901Y245078D01*
X461872Y245106D01*
X461842Y245180D01*
Y265150D01*
G02X461852Y265211I200J-1D01*
G01Y265212D01*
G02X461905Y265296I190J-61D01*
G01X462146Y265523D01*
X462222Y265551D01*
X462264Y265549D01*
G03X462620Y265533I1107J20673D01*
G03X463387Y265518I788J20688D01*
G03X481472Y276143I0J20704D01*
G01Y276144D01*
X481473Y276145D01*
G02X481546Y276219I174J-98D01*
G01X481626Y276267D01*
G02X481727Y276294I100J-173D01*
G37*
G36*
G01X557600Y202336D02*
X561112D01*
G02X561253Y202278I0J-200D01*
G01X563293Y200238D01*
X563308Y200207D01*
G03X563347Y200132I1352J655D01*
G01X563348Y200131D01*
G03X563363Y200105I1308J738D01*
G01X563376Y200083D01*
X563392Y200027D01*
X563405Y199981D01*
Y197600D01*
G02X563372Y197490I-200J0D01*
G03Y195840I1254J-825D01*
G02X563405Y195730I-167J-110D01*
G01Y193600D01*
G02X563372Y193490I-200J0D01*
G03Y191840I1254J-825D01*
G02X563405Y191730I-167J-110D01*
G01Y187518D01*
X563395Y187475D01*
X563384Y187453D01*
G03Y186103I1355J-675D01*
G01X563395Y186081D01*
X563405Y186038D01*
Y181600D01*
G02X563372Y181490I-200J0D01*
G03Y179840I1254J-825D01*
G02X563405Y179730I-167J-110D01*
G01Y177600D01*
G02X563372Y177490I-200J0D01*
G03Y175840I1254J-825D01*
G02X563405Y175730I-167J-110D01*
G01Y173600D01*
G02X563372Y173490I-200J0D01*
G03Y171840I1254J-825D01*
G02X563405Y171730I-167J-110D01*
G01Y169600D01*
G02X563372Y169490I-200J0D01*
G03Y167840I1254J-825D01*
G02X563405Y167730I-167J-110D01*
G01Y163086D01*
G02X563349Y162946I-200J-1D01*
G01X563289Y162885D01*
G02X563234Y162845I-143J139D01*
G01X563145Y162802D01*
X563112Y162798D01*
G03Y159814I180J-1492D01*
G01X563145Y159810D01*
X563234Y159767D01*
G02X563289Y159727I-88J-179D01*
G01X563349Y159666D01*
G02X563405Y159526I-144J-139D01*
G01Y151308D01*
G02X563205Y151108I-200J0D01*
G01X556631D01*
G02X556455Y151213I0J200D01*
G01X556289Y151523D01*
G02X556265Y151625I176J95D01*
G01X556267Y151682D01*
X556298Y151729D01*
G03X556550Y152562I-1251J833D01*
G03X555048Y154064I-1502J0D01*
G03X553754Y153325I0J-1502D01*
G01X553728Y153281D01*
X553643Y153229D01*
X553465Y153219D01*
X553212Y153204D01*
X553122Y153245D01*
X553092Y153285D01*
G03X551898Y153875I-1194J-913D01*
G03X550396Y152373I0J-1502D01*
G03X550561Y151689I1502J0D01*
G01X550585Y151642D01*
X550581Y151539D01*
X550375Y151203D01*
G02X550205Y151108I-170J105D01*
G01X540887D01*
G02X540759Y151155I1J200D01*
G01X539926Y151988D01*
X539621Y152292D01*
G03X538206Y152878I-1415J-1415D01*
G01X531846D01*
G03X530431Y152292I0J-2001D01*
G01X527094Y148955D01*
G03X526508Y147540I1415J-1415D01*
G03X526516Y147354I2001J-7D01*
G01X526517Y147345D01*
Y147340D01*
G03X528504Y145538I1992J200D01*
G01X528509D01*
G03X529011Y145602I0J2002D01*
G03X529924Y146125I-503J1937D01*
G01X532616Y148817D01*
G02X532758Y148876I142J-141D01*
G01X535236D01*
G02X535385Y148809I0J-200D01*
G01X535584Y148588D01*
G02X535634Y148437I-149J-133D01*
G01Y148434D01*
G03X535626Y148277I1494J-155D01*
G03X537128Y146775I1502J0D01*
G03X538317Y147359I0J1502D01*
G01X538341Y147390D01*
X538374Y147410D01*
G02X538444Y147435I101J-173D01*
G01X538713Y147479D01*
G02X538857Y147447I32J-198D01*
G01X538858Y147446D01*
G03X539322Y147214I1120J1659D01*
G03X539977Y147104I654J1892D01*
G01X563205D01*
G02X563405Y146904I0J-200D01*
G01Y124540D01*
X563402Y124524D01*
G03X563383Y124283I1483J-238D01*
G03X563402Y124042I1502J-3D01*
G01X563405Y124026D01*
Y120792D01*
G02X563391Y120718I-200J0D01*
G01X563353Y120621D01*
X563329Y120594D01*
G03Y118594I1122J-1000D01*
G01X563353Y118567D01*
X563391Y118470D01*
G02X563405Y118396I-186J-74D01*
G01Y117752D01*
X563351Y117618D01*
X563328Y117592D01*
G03X562949Y116594I1124J-998D01*
G01Y116592D01*
G03X563253Y115687I1503J1D01*
G02X563293Y115567I-160J-120D01*
G01Y114421D01*
G02X563253Y114301I-200J0D01*
G03Y112487I1199J-907D01*
G02X563293Y112367I-160J-120D01*
G01Y111745D01*
G03X563323Y111640I200J0D01*
G01X563374Y111560D01*
G02X563405Y111453I-169J-107D01*
G01Y109734D01*
G02X563346Y109592I-200J0D01*
G01X562403Y108649D01*
G02X562261Y108590I-142J141D01*
G01X525589D01*
G02X525425Y108676I0J200D01*
G03X522461I-1482J-1027D01*
G02X522297Y108590I-164J114D01*
G01X506016D01*
G02X505874Y108649I0J200D01*
G01X504815Y109708D01*
X504790Y109753D01*
X504783Y109780D01*
G03X503697Y110866I-1456J-370D01*
G01X503670Y110873D01*
X503625Y110898D01*
X503563Y110960D01*
G02X503504Y111102I141J142D01*
G01Y114907D01*
X503591Y115016D01*
X503660Y115031D01*
G03Y117961I-333J1465D01*
G01X503591Y117976D01*
X503504Y118085D01*
Y159263D01*
G02X503563Y159405I200J0D01*
G01X504426Y160268D01*
G02X504568Y160327I142J-141D01*
G01X540085D01*
G03X540227Y160386I0J200D01*
G01X543932Y164091D01*
G03X543991Y164233I-141J142D01*
G01Y201567D01*
G02X544050Y201709I200J0D01*
G01X544618Y202277D01*
G02X544760Y202336I142J-141D01*
G01X554460D01*
G02X554637Y202229I0J-200D01*
G01X554801Y201916D01*
G02X554790Y201711I-177J-93D01*
G01X554789Y201710D01*
G03X554528Y200873I1241J-846D01*
G01Y200845D01*
G03X557532I1502J19D01*
G01Y200865D01*
G03X557271Y201711I-1502J0D01*
G01X557239Y201757D01*
X557233Y201867D01*
X557423Y202229D01*
G02X557600Y202336I177J-93D01*
G37*
G36*
G01X594744Y54588D02*
X623251D01*
X623486Y54353D01*
Y52826D01*
X623251Y52591D01*
X594744D01*
G03X588807Y46654I0J-5937D01*
G01Y7874D01*
G02X582933Y2000I-5874J0D01*
G01X535689D01*
G02X529815Y7874I0J5874D01*
G01Y46526D01*
X531812D01*
Y7874D01*
G03X535687Y3998I3876J0D01*
G01X582933D01*
G03X586810Y7874I0J3877D01*
G01Y46654D01*
G02X594744Y54588I7934J0D01*
G37*
G36*
G01X540397Y275932D02*
X562332D01*
X562406Y275902D01*
X562434Y275873D01*
X563045Y275262D01*
G02X563104Y275120I-141J-142D01*
G01Y205020D01*
X563074Y204946D01*
X563045Y204918D01*
X561524Y203397D01*
G02X561382Y203338I-142J141D01*
G01X540515D01*
X540441Y203368D01*
X540413Y203397D01*
X540255Y203555D01*
G02X540197Y203696I142J141D01*
G01Y204858D01*
G02X540257Y205001I200J0D01*
G01X540491Y205230D01*
X540565Y205259D01*
X540605Y205258D01*
X540639D01*
G03Y208262I0J1502D01*
G01X540605D01*
X540565Y208261D01*
X540491Y208290D01*
X540257Y208519D01*
G02X540197Y208661I140J143D01*
G01Y255107D01*
G02X540315Y255289I200J0D01*
G01X540639Y255436D01*
G02X540810Y255432I81J-183D01*
G01X540860Y255407D01*
X540879Y255392D01*
G03X541853Y255033I975J1143D01*
G03Y258037I0J1502D01*
G03X540879Y257678I1J-1502D01*
G01X540860Y257663D01*
X540810Y257638D01*
G02X540639Y257634I-90J179D01*
G01X540315Y257781D01*
G02X540197Y257963I82J182D01*
G01Y275732D01*
G02X540397Y275932I200J0D01*
G37*
G36*
G01X576129Y242428D02*
X579181D01*
X579198Y242425D01*
G03X579397Y242408I201J1185D01*
G01X583873D01*
G02X584012Y242352I0J-200D01*
G01X584220Y242152D01*
X584252Y242082D01*
X584253Y242042D01*
G03X584722Y241006I1501J55D01*
G01X584724Y241004D01*
X584731Y240997D01*
G03X585774Y240576I1043J1081D01*
G03X587276Y242058I0J1502D01*
G01X587277Y242098D01*
X587308Y242171D01*
X587496Y242352D01*
G02X587635Y242408I139J-144D01*
G01X601873D01*
G02X601930Y242369I-83J-182D01*
G01X604396Y239902D01*
G02X604455Y239761I-141J-142D01*
G01Y153172D01*
G02X604452Y153136I-200J-1D01*
G01X604448Y153114D01*
G02X604392Y153008I-197J36D01*
G01X604383Y152999D01*
X604378Y152995D01*
G03X604224Y147580I2444J-2779D01*
G01X604226Y147578D01*
G03X604343Y147466I2618J2617D01*
G03X604345Y147464I142J140D01*
G03X604379Y147434I2466J2761D01*
G01X604380Y147433D01*
X604388Y147426D01*
G02X604455Y147277I-133J-149D01*
G01Y125105D01*
X604444Y125073D01*
G03X604359Y124576I1417J-498D01*
G03X604444Y124079I1502J1D01*
G01X604455Y124047D01*
Y122985D01*
G03X604470Y122909I200J0D01*
G01X604489Y122863D01*
G02X604505Y122786I-184J-78D01*
G01Y117487D01*
G02X604468Y117370I-200J-1D01*
G03X604187Y116496I1221J-875D01*
G03X604468Y115622I1502J1D01*
G02X604505Y115505I-163J-116D01*
G01Y110680D01*
G03X604518Y110611I200J2D01*
G01X604532Y110573D01*
X604530Y110529D01*
X604520Y110381D01*
X604501Y110329D01*
X604483Y110305D01*
G03X604187Y109410I1205J-895D01*
G03X605689Y107908I1502J0D01*
G03X606620Y108232I-1J1502D01*
G01X606681Y108279D01*
X606831Y108271D01*
X607435Y107667D01*
G03X607577Y107608I142J141D01*
G01X608160D01*
X608177Y107605D01*
G03X608376Y107588I201J1185D01*
G01X624303D01*
G02X624502Y107389I-1J-200D01*
G01Y104239D01*
G03X624525Y103963I1803J11D01*
G03X624532Y103922I1780J283D01*
G01X624534Y103913D01*
X624536Y103896D01*
G02X624452Y103714I-199J-18D01*
G01X624375Y103659D01*
X624264Y103652D01*
X624214Y103677D01*
G03X623527Y103844I-688J-1333D01*
G03X622025Y102342I0J-1502D01*
G03X622495Y101251I1501J0D01*
G01X622497Y101249D01*
X622504Y101242D01*
G03X623547Y100821I1043J1081D01*
G03X625047Y102243I0J1502D01*
G01X625050Y102292D01*
X625099Y102376D01*
X625461Y102601D01*
X625556Y102608D01*
X625602Y102589D01*
G03X626296Y102446I704J1660D01*
G01X626305D01*
G03X628108Y104249I0J1803D01*
G01Y107389D01*
G02X628307Y107588I199J-1D01*
G01X664549D01*
G02X664582Y107585I-2J-200D01*
G02X664689Y107531I-32J-197D01*
G01X666105Y106115D01*
G02X666107Y106113I-140J-142D01*
G02X666164Y105973I-143J-140D01*
G01Y98725D01*
G02X666092Y98571I-200J0D01*
G01X665857Y98374D01*
G02X665693Y98331I-128J154D01*
G01X665692D01*
G03X665426Y98355I-267J-1478D01*
G01X665423D01*
G03X663921Y96853I0J-1502D01*
G03X663998Y96379I1502J1D01*
G01X664013Y96333D01*
X663998Y96238D01*
X663752Y95897D01*
X663666Y95853D01*
X663618D01*
G03X662118Y94351I2J-1502D01*
G03X665122I1502J0D01*
G03X665045Y94825I-1502J-1D01*
G01X665030Y94871D01*
X665045Y94966D01*
X665291Y95307D01*
X665377Y95351D01*
X665425D01*
G03X665692Y95375I0J1502D01*
G01X665693D01*
G02X665857Y95332I36J-197D01*
G01X666092Y95135D01*
G02X666164Y94981I-128J-154D01*
G01Y94811D01*
X666153Y94779D01*
G03X666067Y94279I1416J-501D01*
G03X666153Y93779I1502J1D01*
G01X666164Y93747D01*
Y87556D01*
X666098Y87457D01*
X666041Y87433D01*
G03Y84659I576J-1387D01*
G01X666098Y84635D01*
X666164Y84536D01*
Y62339D01*
G02X666106Y62198I-200J0D01*
G01X665882Y61971D01*
X665811Y61940D01*
X665771D01*
G03X664692Y61457I25J-1502D01*
G01X664662Y61425D01*
X664583Y61392D01*
X664195Y61402D01*
X664118Y61439D01*
X664090Y61473D01*
G03X662935Y62015I-1155J-960D01*
G03Y59011I0J-1502D01*
G03X664038Y59494I0J1501D01*
G01X664068Y59526D01*
X664147Y59559D01*
X664535Y59549D01*
X664612Y59512D01*
X664640Y59478D01*
G03X665134Y59089I1156J959D01*
G01X665180Y59067D01*
X665238Y58986D01*
X665295Y58555D01*
X665260Y58462D01*
X665221Y58429D01*
G03X664707Y57297I988J-1131D01*
G03X665993Y55811I1502J0D01*
G01X666067Y55800D01*
X666164Y55688D01*
Y54059D01*
G02X666105Y53917I-200J0D01*
G01X664903Y52715D01*
X664875Y52686D01*
X664801Y52656D01*
X646231D01*
G02X646089Y52715I0J200D01*
G01X640948Y57856D01*
G03X640851Y57910I-142J-141D01*
G01X640850D01*
G02X640731Y57993I47J194D01*
G01X640526Y58294D01*
X640516Y58392D01*
X640535Y58440D01*
G03X641158Y61614I-7779J3175D01*
G03X641156Y61814I-8402J16D01*
G03X638471Y67773I-8400J-200D01*
G01X638468Y67776D01*
X638464Y67780D01*
G03X632736Y70035I-5728J-6147D01*
G03X624334Y61633I0J-8402D01*
G03X624954Y58466I8402J1D01*
G02X624935Y58279I-185J-76D01*
G01X624749Y58003D01*
G02X624583Y57915I-166J112D01*
G01X617381D01*
X617286Y57974D01*
X617260Y58025D01*
X617113Y58314D01*
G02X617092Y58422I178J91D01*
G01X617097Y58477D01*
X617130Y58523D01*
X617131Y58524D01*
G03X617844Y60708I-2989J2184D01*
G01Y60731D01*
G03X617400Y62466I-3702J-23D01*
G01X617376Y62511D01*
Y62611D01*
X617566Y62963D01*
X617650Y63018D01*
X617701Y63022D01*
G03X619983Y69585I-319J3789D01*
G01X619981Y69587D01*
X619979Y69589D01*
G03X614014Y65028I-2617J-2759D01*
G01X614020Y65018D01*
X614028Y64998D01*
G02X614042Y64911I-186J-74D01*
G01X614039Y64862D01*
X613838Y64528D01*
Y64526D01*
X613837Y64525D01*
G02X613666Y64429I-171J104D01*
G01X606822D01*
G03X603121Y60728I0J-3701D01*
G01Y60726D01*
G03X603829Y58551I3701J2D01*
G01X603862Y58505D01*
X603871Y58394D01*
X603685Y58025D01*
G02X603596Y57937I-178J91D01*
G01X603594Y57936D01*
G02X603505Y57915I-89J179D01*
G01X566809D01*
G02X566667Y57974I0J200D01*
G01X565901Y58740D01*
G02X565860Y58963I142J141D01*
G01X566038Y59361D01*
X566143Y59425D01*
X566205Y59422D01*
G03X566287Y59420I78J1500D01*
G03Y62424I0J1502D01*
G03X565605Y62260I0J-1502D01*
G01X565558Y62236D01*
X565455Y62240D01*
X565119Y62446D01*
G02X565043Y62531I105J170D01*
G01X565042D01*
G02X565023Y62617I181J85D01*
G01Y84646D01*
G02X565109Y84811I200J1D01*
G03Y87281I-853J1235D01*
G02X565023Y87446I114J164D01*
G01Y92494D01*
G02X565059Y92608I200J0D01*
G01X565073Y92628D01*
X565165Y92721D01*
G02X565225Y92762I141J-142D01*
G01X565260Y92778D01*
G03X566709Y94279I-53J1501D01*
G03X565331Y95776I-1502J0D01*
G01X565293Y95779D01*
X565226Y95812D01*
X565017Y96039D01*
G02X564964Y96175I147J136D01*
G01Y108934D01*
X565025Y109032D01*
X565078Y109057D01*
G03X565620Y109497I-650J1354D01*
G01X565622Y109499D01*
X565631Y109510D01*
X565654Y109533D01*
G02X565763Y109588I140J-142D01*
G01X565764Y109589D01*
X566078Y109635D01*
X566155Y109615D01*
X566188Y109590D01*
G03X567069Y109282I912J1194D01*
G01X567098Y109281D01*
G03X567146Y109282I-7J1503D01*
G01X567174Y109284D01*
X567175D01*
G03X568410Y110050I-75J1500D01*
G02X568585Y110152I174J-98D01*
G01X568900D01*
G02X569073Y110052I0J-200D01*
G03X569346Y109708I1301J752D01*
G01X569348Y109706D01*
X569355Y109699D01*
G03X570394Y109282I1039J1086D01*
G03X571896Y110784I0J1502D01*
G03X571423Y111878I-1502J0D01*
G01X571419Y111882D01*
X571417Y111884D01*
G03X570374Y112305I-1043J-1081D01*
G03X569073Y111554I0J-1502D01*
G02X568900Y111454I-173J100D01*
G01X568561D01*
X568434Y111527D01*
G02X568397Y111555I101J173D01*
G01X568379Y111572D01*
X568366Y111593D01*
G03X568310Y111675I-1268J-806D01*
G01X568309D01*
G03X568151Y111857I-1209J-890D01*
G01X568126Y111881D01*
X568124Y111883D01*
G03X567080Y112305I-1044J-1080D01*
G03X565888Y111717I0J-1502D01*
G01X565880Y111706D01*
X565857Y111683D01*
G02X565745Y111627I-141J142D01*
G01X565469Y111586D01*
G02X565393Y111590I-28J198D01*
G01X565353Y111599D01*
X565320Y111623D01*
G03X565294Y111642I-899J-1203D01*
G01X565293Y111643D01*
X565275Y111656D01*
X565229Y111705D01*
G02X565198Y111748I145J137D01*
G01X565164Y111811D01*
G02X565141Y111905I177J93D01*
G01Y111924D01*
G02X565167Y112023I200J0D01*
G01X565183Y112051D01*
X565250Y112121D01*
X565270Y112134D01*
G03X565953Y113394I-821J1260D01*
G01Y113396D01*
G03X565490Y114480I-1503J-1D01*
G01X565488Y114481D01*
G03X565078Y114769I-1057J-1069D01*
G01X565025Y114794D01*
X564964Y114891D01*
Y115031D01*
G02X565021Y115171I200J0D01*
G01X565022Y115172D01*
X565079Y115229D01*
X565109Y115244D01*
G03X565953Y116594I-658J1350D01*
G03X565478Y117690I-1502J0D01*
G01X565476Y117692D01*
G03X565354Y117798I-1045J-1079D01*
G02X565277Y117956I123J158D01*
G01Y118236D01*
G02X565356Y118396I200J1D01*
G03X565953Y119594I-905J1199D01*
G01Y119596D01*
G03X565490Y120680I-1503J-1D01*
G01X565488Y120681D01*
G03X565078Y120969I-1057J-1069D01*
G01X565025Y120994D01*
X564964Y121091D01*
Y122604D01*
G02X565130Y122801I200J0D01*
G01X565131D01*
G03X566387Y124283I-246J1482D01*
G03X565914Y125377I-1502J0D01*
G01X565912Y125379D01*
X565909Y125382D01*
G03X565129Y125781I-1045J-1080D01*
G01X565057Y125794D01*
X564964Y125904D01*
Y131938D01*
G02X564993Y132042I200J0D01*
G02X565070Y132115I171J-103D01*
G01X565080Y132120D01*
X565421Y132267D01*
G02X565590Y132262I79J-184D01*
G01X565618Y132248D01*
X565639Y132228D01*
G03X565819Y132082I1034J1091D01*
G01X565820Y132081D01*
G02X565899Y131967I-115J-164D01*
G01X565964Y131714D01*
G02X565948Y131573I-194J-49D01*
G01Y131572D01*
X565940Y131557D01*
X565938Y131552D01*
G03X565788Y130893I1352J-654D01*
G01Y130877D01*
G03X567290Y129396I1502J21D01*
G03X568792Y130898I0J1502D01*
G03X568157Y132125I-1503J0D01*
G01X568143Y132135D01*
X568115Y132163D01*
X568114Y132165D01*
G02X568063Y132255I142J140D01*
G01X568000Y132502D01*
G02X567995Y132573I194J49D01*
G01X567999Y132608D01*
X568015Y132641D01*
X568016Y132642D01*
G03X568101Y132849I-1343J672D01*
G01X568112Y132882D01*
X568157Y132941D01*
X568190Y132960D01*
X568395Y133083D01*
G02X568466Y133109I103J-171D01*
G01X568502Y133115D01*
X568524Y133111D01*
G03X568841Y133077I318J1468D01*
G03X570343Y134579I0J1502D01*
G03X569870Y135673I-1502J0D01*
G01X569866Y135677D01*
X569864Y135679D01*
G03X568821Y136100I-1043J-1081D01*
G03X567392Y135064I0J-1504D01*
G01X567381Y135030D01*
X567337Y134974D01*
X567048Y134801D01*
X566978Y134788D01*
X566942Y134795D01*
G03X566675Y134819I-267J-1478D01*
G01X566674D01*
G03X565639Y134406I0J-1503D01*
G01X565618Y134386D01*
X565590Y134372D01*
G02X565421Y134367I-90J179D01*
G01X565085Y134512D01*
G02X564964Y134696I79J184D01*
G01Y167115D01*
X565039Y167219D01*
X565101Y167240D01*
G03X566129Y168665I-474J1425D01*
G03X566116Y168865I-1502J3D01*
G03X565653Y169762I-1489J-200D01*
G01X565652Y169763D01*
X565641Y169773D01*
G03X565631Y169782I-1010J-1112D01*
G02X565628Y169784I108J166D01*
G03X565098Y170103I-1023J-1099D01*
G01X565038Y170124D01*
X564964Y170228D01*
Y171115D01*
X565039Y171219D01*
X565101Y171240D01*
G03X566129Y172665I-474J1425D01*
G03X566116Y172865I-1502J3D01*
G03X565653Y173762I-1489J-200D01*
G01X565652Y173763D01*
X565641Y173773D01*
G03X565631Y173782I-1010J-1112D01*
G02X565628Y173784I108J166D01*
G03X565098Y174103I-1023J-1099D01*
G01X565038Y174124D01*
X564964Y174228D01*
Y175115D01*
X565039Y175219D01*
X565101Y175240D01*
G03X566129Y176665I-474J1425D01*
G03X566116Y176865I-1502J3D01*
G03X565653Y177762I-1489J-200D01*
G01X565652Y177763D01*
X565641Y177773D01*
G03X565631Y177782I-1010J-1112D01*
G02X565628Y177784I108J166D01*
G03X565098Y178103I-1023J-1099D01*
G01X565038Y178124D01*
X564964Y178228D01*
Y179115D01*
X565039Y179219D01*
X565101Y179240D01*
G03X566129Y180665I-474J1425D01*
G03X566116Y180865I-1502J3D01*
G03X565653Y181762I-1489J-200D01*
G01X565652Y181763D01*
X565641Y181773D01*
G03X565631Y181782I-1010J-1112D01*
G02X565628Y181784I108J166D01*
G03X565098Y182103I-1023J-1099D01*
G01X565038Y182124D01*
X564964Y182228D01*
Y185198D01*
X565047Y185306D01*
X565114Y185323D01*
G03X566242Y186778I-374J1455D01*
G03X565770Y187871I-1502J0D01*
G02X565768Y187873I140J142D01*
G03X565112Y188247I-1048J-1076D01*
G01X565046Y188265D01*
X564964Y188372D01*
Y191115D01*
X565039Y191219D01*
X565101Y191240D01*
G03X566129Y192665I-474J1425D01*
G03X566116Y192865I-1502J3D01*
G03X565653Y193762I-1489J-200D01*
G01X565652Y193763D01*
X565641Y193773D01*
G03X565631Y193782I-1010J-1112D01*
G02X565628Y193784I108J166D01*
G03X565098Y194103I-1023J-1099D01*
G01X565038Y194124D01*
X564964Y194228D01*
Y195115D01*
X565039Y195219D01*
X565101Y195240D01*
G03X566129Y196665I-474J1425D01*
G03X566116Y196865I-1502J3D01*
G03X565653Y197762I-1489J-200D01*
G01X565652Y197763D01*
X565641Y197773D01*
G03X565631Y197782I-1010J-1112D01*
G02X565628Y197784I108J166D01*
G03X565098Y198103I-1023J-1099D01*
G01X565038Y198124D01*
X564964Y198228D01*
Y199305D01*
X565041Y199410D01*
X565105Y199430D01*
G03X566161Y200864I-446J1434D01*
G03X565687Y201959I-1502J0D01*
G02X565685Y201961I140J142D01*
G03X565102Y202312I-1046J-1078D01*
G01X565040Y202332D01*
X564964Y202437D01*
Y203209D01*
G02X565025Y203353I200J0D01*
G01X565104Y203429D01*
X565146Y203443D01*
G03X566161Y204864I-487J1421D01*
G03X565687Y205959I-1502J0D01*
G02X565685Y205961I140J142D01*
G03X565668Y205977I-1038J-1086D01*
G02X565606Y206122I138J145D01*
G01Y207606D01*
G02X565671Y207754I200J1D01*
G03X566161Y208864I-1012J1110D01*
G03X565687Y209959I-1502J0D01*
G02X565685Y209961I140J142D01*
G03X565668Y209977I-1038J-1086D01*
G02X565606Y210122I138J145D01*
G01Y211606D01*
G02X565671Y211754I200J1D01*
G03X566161Y212864I-1012J1110D01*
G03X565687Y213959I-1502J0D01*
G02X565685Y213961I140J142D01*
G03X565668Y213977I-1038J-1086D01*
G02X565606Y214122I138J145D01*
G01Y215606D01*
G02X565671Y215754I200J1D01*
G03X566161Y216864I-1012J1110D01*
G03X565687Y217959I-1502J0D01*
G02X565685Y217961I140J142D01*
G03X565668Y217977I-1038J-1086D01*
G02X565606Y218122I138J145D01*
G01Y220606D01*
G02X565671Y220754I200J1D01*
G03X566161Y221864I-1012J1110D01*
G03X565687Y222959I-1502J0D01*
G02X565685Y222961I140J142D01*
G03X565668Y222977I-1038J-1086D01*
G02X565606Y223122I138J145D01*
G01Y242110D01*
G02X565664Y242251I200J0D01*
G01X565762Y242349D01*
G02X565904Y242408I142J-141D01*
G01X575913D01*
G03X576112Y242425I-2J1202D01*
G01X576129Y242428D01*
G37*
G36*
G01X641454Y267210D02*
X641119Y267048D01*
G02X641009Y267030I-86J180D01*
G01X640982Y267033D01*
X640932Y267053D01*
X640908Y267072D01*
G03X639974Y267398I-934J-1175D01*
G03Y264394I0J-1502D01*
G03X640907Y264720I-1J1501D01*
G01X640909D01*
X640910Y264721D01*
G02X641010Y264762I123J-157D01*
G01X641038Y264766D01*
X641093Y264756D01*
X641454Y264582D01*
G02X641557Y264411I-97J-175D01*
G01Y257954D01*
G02X641530Y257855I-200J1D01*
G01X641517Y257832D01*
X641481Y257796D01*
X641457Y257782D01*
X641168Y257614D01*
G02X641119Y257593I-103J172D01*
G02X641099Y257589I-49J194D01*
G01X641085Y257587D01*
G02X641024Y257591I-18J199D01*
G01X640960Y257608D01*
X640938Y257620D01*
G03X640216Y257805I-723J-1319D01*
G01X640215D01*
G03Y254801I0J-1502D01*
G01X640216D01*
G03X640938Y254986I-1J1504D01*
G01X640960Y254998D01*
X641024Y255015D01*
G02X641085Y255019I43J-195D01*
G01X641099Y255017D01*
G02X641119Y255013I-29J-198D01*
G02X641168Y254992I-54J-193D01*
G01X641457Y254824D01*
G02X641464Y254820I-96J-176D01*
G02X641557Y254651I-107J-169D01*
G01Y207215D01*
G02X641555Y207189I-200J2D01*
G01X641550Y207149D01*
G03X641499Y206760I1451J-388D01*
G03Y206753I1502J-4D01*
G01Y206690D01*
G03X641500Y206670I200J0D01*
G01X641505Y206622D01*
G03X641534Y206434I1496J135D01*
G01X641541Y206407D01*
G03X641546Y206388I1455J373D01*
G01Y206384D01*
G03X641550Y206371I1437J435D01*
G01X641557Y206345D01*
Y202582D01*
G03X641616Y202440I200J0D01*
G01X642037Y202019D01*
G03X642179Y201960I142J141D01*
G01X644897D01*
G02X644930Y201957I-2J-200D01*
G02X645037Y201903I-32J-197D01*
G01X645293Y201647D01*
G02X645352Y201505I-141J-142D01*
G01Y193725D01*
G02X645351Y193711I-200J7D01*
G02X645266Y193561I-200J14D01*
G01X644998Y193374D01*
G02X644952Y193350I-115J164D01*
G01X644814D01*
X644783Y193361D01*
G03X644293Y193443I-490J-1420D01*
G01X644277D01*
G03X642791Y191941I16J-1502D01*
G03X644293Y190439I1502J0D01*
G01X644296D01*
G03X644814Y190532I-2J1502D01*
G02X644996Y190509I69J-188D01*
G01X645132Y190414D01*
X645266Y190321D01*
X645267Y190320D01*
G02X645351Y190171I-115J-163D01*
G02X645352Y190157I-199J-21D01*
G01Y165176D01*
G02X645350Y165144I-200J-4D01*
G02X645313Y165058I-197J34D01*
G02X645293Y165034I-163J115D01*
G01X641825Y161566D01*
G02X641775Y161530I-140J142D01*
G02X641684Y161508I-91J178D01*
G01X634709D01*
G02X634611Y161534I1J200D01*
G01X634591Y161545D01*
X634554Y161580D01*
X634363Y161896D01*
G02X634344Y161937I171J104D01*
G02X634357Y162094I190J63D01*
G01X634367Y162114D01*
G03X634529Y162788I-1340J679D01*
G01Y162815D01*
G03X634126Y163817I-1502J-22D01*
G01X634124Y163819D01*
G02X634081Y163886I144J139D01*
G01X634069Y163918D01*
Y164231D01*
G02X634082Y164302I200J0D01*
G01X634095Y164336D01*
X634123Y164366D01*
G03Y166420I-1096J1027D01*
G01X634095Y166450D01*
X634082Y166484D01*
G02X634069Y166555I187J71D01*
G01Y166831D01*
G02X634082Y166902I200J0D01*
G01X634095Y166936D01*
X634123Y166966D01*
G03X634529Y167993I-1096J1027D01*
G03X634159Y168980I-1501J0D01*
G01X634135Y169008D01*
X634123Y169040D01*
G02X634110Y169111I187J71D01*
G01Y169375D01*
G02X634123Y169446I200J0D01*
G01X634135Y169478D01*
X634159Y169506D01*
G03X634529Y170493I-1131J987D01*
G03X631525I-1502J0D01*
G03X631895Y169506I1501J0D01*
G01X631919Y169478D01*
X631931Y169446D01*
G02X631944Y169375I-187J-71D01*
G01Y169111D01*
G02X631931Y169040I-200J0D01*
G01X631919Y169008D01*
X631895Y168980D01*
G03X631525Y167993I1131J-987D01*
G03X631931Y166966I1502J0D01*
G01X631959Y166936D01*
X631972Y166902D01*
G02X631985Y166831I-187J-71D01*
G01Y166555D01*
G02X631972Y166484I-200J0D01*
G01X631959Y166450D01*
X631931Y166420D01*
G03Y164366I1096J-1027D01*
G01X631959Y164336D01*
X631972Y164302D01*
G02X631985Y164231I-187J-71D01*
G01Y163955D01*
G02X631972Y163884I-200J0D01*
G01X631959Y163850D01*
X631931Y163820D01*
G03X631525Y162821I1096J-1027D01*
G01Y162793D01*
G03X631686Y162117I1502J1D01*
G01X631705Y162077D01*
G02X631709Y161934I-185J-77D01*
G02X631691Y161896I-189J66D01*
G01X631515Y161605D01*
G02X631344Y161508I-171J103D01*
G01X627772D01*
G02X627684Y161528I-1J200D01*
G01X627665Y161538D01*
X627630Y161566D01*
X627615Y161585D01*
X627420Y161834D01*
G02X627382Y161915I158J123D01*
G01X627373Y161959D01*
X627384Y162005D01*
G03X627429Y162368I-1457J365D01*
G03X625927Y163870I-1502J0D01*
G03X624900Y163464I0J-1502D01*
G01X624870Y163436D01*
X624836Y163423D01*
G02X624765Y163410I-71J187D01*
G01X624489D01*
G02X624418Y163423I0J200D01*
G01X624384Y163436D01*
X624354Y163464D01*
G03X622300I-1027J-1096D01*
G01X622270Y163436D01*
X622236Y163423D01*
G02X622165Y163410I-71J187D01*
G01X621889D01*
G02X621818Y163423I0J200D01*
G01X621784Y163436D01*
X621754Y163464D01*
G03X620727Y163870I-1027J-1096D01*
G03X619225Y162368I0J-1502D01*
G03X619270Y162005I1502J2D01*
G01X619281Y161959D01*
X619272Y161915D01*
G02X619234Y161834I-196J42D01*
G01X619039Y161585D01*
G02X618882Y161508I-158J123D01*
G01X606332D01*
G02X606257Y161522I-1J200D01*
G01X606221Y161537D01*
X605535Y162223D01*
G02X605477Y162364I142J141D01*
G01Y240157D01*
G03X605418Y240298I-200J-1D01*
G01X605229Y240487D01*
G02X605213Y240505I141J142D01*
G03X605112Y240619I-957J-746D01*
G01X602644Y243088D01*
G03X602532Y243187I-858J-858D01*
G02X602513Y243203I119J160D01*
G01X602364Y243352D01*
G03X602224Y243410I-141J-142D01*
G01X602078D01*
G02X602036Y243414I-2J200D01*
G03X601998Y243422I-269J-1183D01*
G01X595121D01*
G02X595038Y243480I69J188D01*
G01X594834Y243745D01*
G02X594796Y243861I162J117D01*
G01X594803Y243912D01*
X594806Y243924D01*
G03X594853Y244287I-1455J373D01*
G01Y244309D01*
G03X593351Y245799I-1502J-12D01*
G03X592984Y245753I2J-1502D01*
G01X592983D01*
G02X592874Y245756I-49J194D01*
G01X592848Y245765D01*
X592803Y245794D01*
X592550Y246088D01*
G02X592504Y246187I151J131D01*
G01X592499Y246214D01*
X592506Y246268D01*
X592517Y246295D01*
G03X592633Y246874I-1387J579D01*
G03X591131Y248376I-1502J0D01*
G03X590102Y247968I0J-1502D01*
G01X590101Y247967D01*
G02X590024Y247922I-137J146D01*
G01X589982Y247909D01*
X589628Y247958D01*
G02X589620Y247959I21J199D01*
G02X589483Y248055I36J197D01*
G03X588189Y248794I-1294J-763D01*
G03Y245790I0J-1502D01*
G03X589218Y246198I0J1502D01*
G01X589219Y246199D01*
G02X589296Y246244I137J-146D01*
G01X589338Y246257D01*
X589692Y246207D01*
G02X589776Y246175I-27J-198D01*
G01X589795Y246163D01*
X589826Y246130D01*
X589837Y246111D01*
G03X591131Y245372I1294J763D01*
G03X591273Y245378I8J1502D01*
G01X591307Y245382D01*
G03X591389Y245394I-176J1492D01*
G01X591391D01*
G03X591497Y245418I-278J1476D01*
G01X591499D01*
X591527Y245425D01*
X591581Y245424D01*
X591607Y245415D01*
G02X591698Y245355I-60J-191D01*
G01X591932Y245083D01*
G02X591978Y244984I-151J-131D01*
G01X591983Y244957D01*
X591976Y244903D01*
X591965Y244876D01*
G03X591849Y244309I1387J-579D01*
G01Y244294D01*
G03X591896Y243924I1502J3D01*
G01X591899Y243912D01*
X591906Y243861D01*
G02X591868Y243745I-200J1D01*
G01X591664Y243480D01*
G02X591581Y243422I-152J130D01*
G01X587634D01*
G03X587480Y243412I1J-1214D01*
G02X587454Y243410I-28J198D01*
G01X586492D01*
X586446Y243422D01*
X586427Y243431D01*
X586425Y243432D01*
G03X586265Y243497I-644J-1357D01*
G03X585575Y243567I-493J-1419D01*
G03X585124Y243433I197J-1489D01*
G03X585122Y243431I133J-135D01*
G01X585119Y243430D01*
X585110Y243425D01*
X585102Y243422D01*
X585056Y243410D01*
X584054D01*
G02X584028Y243412I2J200D01*
G03X583874Y243422I-155J-1204D01*
G01X579398D01*
G02X579370Y243424I-1J188D01*
G01X579299Y243437D01*
G02X579233Y243498I99J174D01*
G01X579231Y243501D01*
X579045Y243786D01*
G02X579016Y243875I170J105D01*
G01X579012Y243924D01*
X579024Y243952D01*
X579030Y243967D01*
X579033Y243973D01*
G03X579157Y244548I-1378J598D01*
G01Y244590D01*
G03X576153I-1502J-19D01*
G01Y244570D01*
G03X576278Y243971I1502J1D01*
G01X576288Y243948D01*
X576296Y243900D01*
X576294Y243875D01*
G02X576265Y243786I-199J16D01*
G01X576079Y243501D01*
X576077Y243498D01*
G02X576011Y243437I-165J113D01*
G01X575940Y243424D01*
G02X575912Y243422I-27J186D01*
G01X565946D01*
G02X565885Y243457I67J188D01*
G01X564260Y245081D01*
G02X564206Y245193I144J139D01*
G02X564204Y245220I198J28D01*
G01Y275400D01*
G02X564208Y275438I200J-2D01*
G02X564261Y275540I196J-37D01*
G01X564958Y276237D01*
G02X565060Y276290I139J-143D01*
G02X565098Y276294I40J-196D01*
G01X640072D01*
G02X640104Y276291I-3J-200D01*
G01X640106D01*
G02X640212Y276237I-34J-197D01*
G01X641500Y274949D01*
G02X641553Y274847I-143J-139D01*
G02X641557Y274809I-196J-40D01*
G01Y267385D01*
Y267381D01*
G02X641454Y267210I-200J4D01*
G37*
G36*
G01X559858Y1186600D02*
X561152D01*
G02X561228Y1186585I0J-200D01*
G01X564489Y1185235D01*
X564555Y1185141D01*
X564558Y1185083D01*
G03X566058Y1183662I1500J81D01*
G03X567284Y1184295I1J1502D01*
G01X567319Y1184346D01*
X567433Y1184388D01*
X569967Y1183789D01*
G02X570062Y1183736I-46J-195D01*
G01X579116Y1174682D01*
G02X579175Y1174540I-141J-142D01*
G01Y1109415D01*
G02X579116Y1109273I-200J0D01*
G01X576620Y1106777D01*
X576592Y1106748D01*
X576518Y1106718D01*
X561628D01*
G02X561486Y1106777I0J200D01*
G01X559328Y1108935D01*
X559299Y1108963D01*
X559269Y1109037D01*
Y1112868D01*
G02X559349Y1113028I200J0D01*
G01X559644Y1113248D01*
X559736Y1113265D01*
X559782Y1113251D01*
G03X560209Y1113189I427J1440D01*
G01X560211D01*
G03Y1116193I0J1502D01*
G01X560209D01*
G03X559782Y1116131I0J-1502D01*
G01X559736Y1116117D01*
X559644Y1116134D01*
X559349Y1116354D01*
G02X559269Y1116514I120J160D01*
G01Y1125468D01*
G02X559349Y1125628I200J0D01*
G01X559644Y1125848D01*
X559736Y1125865D01*
X559782Y1125851D01*
G03X560209Y1125789I427J1440D01*
G01X560211D01*
G03Y1128793I0J1502D01*
G01X560209D01*
G03X559782Y1128731I0J-1502D01*
G01X559736Y1128717D01*
X559644Y1128734D01*
X559349Y1128954D01*
G02X559269Y1129114I120J160D01*
G01Y1138068D01*
G02X559349Y1138228I200J0D01*
G01X559644Y1138448D01*
X559736Y1138465D01*
X559782Y1138451D01*
G03X560209Y1138389I427J1440D01*
G01X560211D01*
G03Y1141393I0J1502D01*
G01X560209D01*
G03X559782Y1141331I0J-1502D01*
G01X559736Y1141317D01*
X559644Y1141334D01*
X559349Y1141554D01*
G02X559269Y1141714I120J160D01*
G01Y1150668D01*
G02X559349Y1150828I200J0D01*
G01X559644Y1151048D01*
X559736Y1151065D01*
X559782Y1151051D01*
G03X560209Y1150989I427J1440D01*
G01X560211D01*
G03Y1153993I0J1502D01*
G01X560209D01*
G03X559782Y1153931I0J-1502D01*
G01X559736Y1153917D01*
X559644Y1153934D01*
X559349Y1154154D01*
G02X559269Y1154314I120J160D01*
G01Y1163268D01*
G02X559349Y1163428I200J0D01*
G01X559644Y1163648D01*
X559736Y1163665D01*
X559782Y1163651D01*
G03X560209Y1163589I427J1440D01*
G01X560211D01*
G03Y1166593I0J1502D01*
G01X560209D01*
G03X559782Y1166531I0J-1502D01*
G01X559736Y1166517D01*
X559644Y1166534D01*
X559349Y1166754D01*
G02X559269Y1166914I120J160D01*
G01Y1175868D01*
G02X559349Y1176028I200J0D01*
G01X559644Y1176248D01*
X559736Y1176265D01*
X559782Y1176251D01*
G03X560209Y1176189I427J1440D01*
G01X560211D01*
G03Y1179193I0J1502D01*
G01X560209D01*
G03X559782Y1179131I0J-1502D01*
G01X559736Y1179117D01*
X559644Y1179134D01*
X559349Y1179354D01*
G02X559269Y1179514I120J160D01*
G01Y1186011D01*
G02X559328Y1186153I200J0D01*
G01X559716Y1186541D01*
G02X559858Y1186600I142J-141D01*
G37*
G36*
G01X746584Y1127672D02*
Y1127595D01*
G02X746582Y1127569I-200J2D01*
G01X746576Y1127521D01*
X746558Y1127488D01*
G03X746406Y1127170I3346J-1795D01*
G01X746405Y1127168D01*
X746392Y1127139D01*
X746375Y1127119D01*
G02X746341Y1127087I-153J129D01*
G01X746272Y1127040D01*
X746247Y1127023D01*
X746141Y1126990D01*
X746114Y1126989D01*
G03Y1124387I47J-1301D01*
G01X746141Y1124386D01*
X746220Y1124361D01*
G02X746232Y1124357I-57J-192D01*
G02X746270Y1124337I-74J-186D01*
G01X746333Y1124295D01*
G02X746337Y1124292I-118J-161D01*
G02X746377Y1124255I-115J-164D01*
G01X746393Y1124236D01*
X746405Y1124209D01*
X746406Y1124205D01*
G03X746417Y1124177I3539J1374D01*
G03X746419Y1124175I142J140D01*
G03X746441Y1124124I3497J1478D01*
G01Y1124123D01*
G03X746449Y1124107I3399J1689D01*
G02X746453Y1124099I-177J-93D01*
G03X746459Y1124085I3492J1488D01*
G01Y1124084D01*
G03X746473Y1124056I3402J1684D01*
G01Y1124054D01*
X746476Y1124050D01*
Y1124048D01*
G03X746477Y1124046I180J89D01*
G02X746479Y1124043I-164J-111D01*
G03X746536Y1123929I3424J1641D01*
G01X746559Y1123885D01*
X746572Y1123861D01*
X746583Y1123816D01*
Y1123703D01*
G02X746553Y1123598I-200J0D01*
G01X746474Y1123472D01*
Y1123470D01*
X746431Y1123400D01*
G02X746429Y1123398I-142J140D01*
G01X746394Y1123342D01*
G02X746232Y1123249I-169J107D01*
G01X746192D01*
G03X746162Y1123250I-58J-1300D01*
G01X746160D01*
G03Y1120646I1J-1302D01*
G01X746162D01*
G03X746192Y1120647I-28J1301D01*
G01X746225D01*
G02X746362Y1120592I-1J-200D01*
G01X746389Y1120564D01*
X746579Y1120257D01*
G02X746583Y1120054I-170J-105D01*
G01X746559Y1120009D01*
G03X746515Y1119925I3341J-1803D01*
G03X746405Y1119689I3384J-1721D01*
G01X746393Y1119661D01*
X746377Y1119641D01*
G02X746337Y1119604I-155J127D01*
G02X746333Y1119601I-122J158D01*
G01X746270Y1119559D01*
G02X746262Y1119554I-110J167D01*
G02X746232Y1119539I-104J171D01*
G02X746220Y1119535I-69J188D01*
G01X746141Y1119510D01*
X746114Y1119509D01*
G03X746140Y1116906I47J-1301D01*
G01X746143D01*
G02X746218Y1116889I-6J-200D01*
G02X746248Y1116872I-83J-182D01*
G01X746337Y1116813D01*
Y1116812D01*
G02X746395Y1116750I-114J-165D01*
G01X746404Y1116729D01*
G03X746519Y1116482I3497J1478D01*
G03X746647Y1116251I3383J1724D01*
G01X746648Y1116250D01*
X746657Y1116235D01*
G02X746666Y1116083I-180J-87D01*
G01X746659Y1116066D01*
X746658Y1116064D01*
G02X746616Y1116002I-184J79D01*
G01X746437Y1115823D01*
G02X746313Y1115765I-142J141D01*
G01X746286D01*
G03X746162Y1115770I-114J-1297D01*
G01X746160D01*
G03X744859Y1114468I1J-1302D01*
G03X744864Y1114351I1302J-3D01*
G02X744806Y1114192I-199J-17D01*
G01X742696Y1112082D01*
G02X742572Y1112024I-142J141D01*
G01X742545D01*
G03X742421Y1112029I-114J-1297D01*
G01X742419D01*
G03X741161Y1111056I1J-1301D01*
G01X741155Y1111033D01*
X741110Y1110951D01*
X741109Y1110950D01*
G02X740962Y1110885I-148J135D01*
G01X740138D01*
G02X740011Y1110930I-1J200D01*
G02X739947Y1111024I127J155D01*
G01X739944Y1111037D01*
G03X737416Y1111039I-1264J-309D01*
G01Y1111037D01*
X737411Y1111018D01*
G02X737233Y1110885I-189J67D01*
G01X736398D01*
G02X736271Y1110930I-1J200D01*
G02X736207Y1111024I127J155D01*
G01X736204Y1111037D01*
G03X733676Y1111039I-1264J-309D01*
G01Y1111037D01*
X733671Y1111018D01*
G02X733493Y1110885I-189J67D01*
G01X732658D01*
G02X732531Y1110930I-1J200D01*
G02X732467Y1111024I127J155D01*
G01X732464Y1111037D01*
G03X729936Y1111039I-1264J-309D01*
G01Y1111037D01*
X729931Y1111018D01*
G02X729753Y1110885I-189J67D01*
G01X728918D01*
G02X728791Y1110930I-1J200D01*
G02X728727Y1111024I127J155D01*
G01X728724Y1111037D01*
G03X726196Y1111039I-1264J-309D01*
G01Y1111037D01*
X726191Y1111018D01*
G02X726013Y1110885I-189J67D01*
G01X725179D01*
G02X725052Y1110930I-1J200D01*
G02X724988Y1111024I127J155D01*
G01X724985Y1111037D01*
G03X722455Y1111039I-1265J-309D01*
G01Y1111037D01*
X722450Y1111018D01*
G02X722272Y1110885I-189J67D01*
G01X721439D01*
G02X721312Y1110930I-1J200D01*
G02X721248Y1111024I127J155D01*
G01X721245Y1111037D01*
G03X718715Y1111039I-1265J-309D01*
G01Y1111037D01*
X718710Y1111018D01*
G02X718532Y1110885I-189J67D01*
G01X717699D01*
G02X717572Y1110930I-1J200D01*
G02X717508Y1111024I127J155D01*
G01X717505Y1111037D01*
G03X714975Y1111039I-1265J-309D01*
G01Y1111037D01*
X714970Y1111018D01*
G02X714792Y1110885I-189J67D01*
G01X713959D01*
G02X713832Y1110930I-1J200D01*
G02X713768Y1111024I127J155D01*
G01X713765Y1111037D01*
G03X711235Y1111039I-1265J-309D01*
G01Y1111037D01*
X711230Y1111018D01*
G02X711052Y1110885I-189J67D01*
G01X710219D01*
G02X710092Y1110930I-1J200D01*
G02X710028Y1111024I127J155D01*
G01X710025Y1111037D01*
G03X707495Y1111039I-1265J-309D01*
G01Y1111037D01*
X707490Y1111018D01*
G02X707312Y1110885I-189J67D01*
G01X706479D01*
G02X706352Y1110930I-1J200D01*
G02X706288Y1111024I127J155D01*
G01X706285Y1111037D01*
G03X703755Y1111039I-1265J-309D01*
G01Y1111037D01*
X703750Y1111018D01*
G02X703572Y1110885I-189J67D01*
G01X702738D01*
G02X702611Y1110930I-1J200D01*
G02X702547Y1111024I127J155D01*
G01X702544Y1111037D01*
G03X700014Y1111039I-1265J-309D01*
G01Y1111037D01*
X700009Y1111018D01*
G02X699831Y1110885I-189J67D01*
G01X698998D01*
G02X698871Y1110930I-1J200D01*
G02X698807Y1111024I127J155D01*
G01X698804Y1111037D01*
G03X696274Y1111039I-1265J-309D01*
G01Y1111037D01*
X696269Y1111018D01*
G02X696091Y1110885I-189J67D01*
G01X695258D01*
G02X695131Y1110930I-1J200D01*
G02X695067Y1111024I127J155D01*
G01X695064Y1111037D01*
G03X692534Y1111039I-1265J-309D01*
G01Y1111037D01*
X692529Y1111018D01*
G02X692351Y1110885I-189J67D01*
G01X687778D01*
G02X687651Y1110930I-1J200D01*
G02X687587Y1111024I127J155D01*
G01X687584Y1111037D01*
G03X685054Y1111039I-1265J-309D01*
G01Y1111037D01*
X685049Y1111018D01*
G02X684871Y1110885I-189J67D01*
G01X684038D01*
G02X683911Y1110930I-1J200D01*
G02X683847Y1111024I127J155D01*
G01X683844Y1111037D01*
G03X681314Y1111039I-1265J-309D01*
G01Y1111037D01*
X681309Y1111018D01*
G02X681131Y1110885I-189J67D01*
G01X680297D01*
G02X680170Y1110930I-1J200D01*
G02X680106Y1111024I127J155D01*
G01X680103Y1111037D01*
G03X677573Y1111039I-1265J-309D01*
G01Y1111037D01*
X677568Y1111018D01*
G02X677390Y1110885I-189J67D01*
G01X676557D01*
G02X676430Y1110930I-1J200D01*
G02X676366Y1111024I127J155D01*
G01X676363Y1111037D01*
G03X673833Y1111039I-1265J-309D01*
G01Y1111037D01*
X673828Y1111018D01*
G02X673650Y1110885I-189J67D01*
G01X672817D01*
G02X672690Y1110930I-1J200D01*
G02X672626Y1111024I127J155D01*
G01X672623Y1111037D01*
G03X670093Y1111039I-1265J-309D01*
G01Y1111037D01*
X670088Y1111018D01*
G02X669910Y1110885I-189J67D01*
G01X669077D01*
G02X668950Y1110930I-1J200D01*
G02X668886Y1111024I127J155D01*
G01X668883Y1111037D01*
G03X666353Y1111039I-1265J-309D01*
G01Y1111037D01*
X666348Y1111018D01*
G02X666170Y1110885I-189J67D01*
G01X665337D01*
G02X665210Y1110930I-1J200D01*
G02X665146Y1111024I127J155D01*
G01X665143Y1111037D01*
G03X662613Y1111039I-1265J-309D01*
G01Y1111037D01*
X662608Y1111018D01*
G02X662430Y1110885I-189J67D01*
G01X661597D01*
G02X661470Y1110930I-1J200D01*
G02X661406Y1111024I127J155D01*
G01X661403Y1111037D01*
G03X658873Y1111039I-1265J-309D01*
G01Y1111037D01*
X658868Y1111018D01*
G02X658690Y1110885I-189J67D01*
G01X657857D01*
G02X657730Y1110930I-1J200D01*
G02X657666Y1111024I127J155D01*
G01X657663Y1111037D01*
G03X655133Y1111039I-1265J-309D01*
G01Y1111037D01*
X655128Y1111018D01*
G02X654950Y1110885I-189J67D01*
G01X654116D01*
G02X653989Y1110930I-1J200D01*
G02X653925Y1111024I127J155D01*
G01X653922Y1111037D01*
G03X651392Y1111039I-1265J-309D01*
G01Y1111037D01*
X651387Y1111018D01*
G02X651209Y1110885I-189J67D01*
G01X650376D01*
G02X650249Y1110930I-1J200D01*
G02X650185Y1111024I127J155D01*
G01X650182Y1111037D01*
G03X647652Y1111039I-1265J-309D01*
G01Y1111037D01*
X647647Y1111018D01*
G02X647469Y1110885I-189J67D01*
G01X646636D01*
G02X646509Y1110930I-1J200D01*
G02X646445Y1111024I127J155D01*
G01X646442Y1111037D01*
G03X643912Y1111039I-1265J-309D01*
G01Y1111037D01*
X643907Y1111018D01*
G02X643729Y1110885I-189J67D01*
G01X642896D01*
G02X642769Y1110930I-1J200D01*
G02X642705Y1111024I127J155D01*
G01X642702Y1111037D01*
G03X640172Y1111039I-1265J-309D01*
G01Y1111037D01*
X640167Y1111018D01*
G02X639989Y1110885I-189J67D01*
G01X639156D01*
G02X639029Y1110930I-1J200D01*
G02X638965Y1111024I127J155D01*
G01X638962Y1111037D01*
G03X636432Y1111039I-1265J-309D01*
G01Y1111037D01*
X636427Y1111018D01*
G02X636249Y1110885I-189J67D01*
G01X635416D01*
G02X635289Y1110930I-1J200D01*
G02X635225Y1111024I127J155D01*
G01X635222Y1111037D01*
G03X632692Y1111039I-1265J-309D01*
G01Y1111037D01*
X632687Y1111018D01*
G02X632509Y1110885I-189J67D01*
G01X631675D01*
G02X631548Y1110930I-1J200D01*
G02X631484Y1111024I127J155D01*
G01X631481Y1111037D01*
G03X628951Y1111039I-1265J-309D01*
G01Y1111037D01*
X628946Y1111018D01*
G02X628768Y1110885I-189J67D01*
G01X627935D01*
G02X627808Y1110930I-1J200D01*
G02X627744Y1111024I127J155D01*
G01X627741Y1111037D01*
G03X625211Y1111039I-1265J-309D01*
G01Y1111037D01*
X625206Y1111018D01*
G02X625028Y1110885I-189J67D01*
G01X624195D01*
G02X624068Y1110930I-1J200D01*
G02X624004Y1111024I127J155D01*
G01X624001Y1111037D01*
G03X621471Y1111039I-1265J-309D01*
G01Y1111037D01*
X621466Y1111018D01*
G02X621288Y1110885I-189J67D01*
G01X620455D01*
G02X620328Y1110930I-1J200D01*
G02X620264Y1111024I127J155D01*
G01X620261Y1111037D01*
G03X617731Y1111039I-1265J-309D01*
G01Y1111037D01*
X617726Y1111018D01*
G02X617548Y1110885I-189J67D01*
G01X616715D01*
G02X616588Y1110930I-1J200D01*
G02X616524Y1111024I127J155D01*
G01X616521Y1111037D01*
G03X613991Y1111039I-1265J-309D01*
G01Y1111037D01*
X613986Y1111018D01*
G02X613808Y1110885I-189J67D01*
G01X612975D01*
G02X612848Y1110930I-1J200D01*
G02X612784Y1111024I127J155D01*
G01X612781Y1111037D01*
G03X610251Y1111039I-1265J-309D01*
G01Y1111037D01*
X610246Y1111018D01*
G02X610068Y1110885I-189J67D01*
G01X609235D01*
G02X609108Y1110930I-1J200D01*
G02X609044Y1111024I127J155D01*
G01X609041Y1111037D01*
G03X607776Y1112030I-1265J-309D01*
G03X607350Y1111958I1J-1302D01*
G01X607349D01*
G02X607239Y1111952I-65J189D01*
G01X607213Y1111958D01*
X607189Y1111971D01*
G02X607144Y1112005I97J175D01*
G01X605324Y1113825D01*
G02X605280Y1113892I142J141D01*
G01X605266Y1113926D01*
Y1114013D01*
X605268Y1114027D01*
X605273Y1114065D01*
X605278Y1114081D01*
G03X605337Y1114466I-1243J388D01*
G01Y1114468D01*
G03X604035Y1115770I-1302J0D01*
G01X604032D01*
G03X603610Y1115699I2J-1302D01*
G01X603608D01*
X603607Y1115698D01*
G02X603402Y1115747I-63J190D01*
G01X601584Y1117565D01*
G02X601540Y1117632I142J141D01*
G01X601526Y1117666D01*
Y1117753D01*
X601528Y1117767D01*
X601533Y1117805D01*
X601538Y1117821D01*
G03X601597Y1118206I-1243J388D01*
G01Y1118208D01*
G03X600295Y1119510I-1302J0D01*
G01X600292D01*
G03X599870Y1119439I2J-1302D01*
G01X599868D01*
X599867Y1119438D01*
G02X599662Y1119487I-63J190D01*
G01X599174Y1119975D01*
G02X599169Y1119980I139J144D01*
G01X599143Y1120039D01*
X599126Y1120080D01*
Y1120422D01*
G02X599135Y1120481I200J0D01*
G01X599144Y1120510D01*
X599172Y1120572D01*
G02X599196Y1120593I143J-140D01*
G01X599209Y1120603D01*
X599512Y1120789D01*
X599569Y1120790D01*
X599630D01*
G02X599656Y1120788I-2J-200D01*
G01X599736Y1120771D01*
X599756Y1120762D01*
G03X600293Y1120646I537J1186D01*
G01X600295D01*
G03Y1123250I0J1302D01*
G01X600293D01*
G03X599698Y1123106I0J-1302D01*
G01X599697D01*
G02X599599Y1123084I-91J178D01*
G01X599547Y1123086D01*
X599232Y1123279D01*
G02X599195Y1123308I104J171D01*
G01X599160Y1123343D01*
X599145Y1123379D01*
X599126Y1123418D01*
Y1124162D01*
G02X599135Y1124221I200J0D01*
G01X599144Y1124250D01*
X599172Y1124312D01*
G02X599196Y1124333I143J-140D01*
G01X599209Y1124343D01*
X599512Y1124529D01*
X599569Y1124530D01*
X599630D01*
G02X599656Y1124528I-2J-200D01*
G01X599736Y1124511D01*
X599756Y1124502D01*
G03X600293Y1124386I537J1186D01*
G01X600295D01*
G03Y1126990I0J1302D01*
G01X600293D01*
G03X599698Y1126846I0J-1302D01*
G01X599697D01*
G02X599599Y1126824I-91J178D01*
G01X599547Y1126826D01*
X599232Y1127019D01*
G02X599195Y1127048I104J171D01*
G01X599160Y1127083D01*
X599145Y1127119D01*
X599126Y1127158D01*
Y1127903D01*
G02X599135Y1127962I200J0D01*
G01X599144Y1127991D01*
X599172Y1128053D01*
G02X599196Y1128074I143J-140D01*
G01X599209Y1128084D01*
X599512Y1128270D01*
X599569Y1128271D01*
X599630D01*
G02X599656Y1128269I-2J-200D01*
G01X599736Y1128252D01*
X599756Y1128243D01*
G03X600293Y1128127I537J1186D01*
G01X600295D01*
G03Y1130731I0J1302D01*
G01X600293D01*
G03X599698Y1130587I0J-1302D01*
G01X599697D01*
G02X599599Y1130565I-91J178D01*
G01X599547Y1130567D01*
X599232Y1130760D01*
G02X599195Y1130789I104J171D01*
G01X599160Y1130824D01*
X599145Y1130860D01*
X599126Y1130899D01*
Y1131643D01*
G02X599135Y1131702I200J0D01*
G01X599144Y1131731D01*
X599172Y1131793D01*
G02X599196Y1131814I143J-140D01*
G01X599209Y1131824D01*
X599512Y1132010D01*
X599569Y1132011D01*
X599630D01*
G02X599656Y1132009I-2J-200D01*
G01X599736Y1131992D01*
X599756Y1131983D01*
G03X600293Y1131867I537J1186D01*
G01X600295D01*
G03Y1134471I0J1302D01*
G01X600293D01*
G03X599698Y1134327I0J-1302D01*
G01X599697D01*
G02X599599Y1134305I-91J178D01*
G01X599547Y1134307D01*
X599232Y1134500D01*
G02X599195Y1134529I104J171D01*
G01X599160Y1134564D01*
X599145Y1134600D01*
X599126Y1134639D01*
Y1135383D01*
G02X599135Y1135442I200J0D01*
G01X599144Y1135471D01*
X599172Y1135533D01*
G02X599196Y1135554I143J-140D01*
G01X599209Y1135564D01*
X599512Y1135750D01*
X599569Y1135751D01*
X599630D01*
G02X599656Y1135749I-2J-200D01*
G01X599736Y1135732D01*
X599756Y1135723D01*
G03X600293Y1135607I537J1186D01*
G01X600295D01*
G03Y1138211I0J1302D01*
G01X600293D01*
G03X599698Y1138067I0J-1302D01*
G01X599697D01*
G02X599599Y1138045I-91J178D01*
G01X599547Y1138047D01*
X599232Y1138240D01*
G02X599195Y1138269I104J171D01*
G01X599160Y1138304D01*
X599145Y1138340D01*
X599126Y1138379D01*
Y1139123D01*
G02X599135Y1139182I200J0D01*
G01X599144Y1139211D01*
X599172Y1139273D01*
G02X599196Y1139294I143J-140D01*
G01X599209Y1139304D01*
X599512Y1139490D01*
X599569Y1139491D01*
X599630D01*
G02X599656Y1139489I-2J-200D01*
G01X599736Y1139472D01*
X599756Y1139463D01*
G03X600293Y1139347I537J1186D01*
G01X600295D01*
G03Y1141951I0J1302D01*
G01X600293D01*
G03X599698Y1141807I0J-1302D01*
G01X599697D01*
G02X599599Y1141785I-91J178D01*
G01X599547Y1141787D01*
X599232Y1141980D01*
G02X599195Y1142009I104J171D01*
G01X599160Y1142044D01*
X599145Y1142080D01*
X599126Y1142119D01*
Y1142863D01*
G02X599135Y1142922I200J0D01*
G01X599144Y1142951D01*
X599172Y1143013D01*
G02X599196Y1143034I143J-140D01*
G01X599209Y1143044D01*
X599512Y1143230D01*
X599569Y1143231D01*
X599630D01*
G02X599656Y1143229I-2J-200D01*
G01X599736Y1143212D01*
X599756Y1143203D01*
G03X600293Y1143087I537J1186D01*
G01X600295D01*
G03Y1145691I0J1302D01*
G01X600293D01*
G03X599698Y1145547I0J-1302D01*
G01X599697D01*
G02X599599Y1145525I-91J178D01*
G01X599547Y1145527D01*
X599232Y1145720D01*
G02X599195Y1145749I104J171D01*
G01X599160Y1145784D01*
X599145Y1145820D01*
X599126Y1145859D01*
Y1146603D01*
G02X599135Y1146662I200J0D01*
G01X599144Y1146691D01*
X599172Y1146753D01*
G02X599196Y1146774I143J-140D01*
G01X599209Y1146784D01*
X599512Y1146970D01*
X599569Y1146971D01*
X599630D01*
G02X599656Y1146969I-2J-200D01*
G01X599736Y1146952D01*
X599756Y1146943D01*
G03X600293Y1146827I537J1186D01*
G01X600295D01*
G03Y1149431I0J1302D01*
G01X600293D01*
G03X599698Y1149287I0J-1302D01*
G01X599697D01*
G02X599599Y1149265I-91J178D01*
G01X599547Y1149267D01*
X599232Y1149460D01*
G02X599195Y1149489I104J171D01*
G01X599160Y1149524D01*
X599145Y1149560D01*
X599126Y1149599D01*
Y1150344D01*
G02X599135Y1150403I200J0D01*
G01X599144Y1150432D01*
X599172Y1150494D01*
G02X599196Y1150515I143J-140D01*
G01X599209Y1150525D01*
X599512Y1150711D01*
X599569Y1150712D01*
X599630D01*
G02X599656Y1150710I-2J-200D01*
G01X599736Y1150693D01*
X599756Y1150684D01*
G03X600293Y1150568I537J1186D01*
G01X600295D01*
G03Y1153172I0J1302D01*
G01X600293D01*
G03X599698Y1153028I0J-1302D01*
G01X599697D01*
G02X599599Y1153006I-91J178D01*
G01X599547Y1153008D01*
X599232Y1153201D01*
G02X599195Y1153230I104J171D01*
G01X599160Y1153265D01*
X599145Y1153301D01*
X599126Y1153340D01*
Y1157824D01*
G02X599135Y1157883I200J0D01*
G01X599144Y1157912D01*
X599172Y1157974D01*
G02X599196Y1157995I143J-140D01*
G01X599209Y1158005D01*
X599512Y1158191D01*
X599569Y1158192D01*
X599630D01*
G02X599656Y1158190I-2J-200D01*
G01X599736Y1158173D01*
X599756Y1158164D01*
G03X600293Y1158048I537J1186D01*
G01X600295D01*
G03Y1160652I0J1302D01*
G01X600293D01*
G03X599698Y1160508I0J-1302D01*
G01X599697D01*
G02X599599Y1160486I-91J178D01*
G01X599547Y1160488D01*
X599232Y1160681D01*
G02X599195Y1160710I104J171D01*
G01X599160Y1160745D01*
X599145Y1160781D01*
X599126Y1160820D01*
Y1169049D01*
G02X599139Y1169119I200J-1D01*
G01X599183Y1169236D01*
G03X599191Y1169265I-188J68D01*
G01X599198Y1169297D01*
G02X599321Y1169442I196J-41D01*
G01X599470Y1169500D01*
X599562Y1169491D01*
X599603Y1169466D01*
G03X600293Y1169268I690J1104D01*
G01X604034D01*
G03Y1171872I0J1302D01*
G01X600293D01*
G03X599786Y1171769I1J-1302D01*
G02X599597Y1171786I-79J184D01*
G01X599330Y1171964D01*
G02X599240Y1172130I110J167D01*
G01Y1173457D01*
G02X599299Y1173599I200J0D01*
G01X602390Y1176689D01*
G02X602532Y1176748I142J-141D01*
G01X604034D01*
G03X605336Y1178050I0J1302D01*
G01Y1178052D01*
G03X604955Y1178972I-1302J0D01*
G01X604954Y1178973D01*
G02X604955Y1179255I142J140D01*
G01X606971Y1181271D01*
G02X607113Y1181330I142J-141D01*
G01X611011D01*
G03X613715Y1182450I-1J3826D01*
G01X613794Y1182530D01*
X613832Y1182545D01*
G03X614502Y1183215I-446J1116D01*
G01X614517Y1183253D01*
X614597Y1183332D01*
G03X615097Y1183949I-2707J2705D01*
G02X615171Y1184016I167J-110D01*
G03X615324Y1184102I-1798J3378D01*
G02X615530Y1184100I101J-172D01*
G01X615831Y1183916D01*
G02X615926Y1183734I-105J-170D01*
G01Y1183733D01*
G03X615924Y1183661I1200J-69D01*
G03X617126Y1184863I1202J0D01*
G03X617054Y1184861I-3J-1202D01*
G01X617053D01*
G02X616871Y1184956I-12J200D01*
G01X616687Y1185257D01*
G02X616685Y1185463I170J105D01*
G03X617020Y1186204I-3299J1938D01*
G03X617126Y1186199I110J1197D01*
G03Y1188603I0J1202D01*
G03X617020Y1188598I4J-1202D01*
G03X616685Y1189339I-3634J-1197D01*
G02X616687Y1189545I172J101D01*
G01X616871Y1189846D01*
G02X617053Y1189941I170J-105D01*
G01X617054D01*
G03X617126Y1189939I69J1200D01*
G03X618328Y1191141I0J1202D01*
G03X618025Y1191939I-1202J0D01*
G01X618001Y1191966D01*
X617975Y1192034D01*
Y1192192D01*
G02X618034Y1192334I200J0D01*
G01X618441Y1192741D01*
G03X618500Y1192883I-141J142D01*
G01Y1226017D01*
G02X618559Y1226159I200J0D01*
G01X619341Y1226941D01*
G02X619483Y1227000I142J-141D01*
G01X751917D01*
G02X752059Y1226941I0J-200D01*
G01X754170Y1224830D01*
G02X754228Y1224705I-141J-142D01*
G01Y1224704D01*
G03X755413Y1223519I1284J99D01*
G01X755414D01*
G02X755539Y1223461I-17J-199D01*
G01X758008Y1220992D01*
G02X758064Y1220881I-142J-141D01*
G03X759071Y1219874I1188J181D01*
G02X759182Y1219818I-30J-198D01*
G01X759264Y1219736D01*
G02X759323Y1219594I-141J-142D01*
G01Y1218879D01*
G02X759270Y1218744I-200J1D01*
G01X759193Y1218660D01*
G02X759074Y1218597I-148J135D01*
G03Y1216047I178J-1275D01*
G01X759109Y1216042D01*
X759169Y1216010D01*
X759273Y1215897D01*
G02X759326Y1215762I-147J-136D01*
G01Y1215056D01*
G02X759274Y1214921I-200J0D01*
G01X759170Y1214808D01*
X759110Y1214776D01*
X759076Y1214771D01*
G03Y1212393I176J-1189D01*
G01X759110Y1212388D01*
X759170Y1212356D01*
X759274Y1212243D01*
G02X759326Y1212108I-148J-135D01*
G01Y1211402D01*
G02X759273Y1211267I-200J1D01*
G01X759193Y1211180D01*
G02X759074Y1211117I-148J135D01*
G03Y1208567I178J-1275D01*
G01X759109Y1208562D01*
X759169Y1208530D01*
X759273Y1208417D01*
G02X759326Y1208282I-147J-136D01*
G01Y1207576D01*
G02X759274Y1207441I-200J0D01*
G01X759170Y1207328D01*
X759110Y1207296D01*
X759076Y1207291D01*
G03Y1204913I176J-1189D01*
G01X759110Y1204908D01*
X759170Y1204876D01*
X759274Y1204763D01*
G02X759326Y1204628I-148J-135D01*
G01Y1203922D01*
G02X759273Y1203787I-200J1D01*
G01X759193Y1203700D01*
G02X759074Y1203637I-148J135D01*
G03Y1201087I178J-1275D01*
G01X759109Y1201082D01*
X759169Y1201050D01*
X759273Y1200937D01*
G02X759326Y1200802I-147J-136D01*
G01Y1200095D01*
G02X759274Y1199960I-200J0D01*
G01X759170Y1199847D01*
X759110Y1199815D01*
X759076Y1199810D01*
G03Y1197432I176J-1189D01*
G01X759110Y1197427D01*
X759170Y1197395D01*
X759274Y1197282D01*
G02X759326Y1197147I-148J-135D01*
G01Y1192615D01*
G02X759274Y1192480I-200J0D01*
G01X759170Y1192367D01*
X759110Y1192335D01*
X759076Y1192330D01*
G03Y1189952I176J-1189D01*
G01X759110Y1189947D01*
X759170Y1189915D01*
X759274Y1189802D01*
G02X759326Y1189667I-148J-135D01*
G01Y1143137D01*
G02X759304Y1143046I-200J0D01*
G02X759268Y1142996I-178J90D01*
G01X758142Y1141870D01*
G02X758029Y1141817I-137J146D01*
G01X758023D01*
G02X757922Y1141834I-18J199D01*
G01X757917Y1141837D01*
X757906Y1141842D01*
X757905D01*
X757886Y1141850D01*
G03X757736Y1141902I-501J-1202D01*
G01Y1141903D01*
G03X757384Y1141951I-350J-1255D01*
G01X757382D01*
G03X756080Y1140649I0J-1302D01*
G01Y1140647D01*
G03X756185Y1140135I1302J0D01*
G01X756189Y1140126D01*
X756201Y1140089D01*
X756208Y1140055D01*
G02X756173Y1139905I-197J-33D01*
G02X756152Y1139880I-163J116D01*
G01X754402Y1138130D01*
G02X754289Y1138077I-137J146D01*
G01X754283D01*
G02X754182Y1138094I-18J199D01*
G01X754177Y1138097D01*
X754166Y1138102D01*
X754165D01*
X754146Y1138110D01*
G03X753996Y1138162I-501J-1202D01*
G01Y1138163D01*
G03X753644Y1138211I-350J-1255D01*
G01X753642D01*
G03X752369Y1137184I0J-1302D01*
G01X752367Y1137174D01*
X752366Y1137171D01*
X752365Y1137162D01*
X752361Y1137144D01*
X752347Y1137119D01*
G02X752310Y1137071I-175J97D01*
G01X752221Y1136987D01*
G02X752150Y1136950I-126J155D01*
G01X752113Y1136939D01*
X752098Y1136937D01*
G03X751883Y1136904I468J-3767D01*
G03X751801Y1136888I686J-3734D01*
G02X751741I-30J198D01*
G03X751429Y1136939I-768J-3718D01*
G01X751428D01*
X751407Y1136943D01*
X751387Y1136947D01*
X751367Y1136956D01*
G02X751328Y1136980I85J181D01*
G01X751299Y1137006D01*
X751233Y1137070D01*
X751231Y1137072D01*
G02X751196Y1137118I140J143D01*
G01X751184Y1137141D01*
X751176Y1137173D01*
Y1137175D01*
G03X749901Y1138211I-1275J-267D01*
G03X749661Y1138189I-2J-1302D01*
G01X749658D01*
X749640Y1138186D01*
X749551Y1138213D01*
X749285Y1138467D01*
G02X749224Y1138636I137J145D01*
G03X749233Y1138778I-1193J147D01*
G01Y1138780D01*
G03X749212Y1139000I-1202J-4D01*
G01Y1139002D01*
G02X749267Y1139179I197J36D01*
G01X749502Y1139413D01*
G02X749679Y1139468I141J-142D01*
G01X749680D01*
G03X749902Y1139447I224J1181D01*
G03X748700Y1140649I0J1202D01*
G03X748721Y1140428I1202J3D01*
G01Y1140426D01*
G02X748666Y1140249I-197J-36D01*
G01X748431Y1140015D01*
G02X748254Y1139960I-141J142D01*
G01X748253D01*
G03X748031Y1139981I-224J-1181D01*
G03X747811Y1139960I4J-1202D01*
G01X747809D01*
G02X747632Y1140015I-36J197D01*
G01X747397Y1140250D01*
G02X747342Y1140427I142J141D01*
G01Y1140429D01*
G03X747363Y1140649I-1181J224D01*
G03X746161Y1139447I-1202J0D01*
G03X746381Y1139468I-4J1202D01*
G01X746383D01*
G02X746560Y1139413I36J-197D01*
G01X746795Y1139178D01*
G02X746850Y1139001I-142J-141D01*
G01Y1138999D01*
G03X746829Y1138780I1181J-224D01*
G01Y1138778D01*
G03X746838Y1138636I1202J5D01*
G02X746777Y1138467I-198J-24D01*
G01X746511Y1138213D01*
X746422Y1138186D01*
X746402Y1138189D01*
G03X746161Y1138211I-238J-1280D01*
G03X744859Y1136909I0J-1302D01*
G03X746160Y1135607I1302J0D01*
G01X746162D01*
G03X746192Y1135608I-28J1301D01*
G01X746225D01*
G02X746362Y1135553I-1J-200D01*
G01X746389Y1135525D01*
X746579Y1135218D01*
G02X746583Y1135015I-170J-105D01*
G01X746559Y1134970D01*
G03X746515Y1134886I3341J-1803D01*
G03X746405Y1134650I3384J-1721D01*
G01X746393Y1134622D01*
X746377Y1134602D01*
G02X746337Y1134565I-155J127D01*
G02X746333Y1134562I-122J158D01*
G01X746270Y1134520D01*
G02X746262Y1134515I-110J167D01*
G02X746232Y1134500I-104J171D01*
G02X746220Y1134496I-69J188D01*
G01X746141Y1134471D01*
X746114Y1134470D01*
G03Y1131868I47J-1301D01*
G01X746141Y1131867D01*
X746220Y1131842D01*
G02X746232Y1131838I-57J-192D01*
G02X746270Y1131818I-74J-186D01*
G01X746333Y1131776D01*
G02X746337Y1131773I-118J-161D01*
G02X746377Y1131736I-115J-164D01*
G01X746393Y1131717D01*
X746405Y1131690D01*
X746406Y1131686D01*
G03X746417Y1131658I3539J1374D01*
G03X746419Y1131656I142J140D01*
G03X746441Y1131605I3497J1478D01*
G01Y1131604D01*
G03X746449Y1131588I3399J1689D01*
G02X746453Y1131580I-177J-93D01*
G03X746459Y1131566I3492J1488D01*
G01Y1131565D01*
G03X746473Y1131537I3402J1684D01*
G01Y1131535D01*
X746476Y1131531D01*
Y1131529D01*
G03X746477Y1131527I180J89D01*
G02X746479Y1131524I-164J-111D01*
G03X746536Y1131410I3424J1641D01*
G01X746559Y1131366D01*
X746572Y1131342D01*
X746583Y1131297D01*
Y1131184D01*
G02X746553Y1131079I-200J0D01*
G01X746474Y1130953D01*
Y1130951D01*
X746431Y1130881D01*
G02X746429Y1130879I-142J140D01*
G01X746394Y1130823D01*
G02X746232Y1130730I-169J107D01*
G01X746192D01*
G03X746162Y1130731I-58J-1300D01*
G01X746160D01*
G03X744859Y1129429I1J-1302D01*
G03X746161Y1128127I1302J0D01*
G03X746208Y1128128I-4J1302D01*
G01X746230D01*
G02X746393Y1128037I-5J-200D01*
G01X746554Y1127777D01*
X746567Y1127751D01*
G02X746584Y1127672I-183J-81D01*
G37*
G36*
G01X659962Y202336D02*
X663474D01*
G02X663615Y202278I0J-200D01*
G01X665655Y200238D01*
X665670Y200207D01*
G03X665709Y200132I1352J655D01*
G01X665710Y200131D01*
G03X665725Y200105I1308J738D01*
G01X665738Y200083D01*
X665754Y200027D01*
X665767Y199981D01*
Y197600D01*
G02X665734Y197490I-200J0D01*
G03Y195840I1254J-825D01*
G02X665767Y195730I-167J-110D01*
G01Y193600D01*
G02X665734Y193490I-200J0D01*
G03Y191840I1254J-825D01*
G02X665767Y191730I-167J-110D01*
G01Y187518D01*
X665757Y187475D01*
X665746Y187453D01*
G03Y186103I1355J-675D01*
G01X665757Y186081D01*
X665767Y186038D01*
Y181600D01*
G02X665734Y181490I-200J0D01*
G03Y179840I1254J-825D01*
G02X665767Y179730I-167J-110D01*
G01Y177600D01*
G02X665734Y177490I-200J0D01*
G03Y175840I1254J-825D01*
G02X665767Y175730I-167J-110D01*
G01Y173600D01*
G02X665734Y173490I-200J0D01*
G03Y171840I1254J-825D01*
G02X665767Y171730I-167J-110D01*
G01Y169600D01*
G02X665734Y169490I-200J0D01*
G03Y167840I1254J-825D01*
G02X665767Y167730I-167J-110D01*
G01Y163086D01*
G02X665711Y162946I-200J-1D01*
G01X665651Y162885D01*
G02X665596Y162845I-143J139D01*
G01X665507Y162802D01*
X665474Y162798D01*
G03Y159814I180J-1492D01*
G01X665507Y159810D01*
X665596Y159767D01*
G02X665651Y159727I-88J-179D01*
G01X665711Y159666D01*
G02X665767Y159526I-144J-139D01*
G01Y151308D01*
G02X665567Y151108I-200J0D01*
G01X658993D01*
G02X658817Y151213I0J200D01*
G01X658651Y151523D01*
G02X658627Y151625I176J95D01*
G01X658629Y151682D01*
X658660Y151729D01*
G03X658912Y152562I-1251J833D01*
G03X657410Y154064I-1502J0D01*
G03X656116Y153325I0J-1502D01*
G01X656090Y153281D01*
X656005Y153229D01*
X655827Y153219D01*
X655574Y153204D01*
X655484Y153245D01*
X655454Y153285D01*
G03X654260Y153875I-1194J-913D01*
G03X652758Y152373I0J-1502D01*
G03X652923Y151689I1502J0D01*
G01X652947Y151642D01*
X652943Y151539D01*
X652737Y151203D01*
G02X652567Y151108I-170J105D01*
G01X643249D01*
G02X643121Y151155I1J200D01*
G01X642288Y151988D01*
X641983Y152292D01*
G03X640568Y152878I-1415J-1415D01*
G01X634208D01*
G03X632793Y152292I0J-2001D01*
G01X629456Y148955D01*
G03X628870Y147540I1415J-1415D01*
G03X628878Y147354I2001J-7D01*
G01X628879Y147345D01*
Y147340D01*
G03X630866Y145538I1992J200D01*
G01X630871D01*
G03X631373Y145602I0J2002D01*
G03X632286Y146125I-503J1937D01*
G01X634978Y148817D01*
G02X635120Y148876I142J-141D01*
G01X637598D01*
G02X637747Y148809I0J-200D01*
G01X637946Y148588D01*
G02X637996Y148437I-149J-133D01*
G01Y148434D01*
G03X637988Y148277I1494J-155D01*
G03X639490Y146775I1502J0D01*
G03X640679Y147359I0J1502D01*
G01X640703Y147390D01*
X640736Y147410D01*
G02X640806Y147435I101J-173D01*
G01X641075Y147479D01*
G02X641219Y147447I32J-198D01*
G01X641220Y147446D01*
G03X641684Y147214I1120J1659D01*
G03X642339Y147104I654J1892D01*
G01X665567D01*
G02X665767Y146904I0J-200D01*
G01Y124540D01*
X665764Y124524D01*
G03X665745Y124283I1483J-238D01*
G03X665764Y124042I1502J-3D01*
G01X665767Y124026D01*
Y120792D01*
G02X665753Y120718I-200J0D01*
G01X665715Y120621D01*
X665691Y120594D01*
G03Y118594I1122J-1000D01*
G01X665715Y118567D01*
X665753Y118470D01*
G02X665767Y118396I-186J-74D01*
G01Y117752D01*
X665713Y117618D01*
X665690Y117592D01*
G03X665311Y116594I1124J-998D01*
G01Y116592D01*
G03X665615Y115687I1503J1D01*
G02X665655Y115567I-160J-120D01*
G01Y114421D01*
G02X665615Y114301I-200J0D01*
G03Y112487I1199J-907D01*
G02X665655Y112367I-160J-120D01*
G01Y111688D01*
G03X665685Y111583I200J0D01*
G01X665736Y111504D01*
G02X665767Y111396I-169J-107D01*
G01Y109734D01*
G02X665708Y109592I-200J0D01*
G01X664765Y108649D01*
G02X664623Y108590I-142J141D01*
G01X627951D01*
G02X627787Y108676I0J200D01*
G03X624823I-1482J-1027D01*
G02X624659Y108590I-164J114D01*
G01X608378D01*
G02X608236Y108649I0J200D01*
G01X607177Y109708D01*
X607152Y109753D01*
X607145Y109780D01*
G03X606059Y110866I-1456J-370D01*
G01X606032Y110873D01*
X605987Y110898D01*
X605925Y110960D01*
G02X605866Y111102I141J142D01*
G01Y114907D01*
X605953Y115016D01*
X606022Y115031D01*
G03Y117961I-333J1465D01*
G01X605953Y117976D01*
X605866Y118085D01*
Y122963D01*
X605966Y123076D01*
X606042Y123085D01*
G03Y126067I-181J1491D01*
G01X605966Y126076D01*
X605866Y126189D01*
Y159263D01*
G02X605925Y159405I200J0D01*
G01X606788Y160268D01*
G02X606930Y160327I142J-141D01*
G01X642447D01*
G03X642589Y160386I0J200D01*
G01X646294Y164091D01*
G03X646353Y164233I-141J142D01*
G01Y201567D01*
G02X646412Y201709I200J0D01*
G01X646980Y202277D01*
G02X647122Y202336I142J-141D01*
G01X656822D01*
G02X656999Y202229I0J-200D01*
G01X657163Y201916D01*
G02X657152Y201711I-177J-93D01*
G01X657151Y201710D01*
G03X656890Y200873I1241J-846D01*
G01Y200845D01*
G03X659894I1502J19D01*
G01Y200865D01*
G03X659633Y201711I-1502J0D01*
G01X659601Y201757D01*
X659595Y201867D01*
X659785Y202229D01*
G02X659962Y202336I177J-93D01*
G37*
G36*
G01X697106Y54588D02*
X725589D01*
X725942Y54235D01*
Y52944D01*
X725589Y52591D01*
X697106D01*
G03X691169Y46654I0J-5937D01*
G01Y7874D01*
G02X685295Y2000I-5874J0D01*
G01X638051D01*
G02X632177Y7874I0J5874D01*
G01Y45760D01*
X634174D01*
Y7874D01*
G03X638049Y3998I3876J0D01*
G01X685295D01*
G03X689172Y7874I0J3877D01*
G01Y46654D01*
G02X697106Y54588I7934J0D01*
G37*
G36*
G01X624603Y1242201D02*
X624606D01*
G03X625908Y1243503I0J1302D01*
G03X624844Y1244783I-1302J0D01*
G02X624681Y1244963I36J197D01*
G03X624631Y1245337I-3814J-319D01*
G02Y1245409I197J36D01*
G03X624681Y1245783I-3764J693D01*
G02X624844Y1245963I199J-17D01*
G03X624923Y1245980I-234J1281D01*
G02X625172Y1245786I49J-194D01*
G01Y1245373D01*
G03X626474Y1244071I1302J0D01*
G03X626700Y1244091I-1J1302D01*
G01X626703D01*
X626737Y1244097D01*
X626826Y1244069D01*
X627127Y1243783D01*
X627159Y1243693D01*
X627153Y1243647D01*
G03X627144Y1243503I1193J-147D01*
G03X628346Y1244705I1202J0D01*
G03X628201Y1244696I2J-1202D01*
G01X628154Y1244690D01*
X628066Y1244722D01*
X627778Y1245022D01*
X627751Y1245111D01*
X627755Y1245138D01*
G03X627776Y1245373I-1281J233D01*
G01Y1245650D01*
G02X627842Y1245799I200J0D01*
G01X628096Y1246026D01*
X628176Y1246052D01*
X628218Y1246048D01*
G03X628346Y1246041I130J1195D01*
G03Y1248445I0J1202D01*
G03X628029Y1248403I-2J-1202D01*
G01X628003Y1248395D01*
X627976D01*
G02X627777Y1248595I1J200D01*
G01Y1248782D01*
G02X627809Y1248890I200J0D01*
G01Y1248891D01*
G03X628155Y1249557I-3206J2089D01*
G02X628342Y1249682I186J-75D01*
G01X628346D01*
G03X629648Y1250984I0J1302D01*
G03X628582Y1252264I-1301J0D01*
G02X628419Y1252444I36J197D01*
G03X628370Y1252818I-3814J-309D01*
G02Y1252890I196J36D01*
G03X628419Y1253264I-3765J683D01*
G02X628582Y1253444I199J-17D01*
G03X629648Y1254724I-235J1280D01*
G03X628346Y1256026I-1302J0D01*
G01X628342D01*
G02X628155Y1256152I-1J200D01*
G03X627755Y1256898I-3552J-1424D01*
G02X627728Y1256956I165J112D01*
G03X627141Y1257713I-1250J-364D01*
G02X627057Y1257813I103J172D01*
G01X627015Y1257921D01*
G02X627012Y1258058I186J73D01*
G03X627218Y1259312I-3721J1255D01*
G01Y1261317D01*
G02X627230Y1261385I200J0D01*
G01X627484Y1262094D01*
G02X627531Y1262168I188J-68D01*
G01X685828Y1320465D01*
G03X685887Y1320607I-141J142D01*
G01Y1341630D01*
G02X685914Y1341730I200J0D01*
G01X686091Y1341988D01*
X687549Y1344114D01*
G03X687574Y1344151I-3212J2197D01*
G02X687577Y1344155I161J-118D01*
G03X687591Y1344177I-3276J2100D01*
G02X687595Y1344181I143J-139D01*
G03X687598Y1344185I-3112J2337D01*
G03X687604Y1344195I-169J108D01*
G03X687617Y1344215I-3256J2131D01*
G01X687628Y1344232D01*
G03X687637Y1344246I-3269J2111D01*
G01X687755Y1344331D01*
X687780Y1344338D01*
G03X688812Y1345691I-371J1353D01*
G03X688734Y1346152I-1401J0D01*
G01Y1346153D01*
G02X688757Y1346330I189J65D01*
G01X688948Y1346599D01*
G02X688966Y1346622I166J-111D01*
G02X689110Y1346684I145J-138D01*
G01X690888D01*
G03X691379Y1346767I-2J1503D01*
G01X691411Y1346778D01*
X691588D01*
G03Y1349784I0J1503D01*
G01X689141D01*
G02X688988Y1349856I1J200D01*
G01X688766Y1350150D01*
X688761Y1350156D01*
X688744Y1350249D01*
X688749Y1350265D01*
G03X688812Y1350681I-1340J416D01*
G01Y1350683D01*
G03X688320Y1351750I-1403J0D01*
G02X688260Y1351839I130J152D01*
G02X688250Y1351902I190J62D01*
G01Y1356384D01*
G02X688260Y1356447I200J1D01*
G02X688320Y1356536I190J-63D01*
G03X688812Y1357603I-911J1067D01*
G03X688734Y1358064I-1401J0D01*
G01Y1358065D01*
G02X688757Y1358242I189J65D01*
G01X688948Y1358511D01*
G02X688966Y1358534I166J-111D01*
G02X689110Y1358596I145J-138D01*
G01X690888D01*
G03X691379Y1358679I-2J1503D01*
G01X691411Y1358690D01*
X691588D01*
G03Y1361696I0J1503D01*
G01X689141D01*
G02X688988Y1361768I1J200D01*
G01X688766Y1362062D01*
X688761Y1362068D01*
X688744Y1362161D01*
X688749Y1362177D01*
G03X688812Y1362593I-1340J416D01*
G01Y1362595D01*
G03X688628Y1363289I-1401J0D01*
G01X688602Y1363335D01*
X688594Y1363348D01*
X688603Y1363413D01*
G02X688660Y1363528I198J-27D01*
G01X692392Y1367260D01*
G03X693355Y1368851I-2752J2752D01*
G01X693361Y1368871D01*
X693404Y1368946D01*
X693413Y1368956D01*
G03X693665Y1369363I-1049J931D01*
G01X693681Y1369400D01*
X695105Y1370824D01*
G02X695158Y1370862I141J-141D01*
G02X695174Y1370869I88J-180D01*
G01X695188Y1370874D01*
G02X695242Y1370882I56J-192D01*
G01X695430D01*
G03X696932Y1372385I0J1502D01*
G03X696924Y1372540I-1502J0D01*
G01Y1372541D01*
G02X696981Y1372701I199J19D01*
G01X697950Y1373670D01*
G02X698198Y1373698I142J-141D01*
G01X698199Y1373697D01*
G03X698262Y1373659I755J1181D01*
G01X698296Y1373640D01*
X698346Y1373578D01*
X698444Y1373229D01*
X698435Y1373151D01*
X698415Y1373116D01*
G03X698226Y1372388I1313J-730D01*
G01Y1372385D01*
G03X699728Y1370882I1503J0D01*
G01X703128D01*
G03Y1373888I0J1503D01*
G01X700651D01*
G02X700488Y1373972I0J200D01*
G01X700271Y1374278D01*
X700258Y1374373D01*
X700274Y1374419D01*
G03X700352Y1374879I-1324J461D01*
G01Y1374881D01*
G03X700134Y1375632I-1403J0D01*
G01X700133Y1375633D01*
G02X700161Y1375881I169J106D01*
G01X703027Y1378747D01*
G03X703086Y1378889I-141J142D01*
G01Y1380918D01*
G02X703091Y1380961I200J-1D01*
G02X703114Y1381017I195J-47D01*
G03X703301Y1381420I-1162J784D01*
G03X703354Y1381790I-1349J382D01*
G01Y1381803D01*
G03X703276Y1382263I-1402J-1D01*
G01Y1382264D01*
G02X703266Y1382345I189J64D01*
G01X703267Y1382353D01*
G02X703303Y1382446I199J-23D01*
G01X703475Y1382689D01*
X703496Y1382718D01*
G02X703501Y1382724I156J-125D01*
G02X703605Y1382788I152J-130D01*
G02X703653Y1382794I49J-194D01*
G01X706130D01*
G03Y1385800I0J1503D01*
G01X704301D01*
G02X704267Y1385803I1J200D01*
G01X704219Y1385811D01*
G03X703728Y1385894I-493J-1420D01*
G01X703586D01*
G02X703424Y1385977I0J200D01*
G01X703416Y1385988D01*
X703299Y1386153D01*
G02X703266Y1386239I165J113D01*
G01X703260Y1386285D01*
X703276Y1386331D01*
G03X703333Y1386551I-1324J460D01*
G03X703354Y1386783I-1381J242D01*
G01Y1386804D01*
G03X703346Y1386945I-1402J-9D01*
G03X703124Y1387563I-1393J-151D01*
G01X703114Y1387579D01*
X703091Y1387633D01*
G02X703086Y1387676I195J44D01*
G01Y1394880D01*
G02X703286Y1395080I200J0D01*
G01X703728D01*
G03Y1398086I0J1503D01*
G01X703286D01*
G02X703086Y1398286I0J200D01*
G01Y1406792D01*
G02X703286Y1406992I200J0D01*
G01X703728D01*
G03Y1409998I0J1503D01*
G01X703286D01*
G02X703086Y1410198I0J200D01*
G01Y1596933D01*
G02X703145Y1597075I200J0D01*
G01X704824Y1598754D01*
G03X705206Y1599676I-924J923D01*
G01Y1624003D01*
G03X704824Y1624925I-1306J-1D01*
G01X703145Y1626604D01*
G02X703086Y1626746I141J142D01*
G01Y1627784D01*
G02X703209Y1627968I200J-1D01*
G02X703428Y1627925I78J-184D01*
G01X709135Y1622218D01*
G02X709194Y1622076I-141J-142D01*
G01Y1618426D01*
G02X709089Y1618249I-200J-1D01*
G01X708778Y1618083D01*
G02X708573Y1618092I-95J176D01*
G03X707520Y1618408I-1053J-1596D01*
G03Y1614584I0J-1912D01*
G03X708573Y1614900I0J1912D01*
G02X708778Y1614909I110J-167D01*
G01X709089Y1614743D01*
G02X709194Y1614566I-95J-176D01*
G01Y1613308D01*
G02X709089Y1613131I-200J-1D01*
G01X708778Y1612965D01*
G02X708573Y1612974I-95J176D01*
G03X707520Y1613290I-1053J-1596D01*
G03Y1609466I0J-1912D01*
G03X708573Y1609782I0J1912D01*
G02X708778Y1609791I110J-167D01*
G01X709089Y1609625D01*
G02X709194Y1609448I-95J-176D01*
G01Y1603072D01*
G02X709089Y1602895I-200J-1D01*
G01X708778Y1602729D01*
G02X708573Y1602738I-95J176D01*
G03X707520Y1603054I-1053J-1596D01*
G03Y1599230I0J-1912D01*
G03X708573Y1599546I0J1912D01*
G02X708778Y1599555I110J-167D01*
G01X709089Y1599389D01*
G02X709194Y1599212I-95J-176D01*
G01Y1597954D01*
G02X709089Y1597777I-200J-1D01*
G01X708778Y1597611D01*
G02X708573Y1597620I-95J176D01*
G03X707520Y1597936I-1053J-1596D01*
G03Y1594112I0J-1912D01*
G03X708573Y1594428I0J1912D01*
G02X708778Y1594437I110J-167D01*
G01X709089Y1594271D01*
G02X709194Y1594094I-95J-176D01*
G01Y1589392D01*
G02X709135Y1589250I-200J0D01*
G01X707643Y1587759D01*
G02X707504Y1587700I-142J141D01*
G01X707503D01*
G03X705608Y1585788I17J-1912D01*
G03X707520Y1583876I1912J0D01*
G03X709432Y1585771I0J1912D01*
G01Y1585772D01*
G02X709491Y1585911I200J-3D01*
G01X711424Y1587844D01*
G03X711806Y1588766I-924J923D01*
G01Y1622702D01*
G03X711424Y1623624I-1306J-1D01*
G01X703145Y1631903D01*
G02X703086Y1632045I141J142D01*
G01Y1642545D01*
G03X703027Y1642687I-200J0D01*
G01X701236Y1644478D01*
G02X701177Y1644620I141J142D01*
G01Y1645138D01*
G02X701236Y1645280I200J0D01*
G01X701490Y1645534D01*
G02X701632Y1645593I142J-141D01*
G01X789787D01*
G02X789929Y1645534I0J-200D01*
G01X791985Y1643478D01*
G02X792044Y1643336I-141J-142D01*
G01Y1634312D01*
G02X791985Y1634170I-200J0D01*
G01X790861Y1633046D01*
G02X790719Y1632987I-142J141D01*
G01X739878D01*
G02X739700Y1633095I0J200D01*
G01X739511Y1633461D01*
X739519Y1633572D01*
X739551Y1633618D01*
G03X739827Y1634485I-1226J868D01*
G03X736823I-1502J0D01*
G03X737099Y1633618I1502J1D01*
G01X737131Y1633572D01*
X737139Y1633461D01*
X736950Y1633095D01*
G02X736772Y1632987I-178J92D01*
G01X730284D01*
G03X730142Y1632928I0J-200D01*
G01X726101Y1628887D01*
G03X726042Y1628745I141J-142D01*
G01Y1430471D01*
G03X726101Y1430329I200J0D01*
G01X737996Y1418434D01*
G03X738138Y1418375I142J141D01*
G01X779544D01*
G02X779686Y1418316I0J-200D01*
G01X793632D01*
G02X793804Y1418218I0J-200D01*
G01X793979Y1417920D01*
G02X793982Y1417722I-172J-102D01*
G03X793794Y1416995I1314J-728D01*
G01Y1416993D01*
G03X793841Y1416621I1502J1D01*
G01Y1416620D01*
G02X793784Y1416424I-194J-50D01*
G01X793486Y1416148D01*
X793378Y1416125D01*
X793327Y1416142D01*
G03X792850Y1416220I-478J-1424D01*
G01X792848D01*
G03X794350Y1414718I0J-1502D01*
G01Y1414720D01*
G03X794303Y1415092I-1502J-1D01*
G01Y1415093D01*
G02X794360Y1415289I194J50D01*
G01X794658Y1415565D01*
X794766Y1415588D01*
X794817Y1415571D01*
G03X795294Y1415493I478J1424D01*
G01X795296D01*
G03X796798Y1416995I0J1502D01*
G03X796610Y1417722I-1502J-1D01*
G01X796584Y1417769D01*
X796585Y1417874D01*
X796788Y1418218D01*
G02X796960Y1418316I172J-102D01*
G01X926535D01*
G02X926677Y1418257I0J-200D01*
G01X932365Y1412569D01*
G02X932424Y1412427I-141J-142D01*
G01Y1409498D01*
G02X932365Y1409356I-200J0D01*
G01X930097Y1407089D01*
G03X929658Y1406029I1062J-1061D01*
G01Y1406027D01*
G03X931159Y1404526I1501J0D01*
G01X931161D01*
G03X932221Y1404965I-1J1501D01*
G01X933583Y1406327D01*
G02X933800Y1406370I141J-142D01*
G01X933857Y1406347D01*
X933924Y1406246D01*
Y1403398D01*
G02X933865Y1403256I-200J0D01*
G01X933222Y1402613D01*
G02X933038Y1402559I-141J142D01*
G01X932660Y1402642D01*
X932583Y1402708D01*
X932565Y1402756D01*
G03X931159Y1403729I-1406J-529D01*
G03X929657Y1402227I0J-1502D01*
G03X930630Y1400821I1502J0D01*
G01X930678Y1400803D01*
X930744Y1400726D01*
X930827Y1400348D01*
G02X930773Y1400164I-196J-43D01*
G01X930097Y1399489D01*
G03X929658Y1398429I1062J-1061D01*
G01Y1398427D01*
G03X931159Y1396926I1501J0D01*
G01X931161D01*
G03X932221Y1397365I-1J1501D01*
G01X936487Y1401631D01*
G03X936926Y1402691I-1062J1061D01*
G01Y1413756D01*
G03X936487Y1414816I-1501J-1D01*
G01X935660Y1415642D01*
G02X935617Y1415859I142J141D01*
G01X935640Y1415916D01*
X935741Y1415983D01*
X966071D01*
G02X966213Y1415924I0J-200D01*
G01X969031Y1413106D01*
G02X969085Y1412921I-141J-142D01*
G01X969000Y1412541D01*
X968932Y1412464D01*
X968884Y1412447D01*
G03X972588Y1411586I1186J-3295D01*
G01X972546Y1411629D01*
X972524Y1411747D01*
X972691Y1412142D01*
G02X972875Y1412264I184J-78D01*
G01X988258D01*
G02X988400Y1412205I0J-200D01*
G01X991195Y1409410D01*
G02X991254Y1409268I-141J-142D01*
G01Y1403236D01*
G03X991313Y1403094I200J0D01*
G01X993178Y1401229D01*
G03X993320Y1401170I142J141D01*
G01X1034058D01*
G02X1034200Y1401111I0J-200D01*
G01X1035756Y1399555D01*
G02X1035815Y1399413I-141J-142D01*
G01Y1385761D01*
G02X1035756Y1385619I-200J0D01*
G01X1034705Y1384567D01*
G02X1034563Y1384508I-142J141D01*
G01X1004513D01*
G02X1004371Y1384567I0J200D01*
G01X1000009Y1388930D01*
G02X999950Y1389072I141J142D01*
G01Y1397481D01*
G02X999971Y1397570I200J0D01*
G01X999972Y1397572D01*
G03X1000145Y1398271I-1329J700D01*
G03X997141I-1502J0D01*
G03X997313Y1397574I1502J1D01*
G02X997315Y1397570I-178J-91D01*
G01X997326Y1397549D01*
X997336Y1397505D01*
Y1388448D01*
G03X997719Y1387524I1306J0D01*
G01X1002965Y1382278D01*
G03X1003887Y1381896I923J924D01*
G01X1006618D01*
G02X1006784Y1381808I0J-200D01*
G01X1006998Y1381493D01*
X1007008Y1381395D01*
X1006990Y1381349D01*
G03X1006885Y1380798I1397J-552D01*
G01Y1380797D01*
G03X1009889I1502J0D01*
G01Y1380798D01*
G03X1009784Y1381349I-1502J-1D01*
G01X1009766Y1381395D01*
X1009776Y1381493D01*
X1009990Y1381808D01*
G02X1010156Y1381896I166J-112D01*
G01X1035187D01*
G03X1035362Y1381907I6J1306D01*
G02X1035520Y1381859I26J-198D01*
G01X1035747Y1381662D01*
G02X1035815Y1381511I-132J-150D01*
G01Y1377333D01*
G03X1036015Y1377133I200J0D01*
G01X1038038D01*
G02X1038238Y1376933I0J-200D01*
G01Y1365928D01*
G02X1038179Y1365786I-200J0D01*
G01X1035196Y1362803D01*
G02X1035054Y1362744I-142J141D01*
G01X1027308D01*
G02X1027166Y1362803I0J200D01*
G01X1024703Y1365266D01*
G03X1023361Y1365822I-1344J-1346D01*
G01X1017067D01*
G03X1015725Y1365266I2J-1902D01*
G01X1012646Y1362187D01*
G03X1012090Y1360842I1346J-1344D01*
G03X1012553Y1359598I1901J-1D01*
G01X1012592Y1359553D01*
X1012608Y1359438D01*
X1012432Y1359053D01*
G02X1012250Y1358936I-182J83D01*
G01X927273D01*
G03X925643Y1358261I0J-2306D01*
G01X915361Y1347979D01*
G02X915219Y1347920I-142J141D01*
G01X914033D01*
G03X912665Y1347471I0J-2307D01*
G02X912434Y1347466I-119J161D01*
G03X911137Y1347866I-1298J-1906D01*
G01X911135D01*
G03X908828Y1345560I0J-2307D01*
G03X909504Y1343929I2307J1D01*
G01X911620Y1341813D01*
G03X913250Y1341138I1630J1631D01*
G01X915608D01*
G02X915793Y1341014I0J-200D01*
G01X915817Y1340958D01*
X915793Y1340840D01*
X895839Y1320885D01*
G02X895697Y1320826I-142J141D01*
G01X888719D01*
G03X887797Y1320444I1J-1306D01*
G01X884276Y1316923D01*
G03X883894Y1316001I924J-923D01*
G01Y1300436D01*
G03X884276Y1299514I1306J1D01*
G01X885443Y1298347D01*
G02X885492Y1298267I-141J-142D01*
G01Y1298266D01*
G03X886926Y1297210I1434J446D01*
G03X888428Y1298712I0J1502D01*
G03X887373Y1300146I-1502J0D01*
G01X887371D01*
G02X887291Y1300195I62J190D01*
G01X886565Y1300920D01*
G02X886506Y1301062I141J142D01*
G01Y1313138D01*
G02X886582Y1313295I200J0D01*
G01X886828Y1313490D01*
G02X886998Y1313528I124J-157D01*
G03X887342Y1313488I344J1462D01*
G03X888844Y1314990I0J1502D01*
G03X888072Y1316303I-1503J0D01*
G01X888031Y1316326D01*
X887978Y1316402D01*
X887927Y1316766D01*
G02X887983Y1316935I198J28D01*
G01X889203Y1318155D01*
G02X889345Y1318214I142J-141D01*
G01X893733D01*
G02X893933Y1318014I0J-200D01*
G01Y1316557D01*
G02X893901Y1316449I-200J0D01*
G03X893694Y1315744I1099J-706D01*
G01Y1301411D01*
G02X893635Y1301269I-200J0D01*
G01X889364Y1296999D01*
G02X889284Y1296950I-142J141D01*
G01X889283D01*
G03X888227Y1295516I446J-1434D01*
G03X889729Y1294014I1502J0D01*
G03X891163Y1295069I0J1502D01*
G01Y1295071D01*
G02X891212Y1295151I190J-62D01*
G01X893591Y1297531D01*
G02X893810Y1297574I141J-141D01*
G02X893933Y1297390I-77J-185D01*
G01Y1294930D01*
G03X893992Y1294788I200J0D01*
G01X894668Y1294112D01*
G02Y1293830I-142J-141D01*
G01X880204Y1279365D01*
G02X880062Y1279306I-142J141D01*
G01X854399D01*
G03X852769Y1278631I0J-2306D01*
G01X844269Y1270131D01*
G03X843594Y1268501I1631J-1630D01*
G01Y1252138D01*
G02X843535Y1251996I-200J0D01*
G01X829069Y1237531D01*
G03X828394Y1235901I1631J-1630D01*
G01Y1136975D01*
G02X828194Y1136775I-200J0D01*
G01X827636D01*
G02X827496Y1136832I0J200D01*
G01X827296Y1137028D01*
G02X827236Y1137166I140J143D01*
G01Y1137167D01*
G03X826680Y1138474I-1901J-37D01*
G01X823659Y1141494D01*
G02X823600Y1141636I141J142D01*
G01Y1147781D01*
G02X823659Y1147923I200J0D01*
G01X823863Y1148127D01*
G02X824005Y1148186I142J-141D01*
G01X825744D01*
G03Y1151988I0J1901D01*
G01X823131D01*
G03X821789Y1151432I2J-1902D01*
G01X820354Y1149997D01*
G03X819798Y1148655I1346J-1344D01*
G01Y1140762D01*
G03X820354Y1139420I1902J2D01*
G01X822659Y1137116D01*
G02X822702Y1136899I-142J-141D01*
G01X822679Y1136842D01*
X822578Y1136775D01*
X797970D01*
G02X797893Y1136790I-1J200D01*
G01X797835Y1136814D01*
G02X797722Y1136935I77J185D01*
G01X797625Y1137219D01*
G02X797641Y1137382I189J64D01*
G01Y1137383D01*
G03X797840Y1138130I-1303J747D01*
G03X794836I-1502J0D01*
G03X794837Y1138067I1502J-8D01*
G01X794839Y1138026D01*
X794811Y1137950D01*
X794582Y1137712D01*
G02X794438Y1137650I-145J138D01*
G01X787471D01*
G03X786049Y1137384I-2J-3926D01*
G02X785977Y1137370I-73J186D01*
G01X776010D01*
G02X775810Y1137570I0J200D01*
G01Y1138990D01*
G03X775610Y1139190I-200J0D01*
G01X773532D01*
G02X773361Y1139309I12J200D01*
G01X773207Y1139655D01*
G02X773194Y1139722I187J71D01*
G01X773202Y1139743D01*
X773243Y1139852D01*
X773265Y1139879D01*
X773266Y1139880D01*
G03X773544Y1140649I-925J769D01*
G03X771140I-1202J0D01*
G03X771157Y1140449I1202J1D01*
G01X771155D01*
X771160Y1140406D01*
X770856Y1140116D01*
G02X770686Y1140063I-138J144D01*
G01X770685D01*
G03X770472Y1140081I-216J-1284D01*
G03X770258Y1140063I2J-1302D01*
G01X770211Y1140055D01*
X770122Y1140083D01*
X769821Y1140370D01*
X769789Y1140458D01*
X769791Y1140473D01*
G03X769804Y1140649I-1190J176D01*
G03X767400I-1202J0D01*
G03X767406Y1140531I1202J2D01*
G01X767407Y1140521D01*
Y1140518D01*
X767412Y1140473D01*
X767387Y1140424D01*
G02X767329Y1140354I-179J89D01*
G03X767325Y1140352I86J-177D01*
G02X767315Y1140344I-129J151D01*
G01X767176Y1140256D01*
X767002Y1140146D01*
G02X766906Y1140121I-97J175D01*
G01X766803Y1140149D01*
X766780Y1140163D01*
G03X766612Y1140256I-1913J-3257D01*
G03X766266Y1140415I-1748J-3348D01*
G02X766174Y1140524I97J175D01*
G01Y1140526D01*
G02X766167Y1140548I187J72D01*
G02X766163Y1140589I196J40D01*
G03X766164Y1140648I-1301J52D01*
G01Y1140650D01*
G03X764862Y1141951I-1302J-1D01*
G03X764662Y1141936I-3J-1302D01*
G03X763583Y1140896I200J-1287D01*
G02X763569Y1140851I-197J37D01*
G02X763561Y1140836I-181J87D01*
G01X763548Y1140813D01*
X763475Y1140744D01*
G02X763421Y1140707I-139J144D01*
G01X763376Y1140687D01*
G02X763349Y1140677I-83J182D01*
G01X763303Y1140664D01*
G03X763266Y1140659I487J-3745D01*
G01X763264D01*
G03X763249Y1140657I492J-3745D01*
G03X763032Y1140623I476J-3747D01*
G01X763021Y1140621D01*
X762992Y1140619D01*
X762963Y1140621D01*
X762952Y1140623D01*
G03X762785Y1140650I-686J-3714D01*
G03X762621Y1140669I-517J-3741D01*
G01X762608Y1140671D01*
X762578Y1140674D01*
G02X762553Y1140680I34J196D01*
G01X762481Y1140761D01*
X762448Y1140799D01*
G02X762418Y1140843I149J134D01*
G01X762407Y1140866D01*
X762402Y1140893D01*
G03X762321Y1141158I-1279J-246D01*
G03X762036Y1141577I-1199J-509D01*
G03X761852Y1141727I-911J-930D01*
G03X761238Y1141946I-731J-1078D01*
G01X761232Y1141947D01*
X761225Y1141948D01*
X761175Y1141952D01*
X761121D01*
G03X760484Y1141785I1J-1303D01*
G01X760461Y1141772D01*
X760362Y1141746D01*
G02X760281Y1141763I0J200D01*
G01X760247Y1141789D01*
X760246D01*
X760208Y1141819D01*
G02X760163Y1141945I155J126D01*
G01Y1142479D01*
G02X760186Y1142571I200J-1D01*
G01Y1142572D01*
G03X760196Y1142591I-1058J569D01*
G03X760307Y1142916I-1070J547D01*
G01X760315Y1142959D01*
X760337Y1142992D01*
G02X760388Y1143043I165J-114D01*
G01X760526Y1143130D01*
X760527Y1143131D01*
X760560Y1143152D01*
X760661Y1143214D01*
G02X760700Y1143229I91J-178D01*
G01X760805D01*
X760825Y1143224D01*
G03X760875Y1143212I306J1163D01*
G01X760876D01*
X760895Y1143208D01*
G03X761100Y1143187I225J1181D01*
G01X761134D01*
G03X762324Y1144389I-12J1202D01*
G03X761122Y1145591I-1202J0D01*
G03X760922Y1145574I1J-1202D01*
G01Y1145575D01*
G03X760833Y1145556I206J-1185D01*
G01X760832D01*
X760822Y1145553D01*
X760781Y1145548D01*
G02X760654Y1145590I-4J200D01*
G01X760405Y1145784D01*
G02X760380Y1145807I122J158D01*
G02X760331Y1145905I148J135D01*
G02X760328Y1145937I197J35D01*
G01Y1147773D01*
G02X760334Y1147818I200J-4D01*
G02X760382Y1147906I194J-49D01*
G01X760434Y1147957D01*
G03X760492Y1148098I-142J141D01*
G01Y1150284D01*
G02X760555Y1150429I200J-1D01*
G01X760791Y1150633D01*
G02X760866Y1150674I131J-151D01*
G01X760904Y1150685D01*
X760948Y1150679D01*
G03X761122Y1150667I170J1190D01*
G03Y1153071I0J1202D01*
G03X760948Y1153059I-4J-1202D01*
G01X760904Y1153053D01*
X760866Y1153064D01*
G02X760791Y1153105I56J192D01*
G01X760555Y1153309D01*
G02X760492Y1153454I137J146D01*
G01Y1157765D01*
G02X760555Y1157910I200J-1D01*
G01X760791Y1158114D01*
G02X760866Y1158155I131J-151D01*
G01X760904Y1158166D01*
X760948Y1158160D01*
G03X761122Y1158148I170J1190D01*
G03Y1160552I0J1202D01*
G03X760948Y1160540I-4J-1202D01*
G01X760904Y1160534D01*
X760866Y1160545D01*
G02X760791Y1160586I56J192D01*
G01X760555Y1160790D01*
G02X760492Y1160935I137J146D01*
G01Y1165245D01*
G02X760555Y1165390I200J-1D01*
G01X760791Y1165594D01*
G02X760866Y1165635I131J-151D01*
G01X760904Y1165646D01*
X760948Y1165640D01*
G03X761122Y1165628I170J1190D01*
G03Y1168032I0J1202D01*
G03X760948Y1168020I-4J-1202D01*
G01X760904Y1168014D01*
X760866Y1168025D01*
G02X760791Y1168066I56J192D01*
G01X760555Y1168270D01*
G02X760492Y1168415I137J146D01*
G01Y1172725D01*
G02X760555Y1172870I200J-1D01*
G01X760791Y1173074D01*
G02X760866Y1173115I131J-151D01*
G01X760904Y1173126D01*
X760948Y1173120D01*
G03X761122Y1173108I170J1190D01*
G03Y1175512I0J1202D01*
G03X760948Y1175500I-4J-1202D01*
G01X760904Y1175494D01*
X760866Y1175505D01*
G02X760791Y1175546I56J192D01*
G01X760555Y1175750D01*
G02X760492Y1175895I137J146D01*
G01Y1180206D01*
G02X760555Y1180351I200J-1D01*
G01X760791Y1180555D01*
G02X760866Y1180596I131J-151D01*
G01X760904Y1180607D01*
X760948Y1180601D01*
G03X761122Y1180589I170J1190D01*
G03Y1182993I0J1202D01*
G03X760948Y1182981I-4J-1202D01*
G01X760904Y1182975D01*
X760866Y1182986D01*
G02X760791Y1183027I56J192D01*
G01X760555Y1183231D01*
G02X760492Y1183376I137J146D01*
G01Y1187686D01*
G02X760555Y1187831I200J-1D01*
G01X760791Y1188035D01*
G02X760866Y1188076I131J-151D01*
G01X760904Y1188087D01*
X760948Y1188081D01*
G03X761122Y1188069I170J1190D01*
G03Y1190473I0J1202D01*
G03X760948Y1190461I-4J-1202D01*
G01X760904Y1190455D01*
X760866Y1190466D01*
G02X760791Y1190507I56J192D01*
G01X760666Y1190615D01*
X760554Y1190712D01*
G02X760507Y1190781I138J145D01*
G01X760526Y1190872D01*
G03X760554Y1191140I-1274J269D01*
G01Y1191141D01*
G03X760500Y1191511I-1302J-1D01*
G01X760492Y1191539D01*
Y1195166D01*
G02X760555Y1195311I200J-1D01*
G01X760791Y1195515D01*
G02X760866Y1195556I131J-151D01*
G01X760904Y1195567D01*
X760948Y1195561D01*
G03X761122Y1195549I170J1190D01*
G03Y1197953I0J1202D01*
G03X760948Y1197941I-4J-1202D01*
G01X760904Y1197935D01*
X760866Y1197946D01*
G02X760791Y1197987I56J192D01*
G01X760666Y1198095D01*
X760554Y1198192D01*
G02X760507Y1198261I138J145D01*
G01X760526Y1198352D01*
G03X760554Y1198620I-1274J269D01*
G01Y1198621D01*
G03X760500Y1198991I-1302J-1D01*
G01X760492Y1199019D01*
Y1202015D01*
X760498Y1202039D01*
G03X760540Y1202361I-1246J326D01*
G01Y1202363D01*
G03X760526Y1202545I-1288J-8D01*
G01X760513Y1202635D01*
G02X760532Y1202665I178J-92D01*
G03X760534Y1202667I-140J142D01*
G02X760558Y1202694I161J-119D01*
G01X760605Y1202735D01*
X760607D01*
X760787Y1202892D01*
G02X760856Y1202931I131J-151D01*
G01X760902Y1202945D01*
X760931Y1202942D01*
G03X761119Y1202928I191J1289D01*
G01X761312D01*
G02X761461Y1202862I1J-200D01*
G01X761660Y1202642D01*
G02X761711Y1202490I-148J-134D01*
G01Y1202489D01*
G03X761704Y1202363I1281J-134D01*
G01Y1202361D01*
G03X764280I1288J1D01*
G01Y1202363D01*
G03X764273Y1202488I-1288J-9D01*
G01Y1202490D01*
X764269Y1202532D01*
X764295Y1202610D01*
X764523Y1202862D01*
G02X764672Y1202928I148J-134D01*
G01X764862D01*
G03Y1205534I0J1303D01*
G01X761119D01*
G03X760931Y1205520I3J-1303D01*
G01X760902Y1205517D01*
X760856Y1205531D01*
G02X760787Y1205570I62J190D01*
G01X760712Y1205635D01*
X760553Y1205773D01*
G02X760537Y1205791I141J142D01*
G01X760530Y1205801D01*
G02X760524Y1205809I157J124D01*
G01X760539Y1205908D01*
G03X760554Y1206102I-1287J197D01*
G03X760500Y1206472I-1302J-1D01*
G01X760492Y1206500D01*
Y1209495D01*
X760498Y1209519D01*
G03X760540Y1209841I-1246J326D01*
G01Y1209843D01*
G03X760526Y1210025I-1288J-8D01*
G01X760513Y1210115D01*
G02X760532Y1210145I178J-92D01*
G03X760534Y1210147I-140J142D01*
G02X760558Y1210174I161J-119D01*
G01X760605Y1210215D01*
X760607D01*
X760787Y1210372D01*
G02X760856Y1210411I131J-151D01*
G01X760902Y1210425D01*
X760931Y1210422D01*
G03X761119Y1210408I191J1289D01*
G01X761312D01*
G02X761461Y1210342I1J-200D01*
G01X761660Y1210122D01*
G02X761711Y1209970I-148J-134D01*
G01Y1209969D01*
G03X761704Y1209843I1281J-134D01*
G01Y1209841D01*
G03X764280I1288J1D01*
G01Y1209843D01*
G03X764273Y1209968I-1288J-9D01*
G01Y1209970D01*
X764269Y1210012D01*
X764295Y1210090D01*
X764523Y1210342D01*
G02X764672Y1210408I148J-134D01*
G01X764862D01*
G03Y1213014I0J1303D01*
G01X761119D01*
G03X760931Y1213000I3J-1303D01*
G01X760902Y1212997D01*
X760856Y1213011D01*
G02X760787Y1213050I62J190D01*
G01X760712Y1213115D01*
X760553Y1213253D01*
G02X760537Y1213271I141J142D01*
G01X760530Y1213281D01*
G02X760524Y1213289I157J124D01*
G01X760539Y1213388D01*
G03X760554Y1213582I-1287J197D01*
G03X760500Y1213952I-1302J-1D01*
G01X760492Y1213980D01*
Y1216975D01*
X760498Y1216999D01*
G03X760540Y1217321I-1246J326D01*
G01Y1217323D01*
G03X760526Y1217504I-1287J-9D01*
G01Y1217506D01*
X760513Y1217596D01*
G02X760533Y1217627I178J-93D01*
G02X760559Y1217655I159J-121D01*
G01X760790Y1217857D01*
G02X760831Y1217883I127J-155D01*
G02X760842Y1217887I74J-186D01*
G01X760904Y1217907D01*
X760924Y1217904D01*
G03X760944Y1217901I203J1286D01*
G01X760945D01*
G03X760953Y1217900I166J1292D01*
G01X760955D01*
G03X760983Y1217897I153J1293D01*
G01X760985D01*
X760994Y1217896D01*
G03X761122Y1217890I125J1296D01*
G01X761313D01*
G02X761462Y1217824I1J-200D01*
G01X761660Y1217605D01*
G02X761711Y1217451I-148J-134D01*
G01Y1217450D01*
G03X761704Y1217323I1281J-134D01*
G01Y1217321D01*
G03X764280I1288J1D01*
G01Y1217323D01*
G03X764273Y1217450I-1288J-7D01*
G01Y1217451D01*
G02X764324Y1217605I199J20D01*
G01X764522Y1217824D01*
G02X764671Y1217890I148J-134D01*
G01X764862D01*
G03Y1220494I0J1302D01*
G01X761112D01*
G03X760583Y1220378I8J-1303D01*
G03X760360Y1220251I530J-1190D01*
G02X760358Y1220249I-140J138D01*
G01X760289Y1220202D01*
X760268Y1220190D01*
G02X760254Y1220184I-86J181D01*
G01X760239Y1220178D01*
X760223Y1220194D01*
G03X760554Y1221061I-971J867D01*
G01Y1221062D01*
G03X759252Y1222364I-1302J0D01*
G01X759251D01*
G03X758384Y1222033I0J-1302D01*
G01X758368Y1222049D01*
X758371Y1222056D01*
X758373Y1222062D01*
G02X758380Y1222078I187J-72D01*
G01X758392Y1222099D01*
X758439Y1222168D01*
G02X758441Y1222170I142J-140D01*
G03X758568Y1222393I-1063J753D01*
G03X758684Y1222922I-1187J537D01*
G01Y1226672D01*
G03X757382Y1227974I-1302J0D01*
G03X757235Y1227966I-3J-1302D01*
G01X757190Y1227961D01*
X757104Y1227990D01*
X756850Y1228243D01*
G02X756792Y1228405I141J142D01*
G01Y1228406D01*
G03X756800Y1228542I-1280J144D01*
G01Y1228544D01*
G03X755512Y1227256I-1287J-1D01*
G03X755649Y1227263I3J1287D01*
G01X755694Y1227268D01*
X755779Y1227237D01*
X756064Y1226951D01*
X756093Y1226865D01*
X756088Y1226820D01*
G03X756080Y1226672I1294J-144D01*
G01Y1226482D01*
G02X756014Y1226333I-200J-1D01*
G01X755795Y1226135D01*
G02X755641Y1226084I-134J148D01*
G01X755640D01*
G03X755512Y1226090I-124J-1281D01*
G01X755511D01*
G03X754783Y1225864I1J-1287D01*
G02X754529Y1225888I-113J165D01*
G01X752474Y1227943D01*
G03X752332Y1228002I-142J-141D01*
G01X752200D01*
G02X752058Y1228061I0J200D01*
G01X750800Y1229318D01*
G03X750658Y1229377I-142J-141D01*
G01X749100D01*
G02X748957Y1229438I1J200D01*
G03X748031Y1229830I-925J-895D01*
G03X747105Y1229438I-1J-1287D01*
G02X746962Y1229377I-144J139D01*
G01X745381D01*
G02X745236Y1229439I0J200D01*
G03X743346I-945J-896D01*
G02X743201Y1229377I-145J138D01*
G01X741498D01*
G02X741363Y1229429I0J200D01*
G03X739739I-812J-887D01*
G02X739604Y1229377I-135J148D01*
G01X737901D01*
G02X737756Y1229439I0J200D01*
G03X735866I-945J-896D01*
G02X735721Y1229377I-145J138D01*
G01X734018D01*
G02X733883Y1229429I0J200D01*
G03X732259I-812J-887D01*
G02X732124Y1229377I-135J148D01*
G01X730421D01*
G02X730276Y1229439I0J200D01*
G03X728386I-945J-896D01*
G02X728241Y1229377I-145J138D01*
G01X726537D01*
G02X726402Y1229429I0J200D01*
G03X724778I-812J-887D01*
G02X724643Y1229377I-135J148D01*
G01X722940D01*
G02X722795Y1229439I0J200D01*
G03X720905I-945J-896D01*
G02X720760Y1229377I-145J138D01*
G01X719057D01*
G02X718922Y1229429I0J200D01*
G03X717298I-812J-887D01*
G02X717163Y1229377I-135J148D01*
G01X715460D01*
G02X715315Y1229439I0J200D01*
G03X713425I-945J-896D01*
G02X713280Y1229377I-145J138D01*
G01X711699D01*
G02X711556Y1229438I1J200D01*
G03X710630Y1229830I-925J-895D01*
G03X709704Y1229438I-1J-1287D01*
G02X709561Y1229377I-144J139D01*
G01X707980D01*
G02X707835Y1229439I0J200D01*
G03X705945I-945J-896D01*
G02X705800Y1229377I-145J138D01*
G01X704218D01*
G02X704075Y1229438I1J200D01*
G03X703149Y1229830I-925J-895D01*
G03X702223Y1229438I-1J-1287D01*
G02X702080Y1229377I-144J139D01*
G01X700499D01*
G02X700354Y1229439I0J200D01*
G03X698464I-945J-896D01*
G02X698319Y1229377I-145J138D01*
G01X696738D01*
G02X696595Y1229438I1J200D01*
G03X695669Y1229830I-925J-895D01*
G03X694743Y1229438I-1J-1287D01*
G02X694600Y1229377I-144J139D01*
G01X693019D01*
G02X692874Y1229439I0J200D01*
G03X690984I-945J-896D01*
G02X690839Y1229377I-145J138D01*
G01X689258D01*
G02X689115Y1229438I1J200D01*
G03X688189Y1229830I-925J-895D01*
G03X687263Y1229438I-1J-1287D01*
G02X687120Y1229377I-144J139D01*
G01X685539D01*
G02X685394Y1229439I0J200D01*
G03X683504I-945J-896D01*
G02X683359Y1229377I-145J138D01*
G01X681778D01*
G02X681635Y1229438I1J200D01*
G03X680709Y1229830I-925J-895D01*
G03X679783Y1229438I-1J-1287D01*
G02X679640Y1229377I-144J139D01*
G01X678058D01*
G02X677913Y1229439I0J200D01*
G03X676023I-945J-896D01*
G02X675878Y1229377I-145J138D01*
G01X674297D01*
G02X674154Y1229438I1J200D01*
G03X673228Y1229830I-925J-895D01*
G03X672302Y1229438I-1J-1287D01*
G02X672159Y1229377I-144J139D01*
G01X670578D01*
G02X670433Y1229439I0J200D01*
G03X668543I-945J-896D01*
G02X668398Y1229377I-145J138D01*
G01X666817D01*
G02X666674Y1229438I1J200D01*
G03X665748Y1229830I-925J-895D01*
G03X664822Y1229438I-1J-1287D01*
G02X664679Y1229377I-144J139D01*
G01X663098D01*
G02X662953Y1229439I0J200D01*
G03X661063I-945J-896D01*
G02X660918Y1229377I-145J138D01*
G01X659337D01*
G02X659194Y1229438I1J200D01*
G03X658268Y1229830I-925J-895D01*
G03X657342Y1229438I-1J-1287D01*
G02X657199Y1229377I-144J139D01*
G01X655617D01*
G02X655472Y1229439I0J200D01*
G03X653582I-945J-896D01*
G02X653437Y1229377I-145J138D01*
G01X651734D01*
G02X651599Y1229429I0J200D01*
G03X649975I-812J-887D01*
G02X649840Y1229377I-135J148D01*
G01X648137D01*
G02X647992Y1229439I0J200D01*
G03X646102I-945J-896D01*
G02X645957Y1229377I-145J138D01*
G01X644254D01*
G02X644119Y1229429I0J200D01*
G03X642495I-812J-887D01*
G02X642360Y1229377I-135J148D01*
G01X640657D01*
G02X640512Y1229439I0J200D01*
G03X638622I-945J-896D01*
G02X638477Y1229377I-145J138D01*
G01X636774D01*
G02X636639Y1229429I0J200D01*
G03X635015I-812J-887D01*
G02X634880Y1229377I-135J148D01*
G01X633176D01*
G02X633031Y1229439I0J200D01*
G03X631141I-945J-896D01*
G02X630996Y1229377I-145J138D01*
G01X629293D01*
G02X629158Y1229429I0J200D01*
G03X627534I-812J-887D01*
G02X627399Y1229377I-135J148D01*
G01X625696D01*
G02X625551Y1229439I0J200D01*
G03X624692Y1229842I-944J-896D01*
G01X624654Y1229844D01*
X624585Y1229877D01*
X624372Y1230104D01*
G02X624318Y1230241I146J137D01*
G01Y1230685D01*
G02X624372Y1230822I200J0D01*
G01X624558Y1231021D01*
G02X624689Y1231084I146J-136D01*
G01X624690D01*
G03X624691Y1233482I-84J1199D01*
G01X624689D01*
G02X624558Y1233545I15J199D01*
G01X624372Y1233744D01*
G02X624318Y1233881I146J137D01*
G01Y1234425D01*
G02X624372Y1234562I200J0D01*
G01X624558Y1234761D01*
G02X624689Y1234824I146J-136D01*
G01X624690D01*
G03X624691Y1237222I-84J1199D01*
G01X624689D01*
G02X624558Y1237285I15J199D01*
G01X624372Y1237484D01*
G02X624318Y1237621I146J137D01*
G01Y1241806D01*
G02X624337Y1241891I200J0D01*
G03X624417Y1242076I-3471J1611D01*
G02X624603Y1242201I186J-75D01*
G37*
G36*
G01X642759Y275932D02*
X664694D01*
X664768Y275902D01*
X664796Y275873D01*
X665407Y275262D01*
G02X665466Y275120I-141J-142D01*
G01Y205020D01*
X665436Y204946D01*
X665407Y204918D01*
X663886Y203397D01*
G02X663744Y203338I-142J141D01*
G01X642877D01*
X642803Y203368D01*
X642775Y203397D01*
X642617Y203555D01*
G02X642559Y203696I142J141D01*
G01Y204858D01*
G02X642619Y205001I200J0D01*
G01X642853Y205230D01*
X642927Y205259D01*
X642967Y205258D01*
X643001D01*
G03Y208262I0J1502D01*
G01X642967D01*
X642927Y208261D01*
X642853Y208290D01*
X642619Y208519D01*
G02X642559Y208661I140J143D01*
G01Y255107D01*
G02X642677Y255289I200J0D01*
G01X643001Y255436D01*
G02X643172Y255432I81J-183D01*
G01X643222Y255407D01*
X643241Y255392D01*
G03X644215Y255033I975J1143D01*
G03Y258037I0J1502D01*
G03X643241Y257678I1J-1502D01*
G01X643222Y257663D01*
X643172Y257638D01*
G02X643001Y257634I-90J179D01*
G01X642677Y257781D01*
G02X642559Y257963I82J182D01*
G01Y275732D01*
G02X642759Y275932I200J0D01*
G37*
G36*
G01X681597Y242429D02*
X681609Y242428D01*
G03X681746Y242420I139J1202D01*
G01X686225D01*
G02X686363Y242364I-1J-200D01*
G01X686555Y242180D01*
X686571Y242144D01*
X686616Y242044D01*
X686618Y242008D01*
G03X687000Y241095I1499J91D01*
G01X687002Y241093D01*
X687006Y241088D01*
G03X687086Y241003I1133J986D01*
G03X688136Y240576I1049J1075D01*
G03X689638Y242037I0J1503D01*
G02X689642Y242073I200J-4D01*
G01X689655Y242136D01*
X689672Y242174D01*
X689702Y242202D01*
X689868Y242362D01*
G02X689971Y242414I138J-145D01*
G01X690003Y242420D01*
X693871D01*
G03X694012Y242428I2J1210D01*
G01X697414D01*
G03X697555Y242420I139J1202D01*
G01X704144D01*
G02X704178Y242417I-1J-200D01*
G01X704182D01*
G02X704289Y242361I-35J-197D01*
G01X706742Y239908D01*
X706754Y239895D01*
X706795Y239854D01*
G02X706818Y239762I-177J-93D01*
G01Y153180D01*
G02X706815Y153143I-200J-2D01*
G01X706803Y153079D01*
X706770Y153022D01*
X706744Y152999D01*
G03X706412Y147766I2441J-2782D01*
G03X706639Y147528I2789J2433D01*
G03X706684Y147486I2548J2685D01*
G01X706685Y147485D01*
G03X706720Y147452I2557J2677D01*
G01X706751Y147425D01*
X706800Y147316D01*
G02X706818Y147234I-182J-83D01*
G01Y125108D01*
X706807Y125076D01*
G03X706721Y124576I1416J-501D01*
G03X706807Y124076I1502J1D01*
G01X706818Y124044D01*
Y122986D01*
G03X706833Y122910I200J0D01*
G01X706853Y122862D01*
G02X706868Y122786I-185J-76D01*
G01Y117488D01*
G02X706831Y117371I-200J-1D01*
G03X706549Y116496I1220J-876D01*
G03X706831Y115621I1502J1D01*
G02X706868Y115504I-163J-116D01*
G01Y110681D01*
G03X706881Y110611I200J1D01*
G02X706893Y110527I-188J-70D01*
G01X706884Y110411D01*
G02X706845Y110306I-199J14D01*
G03X706549Y109410I1206J-895D01*
G03X708051Y107908I1502J0D01*
G03X708983Y108232I0J1502D01*
G01X709044Y108280D01*
X709194Y108272D01*
X709798Y107668D01*
G03X709940Y107609I142J141D01*
G01X710514D01*
X710532Y107606D01*
G03X710738Y107587I213J1183D01*
G01X726664Y107588D01*
G02X726864Y107388I0J-200D01*
G01Y104248D01*
G03X726892Y103932I1803J1D01*
G01X726896Y103910D01*
X726894Y103864D01*
G02X726808Y103708I-200J8D01*
G01X726782Y103690D01*
G02X726599Y103667I-114J165D01*
G03X725890Y103845I-709J-1323D01*
G03X724388Y102343I0J-1502D01*
G03X724806Y101303I1503J0D01*
G01X724813Y101296D01*
X724815Y101294D01*
G03X725605Y100852I1094J1029D01*
G03X725907Y100821I303J1470D01*
G01X725909D01*
G03X727409Y102243I0J1502D01*
G01X727412Y102292D01*
X727461Y102376D01*
X727775Y102571D01*
X727777D01*
X727807Y102590D01*
X727848Y102597D01*
X727885Y102604D01*
X727961Y102590D01*
X727981Y102582D01*
G03X728666Y102446I687J1667D01*
G01X728667D01*
G03X730470Y104249I0J1803D01*
G01Y107389D01*
G02X730669Y107588I199J-1D01*
G01X766987D01*
G03X766995Y107589I-144J1184D01*
G01X768468Y106116D01*
G02X768527Y105974I-141J-142D01*
G01Y98782D01*
G02X768461Y98633I-200J-1D01*
G01X768208Y98405D01*
X768128Y98379D01*
X768085Y98384D01*
G03X767929Y98392I-155J-1494D01*
G03X766427Y96890I0J-1502D01*
G03X766516Y96382I1502J1D01*
G01X766533Y96334D01*
X766517Y96233D01*
X766250Y95885D01*
X766157Y95844D01*
X766106Y95848D01*
G03X765982Y95853I-122J-1497D01*
G03X767484Y94351I0J-1502D01*
G03X767395Y94859I-1502J-1D01*
G01X767378Y94907D01*
X767394Y95008D01*
X767661Y95356D01*
X767754Y95397D01*
X767805Y95393D01*
G03X767929Y95388I122J1497D01*
G03X768085Y95396I1J1502D01*
G01X768128Y95401D01*
X768208Y95375D01*
X768461Y95147D01*
G02X768527Y94998I-134J-148D01*
G01Y94814D01*
X768515Y94780D01*
G03Y93778I1416J-501D01*
G01X768527Y93744D01*
Y87619D01*
G02X768403Y87434I-200J0D01*
G03X768278Y84718I575J-1387D01*
G03X768404Y84659I699J1329D01*
G01X768460Y84635D01*
X768527Y84535D01*
Y62339D01*
G02X768469Y62198I-200J0D01*
G01X768373Y62101D01*
X768244Y61971D01*
X768173Y61941D01*
X768133Y61940D01*
G03X767053Y61457I24J-1502D01*
G01X767024Y61425D01*
X766945Y61392D01*
X766557Y61402D01*
X766480Y61440D01*
X766452Y61473D01*
G03X765297Y62015I-1155J-960D01*
G03Y59011I0J-1502D01*
G03X766400Y59494I0J1501D01*
G01X766430Y59526D01*
X766509Y59559D01*
X766897Y59549D01*
X766974Y59511D01*
X767002Y59478D01*
G03X768125Y58936I1155J960D01*
G01X768139D01*
G02X768271Y58877I-10J-200D01*
G01X768459Y58688D01*
X768468Y58679D01*
G02X768527Y58537I-141J-142D01*
G01Y54060D01*
G02X768468Y53918I-200J0D01*
G01X767266Y52716D01*
G02X767124Y52657I-142J141D01*
G01X748594D01*
G02X748452Y52716I0J200D01*
G01X743311Y57857D01*
G03X743215Y57911I-142J-141D01*
G02X743095Y57993I45J195D01*
G01X742933Y58231D01*
X742916Y58257D01*
X742907Y58286D01*
G02X742898Y58345I191J59D01*
G01Y58396D01*
X742910Y58455D01*
X742914Y58477D01*
X742921Y58494D01*
G03X743522Y61612I-7804J3121D01*
G01Y61614D01*
G03X740791Y67814I-8403J0D01*
G03X735099Y70036I-5692J-6179D01*
G03X726697Y61634I0J-8402D01*
G03X727317Y58467I8402J1D01*
G02X727298Y58280I-185J-76D01*
G01X727112Y58004D01*
G02X726946Y57916I-166J112D01*
G01X719804D01*
G02X719662Y57975I0J200D01*
G01X719634Y58003D01*
X719504Y58260D01*
G02X719483Y58350I179J89D01*
G01Y58441D01*
G02X719504Y58530I200J0D01*
G01X719514Y58550D01*
X719523Y58562D01*
G03X720208Y60708I-3019J2146D01*
G01Y60709D01*
G03X719763Y62468I-3704J-1D01*
G01X719739Y62513D01*
Y62613D01*
X719928Y62963D01*
X720012Y63018D01*
X720063Y63022D01*
G03X722689Y69217I-319J3789D01*
G01X722688Y69218D01*
G03X716369Y65045I-2963J-2384D01*
G01X716377Y65030D01*
X716378Y65027D01*
X716385Y65013D01*
G02X716406Y64924I-179J-89D01*
G01Y64866D01*
X716242Y64596D01*
X716245Y64580D01*
X716186Y64506D01*
G02X716085Y64438I-157J124D01*
G01X716057Y64430D01*
X709185D01*
G03X705484Y60729I0J-3701D01*
G01Y60727D01*
G03X706117Y58664I3700J7D01*
G01X706118Y58663D01*
X706152Y58612D01*
X706155Y58607D01*
X706181Y58571D01*
G02X706213Y58411I-163J-116D01*
G01X706191Y58314D01*
X706183Y58277D01*
X706162Y58246D01*
G03X706144Y58213I166J-112D01*
G01X706141Y58206D01*
X706048Y58025D01*
G02X705925Y57924I-178J91D01*
G01X705897Y57916D01*
X669172D01*
G02X669030Y57975I0J200D01*
G01X668265Y58740D01*
G02X668224Y58961I142J141D01*
G01Y58962D01*
X668376Y59303D01*
G02X668558Y59422I183J-81D01*
G01X668576D01*
G03X668647Y59420I78J1500D01*
G01X668651D01*
G03X670151Y60922I-2J1502D01*
G03X668649Y62424I-1502J0D01*
G03X667967Y62260I0J-1502D01*
G01X667920Y62236D01*
X667817Y62240D01*
X667481Y62447D01*
G02X667386Y62617I105J170D01*
G01Y84624D01*
X667392Y84648D01*
X667398Y84674D01*
X667449Y84769D01*
G02X667476Y84807I175J-96D01*
G01X667492Y84825D01*
X667509Y84837D01*
G03X668109Y85870I-892J1209D01*
G01X668115Y85924D01*
G03X668120Y86046I-1498J122D01*
G03X667522Y87246I-1503J0D01*
G01X667510Y87254D01*
X667482Y87282D01*
X667461Y87303D01*
X667409Y87399D01*
G02X667386Y87493I177J93D01*
G01Y92495D01*
G02X667443Y92635I200J0D01*
G01X667525Y92719D01*
G02X667583Y92760I143J-140D01*
G01X667620Y92777D01*
X667658Y92780D01*
G03X669071Y94279I-89J1499D01*
G03X667697Y95776I-1503J0D01*
G01X667656Y95779D01*
X667620Y95798D01*
G02X667564Y95840I90J178D01*
G01X667380Y96040D01*
G02X667327Y96176I147J136D01*
G01Y108935D01*
X667388Y109033D01*
X667441Y109058D01*
G03X667984Y109498I-648J1355D01*
G01X667992Y109509D01*
X668017Y109534D01*
G02X668129Y109590I141J-142D01*
G01X668440Y109636D01*
X668517Y109616D01*
X668549Y109591D01*
G03X669462Y109282I913J1194D01*
G03X670749Y110010I0J1502D01*
G01X670762Y110031D01*
X670779Y110048D01*
X670798Y110067D01*
X670899Y110126D01*
G02X671000Y110153I100J-173D01*
G01X671240D01*
G02X671363Y110110I-1J-200D01*
G01X671435Y110054D01*
X671454Y110023D01*
G03X671613Y109808I1282J782D01*
G01X671615Y109806D01*
X671622Y109799D01*
X671627Y109794D01*
G03X672756Y109282I1129J989D01*
G03X674258Y110784I0J1502D01*
G03X673840Y111824I-1503J0D01*
G01X673831Y111833D01*
X673830Y111834D01*
G03X673822Y111842I-1066J-1058D01*
G02X673820Y111844I140J142D01*
G03X672739Y112306I-1083J-1039D01*
G01X672737D01*
G03X671436Y111555I0J-1502D01*
G02X671263Y111455I-173J100D01*
G01X670925D01*
G02X670753Y111553I0J200D01*
G03X670639Y111718I-1290J-770D01*
G01X670620Y111741D01*
G03X670568Y111800I-1152J-963D01*
G01X670562Y111807D01*
X670559Y111810D01*
G03X669444Y112306I-1115J-1005D01*
G01X669443D01*
G03X668251Y111718I0J-1502D01*
G01X668243Y111707D01*
X668220Y111684D01*
G02X668110Y111628I-141J142D01*
G01X668108D01*
X667798Y111582D01*
X667761Y111590D01*
X667715Y111600D01*
X667681Y111626D01*
G03X667674Y111631I-875J-1218D01*
G01X667669Y111634D01*
X667637Y111658D01*
X667591Y111707D01*
X667572Y111727D01*
X667527Y111811D01*
G02X667504Y111905I177J93D01*
G01Y111926D01*
X667505Y111979D01*
X667534Y112030D01*
X667547Y112054D01*
X667588Y112095D01*
X667598Y112106D01*
X667632Y112134D01*
X667641Y112140D01*
G03X668315Y113394I-830J1254D01*
G01Y113395D01*
G03X668151Y114077I-1500J0D01*
G03X667926Y114403I-1338J-683D01*
G01X667924Y114405D01*
X667920Y114409D01*
G03X667441Y114770I-1126J-996D01*
G01X667388Y114795D01*
X667327Y114892D01*
Y115108D01*
X667390Y115206D01*
X667443Y115231D01*
G03X668315Y116594I-629J1363D01*
G03X668280Y116921I-1502J5D01*
G03X667896Y117635I-1466J-328D01*
G01X667877Y117655D01*
X667876D01*
G03X667862Y117669I-1069J-1055D01*
G03X667744Y117777I-1072J-1052D01*
G01X667726Y117792D01*
X667700Y117826D01*
X667659Y117916D01*
G02X667640Y118000I181J85D01*
G01Y118197D01*
X667644Y118243D01*
X667700Y118358D01*
X667711Y118373D01*
X667736Y118408D01*
X667753Y118422D01*
X667754Y118423D01*
G03X668315Y119594I-942J1171D01*
G01Y119595D01*
G03X668151Y120277I-1500J0D01*
G03X667926Y120603I-1338J-683D01*
G01X667924Y120605D01*
X667920Y120609D01*
G03X667441Y120970I-1126J-996D01*
G01X667388Y120995D01*
X667327Y121092D01*
Y122677D01*
X667422Y122789D01*
X667494Y122801D01*
G03X668370Y125281I-247J1482D01*
G01X668365Y125286D01*
X668362Y125289D01*
G03X668354Y125298I-1127J-993D01*
G02X668352Y125301I165J112D01*
G03X667492Y125782I-1123J-999D01*
G01X667420Y125795D01*
X667327Y125905D01*
Y131939D01*
G02X667431Y132114I200J0D01*
G01X667448Y132124D01*
X667840Y132292D01*
X667959Y132270D01*
X668003Y132227D01*
G03X669056Y131796I1053J1071D01*
G03X670494Y132865I0J1502D01*
G01X670505Y132901D01*
X670550Y132959D01*
X670810Y133115D01*
X670842Y133121D01*
G03X671203Y133077I361J1459D01*
G03X672695Y134403I0J1502D01*
G01X672701Y134457D01*
G03X672288Y135619I-1498J122D01*
G01X672280Y135626D01*
X672276Y135631D01*
G03X671186Y136101I-1091J-1031D01*
G01X671184D01*
G03X669760Y135080I0J-1504D01*
G01X669759Y135077D01*
X669744Y135032D01*
X669685Y134973D01*
X669667Y134954D01*
X669410Y134802D01*
X669340Y134790D01*
X669304Y134796D01*
G03X669038Y134820I-267J-1478D01*
G01X669037D01*
G03X668004Y134408I1J-1503D01*
G01X667983Y134388D01*
X667953Y134373D01*
G02X667784Y134368I-90J179D01*
G01X667448Y134513D01*
G02X667327Y134697I79J184D01*
G01Y167034D01*
G02X667350Y167127I200J0D01*
G01X667378Y167179D01*
X667435Y167229D01*
X667472Y167241D01*
G03X668493Y168665I-483J1424D01*
G03X667966Y169809I-1505J0D01*
G01X667965Y169810D01*
G03X667461Y170104I-994J-1125D01*
G01X667401Y170125D01*
X667327Y170229D01*
Y171034D01*
G02X667350Y171127I200J0D01*
G01X667378Y171179D01*
X667435Y171229D01*
X667472Y171241D01*
G03X668493Y172665I-483J1424D01*
G03X667966Y173809I-1505J0D01*
G01X667965Y173810D01*
G03X667461Y174104I-994J-1125D01*
G01X667401Y174125D01*
X667327Y174229D01*
Y175034D01*
G02X667350Y175127I200J0D01*
G01X667378Y175179D01*
X667435Y175229D01*
X667472Y175241D01*
G03X668493Y176665I-483J1424D01*
G03X667966Y177809I-1505J0D01*
G01X667965Y177810D01*
G03X667461Y178104I-994J-1125D01*
G01X667401Y178125D01*
X667327Y178229D01*
Y179034D01*
G02X667350Y179127I200J0D01*
G01X667378Y179179D01*
X667435Y179229D01*
X667472Y179241D01*
G03X668493Y180665I-483J1424D01*
G03X667966Y181809I-1505J0D01*
G01X667965Y181810D01*
G03X667461Y182104I-994J-1125D01*
G01X667401Y182125D01*
X667327Y182229D01*
Y185124D01*
G02X667416Y185290I200J0D01*
G01X667431Y185300D01*
X667465Y185320D01*
X667491Y185327D01*
G03X668604Y186778I-389J1451D01*
G01Y186779D01*
G03X668228Y187773I-1504J-1D01*
G01X668226Y187775D01*
X668221Y187780D01*
G03X667478Y188247I-1136J-983D01*
G01X667475Y188248D01*
X667470Y188250D01*
G02X667327Y188441I57J192D01*
G01Y191034D01*
G02X667350Y191127I200J0D01*
G01X667378Y191179D01*
X667435Y191229D01*
X667472Y191241D01*
G03X668493Y192665I-483J1424D01*
G03X667966Y193809I-1505J0D01*
G01X667965Y193810D01*
G03X667461Y194104I-994J-1125D01*
G01X667401Y194125D01*
X667327Y194229D01*
Y195034D01*
G02X667350Y195127I200J0D01*
G01X667378Y195179D01*
X667435Y195229D01*
X667472Y195241D01*
G03X668493Y196665I-483J1424D01*
G03X667966Y197809I-1505J0D01*
G01X667965Y197810D01*
G03X667461Y198104I-994J-1125D01*
G01X667401Y198125D01*
X667327Y198229D01*
Y199239D01*
G02X667468Y199430I200J0D01*
G01X667476Y199433D01*
G03X668523Y200864I-454J1431D01*
G03X668122Y201886I-1503J0D01*
G01X668110Y201899D01*
X668109Y201900D01*
X668081Y201930D01*
G03X667466Y202313I-1078J-1046D01*
G01X667435Y202323D01*
X667384Y202359D01*
X667366Y202385D01*
G02X667327Y202503I161J119D01*
G01Y203239D01*
G02X667468Y203430I200J0D01*
G01X667476Y203433D01*
G03X668523Y204864I-454J1431D01*
G03X668122Y205886I-1503J0D01*
G01X668110Y205899D01*
X668109Y205900D01*
X668081Y205930D01*
G03X667466Y206313I-1078J-1046D01*
G01X667435Y206323D01*
X667384Y206359D01*
X667366Y206385D01*
G02X667327Y206503I161J119D01*
G01Y207239D01*
G02X667468Y207430I200J0D01*
G01X667476Y207433D01*
G03X668523Y208864I-454J1431D01*
G03X668122Y209886I-1503J0D01*
G01X668110Y209899D01*
X668109Y209900D01*
X668081Y209930D01*
G03X667466Y210313I-1078J-1046D01*
G01X667435Y210323D01*
X667384Y210359D01*
X667366Y210385D01*
G02X667327Y210503I161J119D01*
G01Y211239D01*
G02X667468Y211430I200J0D01*
G01X667476Y211433D01*
G03X668523Y212864I-454J1431D01*
G03X668122Y213886I-1503J0D01*
G01X668110Y213899D01*
X668109Y213900D01*
X668081Y213930D01*
G03X667466Y214313I-1078J-1046D01*
G01X667435Y214323D01*
X667384Y214359D01*
X667366Y214385D01*
G02X667327Y214503I161J119D01*
G01Y215239D01*
G02X667468Y215430I200J0D01*
G01X667476Y215433D01*
G03X668523Y216864I-454J1431D01*
G03X668122Y217886I-1503J0D01*
G01X668110Y217899D01*
X668109Y217900D01*
X668081Y217930D01*
G03X667466Y218313I-1078J-1046D01*
G01X667435Y218323D01*
X667384Y218359D01*
X667366Y218385D01*
G02X667327Y218503I161J119D01*
G01Y220239D01*
G02X667468Y220430I200J0D01*
G01X667476Y220433D01*
G03X668523Y221864I-454J1431D01*
G03X668122Y222886I-1503J0D01*
G01X668110Y222899D01*
X668109Y222900D01*
X668081Y222930D01*
G03X667466Y223313I-1078J-1046D01*
G01X667435Y223323D01*
X667384Y223359D01*
X667366Y223385D01*
G02X667327Y223503I161J119D01*
G01Y241469D01*
G02X667386Y241611I200J0D01*
G01X668136Y242361D01*
G02X668278Y242420I142J-141D01*
G01X678288D01*
G03X678425Y242428I-2J1210D01*
G01X678437Y242429D01*
X681597D01*
G37*
G36*
G01X667460Y276294D02*
X742434D01*
G02X742576Y276235I0J-200D01*
G01X743860Y274951D01*
G02X743862Y274949I-140J-142D01*
G02X743919Y274809I-143J-140D01*
G01Y267385D01*
G02X743806Y267205I-200J0D01*
G01X743429Y267023D01*
X743316Y267036D01*
X743270Y267072D01*
G03X742336Y267398I-934J-1175D01*
G03Y264394I0J-1502D01*
G03X743270Y264720I0J1501D01*
G01X743316Y264756D01*
X743429Y264769D01*
X743806Y264587D01*
G02X743919Y264407I-87J-180D01*
G01Y257901D01*
X743865Y257809D01*
X743820Y257782D01*
X743818D01*
X743530Y257613D01*
G02X743456Y257588I-100J174D01*
G01X743415Y257583D01*
X743322Y257608D01*
X743300Y257620D01*
G03X742578Y257805I-723J-1319D01*
G01X742577D01*
G03Y254801I0J-1502D01*
G01X742578D01*
G03X743300Y254986I-1J1504D01*
G01X743322Y254998D01*
X743376Y255013D01*
G02X743456Y255018I52J-193D01*
G01X743495Y255013D01*
X743819Y254824D01*
G02X743822Y254822I-109J-167D01*
G02X743919Y254651I-103J-171D01*
G01Y207215D01*
G02X743917Y207189I-200J2D01*
G01X743912Y207148D01*
X743909Y207137D01*
G03X743861Y206760I1454J-377D01*
G01Y206690D01*
G03X743862Y206670I200J0D01*
G01X743869Y206603D01*
G03X743896Y206434I1495J152D01*
G01X743903Y206407D01*
X743904Y206405D01*
G03X743908Y206388I1464J335D01*
G01Y206384D01*
G03X743912Y206371I1437J435D01*
G01X743919Y206345D01*
Y202582D01*
G03X743978Y202440I200J0D01*
G01X744399Y202019D01*
G03X744541Y201960I142J141D01*
G01X747259D01*
G02X747292Y201957I-2J-200D01*
G02X747399Y201903I-32J-197D01*
G01X747714Y201588D01*
Y193725D01*
G02X747628Y193561I-200J0D01*
G01X747377Y193386D01*
G02X747263Y193350I-114J164D01*
G01X747176D01*
X747145Y193361D01*
G03X746655Y193443I-490J-1420D01*
G01X746639D01*
G03X745153Y191941I16J-1502D01*
G03X746655Y190439I1502J0D01*
G01X746658D01*
G03X747176Y190532I-2J1502D01*
G01X747222Y190549D01*
X747319Y190537D01*
X747628Y190321D01*
G02X747714Y190157I-114J-164D01*
G01Y165175D01*
G02X747655Y165034I-200J1D01*
G01X744188Y161567D01*
X744160Y161538D01*
X744086Y161508D01*
X737072D01*
G02X736901Y161604I0J200D01*
G01X736724Y161896D01*
G02X736708Y161930I172J102D01*
G02X736719Y162094I188J70D01*
G01X736722Y162100D01*
X736739Y162135D01*
G03X736891Y162788I-1350J658D01*
G01Y162790D01*
Y162815D01*
G03X736488Y163817I-1502J-22D01*
G01X736487Y163818D01*
G02X736431Y163957I144J139D01*
G01Y164268D01*
X736458Y164338D01*
X736485Y164366D01*
G03Y166420I-1096J1027D01*
G01X736458Y166448D01*
X736431Y166518D01*
Y166868D01*
X736458Y166938D01*
X736485Y166966D01*
G03X736891Y167993I-1096J1027D01*
G03X736521Y168980I-1501J0D01*
G01X736497Y169008D01*
X736472Y169074D01*
Y169412D01*
X736497Y169478D01*
X736521Y169506D01*
G03X736891Y170493I-1131J987D01*
G03X733887I-1502J0D01*
G03X734257Y169506I1501J0D01*
G01X734281Y169478D01*
X734306Y169412D01*
Y169074D01*
X734281Y169008D01*
X734257Y168980D01*
G03X733887Y167993I1131J-987D01*
G03X734293Y166966I1502J0D01*
G01X734320Y166938D01*
X734347Y166868D01*
Y166518D01*
X734320Y166448D01*
X734293Y166420D01*
G03Y164366I1096J-1027D01*
G01X734320Y164338D01*
X734347Y164268D01*
Y163918D01*
X734320Y163849D01*
X734293Y163820D01*
G03X733887Y162821I1096J-1027D01*
G01Y162812D01*
Y162793D01*
G03X734039Y162135I1502J0D01*
G01X734067Y162077D01*
G02X734070Y161930I-185J-77D01*
G02X734054Y161896I-188J68D01*
G01X733877Y161605D01*
X733850Y161559D01*
X733759Y161508D01*
X730135D01*
G02X729977Y161585I0J200D01*
G01X729754Y161870D01*
X729735Y161959D01*
X729746Y162005D01*
G03X729791Y162368I-1457J365D01*
G03X728289Y163870I-1502J0D01*
G03X727262Y163464I0J-1502D01*
G01X727234Y163437D01*
X727164Y163410D01*
X726814D01*
X726744Y163437D01*
X726716Y163464D01*
G03X725689Y163870I-1027J-1096D01*
G03X724187Y162368I0J-1502D01*
G03X724232Y162005I1502J2D01*
G01X724243Y161959D01*
X724224Y161870D01*
X724001Y161585D01*
G02X723843Y161508I-158J123D01*
G01X708695D01*
G02X708553Y161567I0J200D01*
G01X707897Y162223D01*
G02X707839Y162364I142J141D01*
G01Y240157D01*
G03X707780Y240298I-200J-1D01*
G01X707483Y240595D01*
X707481Y240598D01*
G03X707468Y240611I-856J-843D01*
G01X707467Y240612D01*
X704997Y243082D01*
G03X704974Y243104I-842J-857D01*
G01X704972Y243106D01*
X704726Y243352D01*
G03X704586Y243410I-141J-142D01*
G01X704367D01*
X704350Y243413D01*
G03X704154Y243430I-201J-1185D01*
G01X697557D01*
G02X697399Y243507I0J200D01*
G01X697176Y243793D01*
X697157Y243882D01*
X697169Y243928D01*
G03X697215Y244297I-1457J369D01*
G03X695713Y245799I-1502J0D01*
G03X695346Y245753I2J-1502D01*
G01X695290Y245739D01*
X695183Y245773D01*
X694875Y246131D01*
X694857Y246242D01*
X694879Y246295D01*
G03X694995Y246874I-1387J579D01*
G03X693493Y248376I-1502J0D01*
G03X692464Y247968I0J-1502D01*
G01X692430Y247936D01*
X692344Y247909D01*
X691990Y247958D01*
G02X691982Y247959I21J199D01*
G02X691845Y248055I36J197D01*
G03X690551Y248794I-1294J-763D01*
G03Y245790I0J-1502D01*
G03X691580Y246198I0J1502D01*
G01X691614Y246230D01*
X691700Y246257D01*
X692100Y246201D01*
X692175Y246151D01*
X692199Y246111D01*
G03X693493Y245372I1294J763D01*
G03X693572Y245374I1J1502D01*
G01X693573D01*
G03X693635Y245378I-66J1501D01*
G01X693669Y245382D01*
G03X693751Y245394I-176J1492D01*
G01X693752D01*
G03X693860Y245418I-272J1477D01*
G01X693916Y245432D01*
X694023Y245398D01*
X694331Y245040D01*
X694348Y244930D01*
X694326Y244876D01*
G03X694220Y244474I1387J-581D01*
G01X694215Y244419D01*
G03X694210Y244297I1498J-122D01*
G01Y244295D01*
G03X694256Y243927I1503J1D01*
G01X694268Y243881D01*
X694249Y243792D01*
X694027Y243507D01*
G02X693869Y243430I-158J123D01*
G01X690017D01*
G03X689817Y243413I1J-1202D01*
G01X689800Y243410D01*
X688854D01*
X688808Y243422D01*
X688789Y243431D01*
X688787Y243432D01*
G03X688545Y243523I-648J-1355D01*
G03X687885Y243559I-410J-1445D01*
G03X687481Y243430I250J-1481D01*
G01X687461Y243420D01*
X687417Y243410D01*
X686533D01*
X686509Y243411D01*
X686448Y243425D01*
G03X686403Y243430I-44J-195D01*
G01X681748D01*
G02X681601Y243494I0J200D01*
G01X681587Y243509D01*
X681410Y243781D01*
X681382Y243824D01*
X681378Y243875D01*
X681374Y243924D01*
X681386Y243952D01*
Y243953D01*
X681395Y243973D01*
G03X681519Y244571I-1378J598D01*
G01Y244590D01*
G03X678515I-1502J-19D01*
G01Y244570D01*
G03X678640Y243971I1502J1D01*
G01X678660Y243925D01*
X678656Y243875D01*
X678652Y243824D01*
X678454Y243521D01*
X678426Y243478D01*
X678338Y243430D01*
X668356D01*
G02X668214Y243489I0J200D01*
G01X666625Y245078D01*
X666596Y245106D01*
X666566Y245180D01*
Y275400D01*
G02X666623Y275540I200J0D01*
G01X666624Y275541D01*
X667318Y276235D01*
G02X667320Y276237I142J-140D01*
G02X667460Y276294I140J-143D01*
G37*
G36*
G01X767929Y151108D02*
X761355D01*
G02X761338Y151109I3J200D01*
G01X761336D01*
G02X761183Y151204I18J199D01*
G01X761012Y151524D01*
G02X761007Y151704I176J95D01*
G02X761021Y151728I180J-89D01*
G01X761022Y151729D01*
Y151730D01*
G03X761274Y152562I-1250J833D01*
G03X759772Y154064I-1502J0D01*
G03X758501Y153363I0J-1503D01*
G01X758487Y153341D01*
X758458Y153313D01*
X758399Y153276D01*
X758397D01*
X758360Y153253D01*
G02X758268Y153224I-104J170D01*
G01X757989Y153206D01*
G02X757961I-14J200D01*
G02X757890Y153225I15J200D01*
G02X757817Y153284I86J181D01*
G01X757816Y153285D01*
X757809Y153295D01*
G03X756623Y153875I-1186J-923D01*
G01X756622D01*
G03X755120Y152373I0J-1502D01*
G03X755285Y151689I1502J0D01*
G02X755307Y151590I-178J-91D01*
G01X755305Y151539D01*
X755099Y151204D01*
G02X755019Y151130I-170J104D01*
G01X755017Y151129D01*
G02X754928Y151108I-89J179D01*
G01X745612D01*
G02X745537Y151122I-1J200D01*
G01X745501Y151137D01*
X744426Y152212D01*
X744345Y152292D01*
G03X742930Y152878I-1415J-1415D01*
G01X736570D01*
G03X735155Y152292I0J-2001D01*
G01X731818Y148955D01*
G03X731232Y147540I1415J-1415D01*
G03X731240Y147354I2001J-7D01*
G01X731241Y147345D01*
Y147340D01*
G03X733228Y145538I1992J200D01*
G01X733271Y145539D01*
G03X734649Y146125I-37J2001D01*
G01X734986Y146463D01*
X737340Y148817D01*
G02X737359Y148834I143J-140D01*
G02X737481Y148876I123J-158D01*
G01X739961D01*
G02X739975Y148875I-7J-200D01*
G02X740110Y148809I-14J-200D01*
G01X740308Y148587D01*
G02X740349Y148516I-149J-133D01*
G01X740362Y148475D01*
X740358Y148433D01*
G03X740350Y148299I1494J-156D01*
G01Y148271D01*
G03X741852Y146775I1502J6D01*
G03X743041Y147359I0J1502D01*
G01X743065Y147390D01*
X743095Y147408D01*
G02X743166Y147434I103J-171D01*
G01X743197Y147439D01*
X743231Y147444D01*
X743233D01*
X743236Y147445D01*
G02X743263Y147447I28J-198D01*
G01X743521D01*
G02X743579Y147438I-1J-200D01*
G01X743604Y147431D01*
X743625Y147418D01*
G03X743679Y147386I1047J1705D01*
G02X743681Y147384I-136J-138D01*
G03X744045Y147215I1021J1722D01*
G02X744049Y147213I-87J-179D01*
G03X744067Y147207I642J1896D01*
G03X744071Y147205I91J176D01*
G03X744760Y147104I630J1900D01*
G01X767929D01*
G02X768129Y146904I0J-200D01*
G01Y124540D01*
X768126Y124524D01*
G03X768107Y124283I1483J-238D01*
G03X768126Y124042I1502J-3D01*
G01X768129Y124026D01*
Y120791D01*
G02X768115Y120718I-200J1D01*
G01X768075Y120618D01*
X768052Y120592D01*
G03Y118596I1123J-998D01*
G01X768075Y118570D01*
X768115Y118470D01*
G02X768129Y118397I-186J-74D01*
G01Y117791D01*
G02X768115Y117718I-200J1D01*
G01X768075Y117618D01*
X768052Y117592D01*
G03X767673Y116594I1124J-998D01*
G01Y116592D01*
G03X767986Y115675I1503J1D01*
G02X768017Y115570I-169J-107D01*
G01Y114455D01*
G02X768006Y114391I-200J1D01*
G01X767976Y114302D01*
X767969Y114291D01*
G03X767672Y113394I1206J-897D01*
G03X767969Y112497I1503J0D01*
G01X767976Y112486D01*
X768006Y112397D01*
G02X768017Y112333I-189J-65D01*
G01Y111688D01*
G03X768047Y111583I200J0D01*
G01X768101Y111498D01*
G02X768126Y111429I-172J-101D01*
G01Y111427D01*
G02X768129Y111396I-197J-35D01*
G01Y109734D01*
G02X768107Y109643I-200J0D01*
G02X768071Y109593I-178J90D01*
G01X767137Y108659D01*
G02X767020Y108602I-141J141D01*
G01X766953Y108594D01*
X766925Y108591D01*
G02X766912Y108590I-22J198D01*
G01X730361D01*
G02X730269Y108613I1J200D01*
G01X730268D01*
X730192Y108653D01*
G02X730152Y108680I91J178D01*
G01X730136Y108694D01*
X730122Y108713D01*
G03X727212I-1455J-1063D01*
G01X727198Y108694D01*
X727182Y108680D01*
G02X727142Y108653I-131J151D01*
G01X727066Y108613D01*
X727065D01*
G02X726973Y108590I-93J177D01*
G01X710740D01*
G02X710646Y108614I1J200D01*
G01X710619Y108628D01*
X709540Y109707D01*
X709513Y109754D01*
X709507Y109780D01*
G03X708421Y110866I-1456J-370D01*
G01X708395Y110872D01*
X708348Y110899D01*
X708286Y110961D01*
G02X708250Y111011I142J140D01*
G02X708228Y111102I178J91D01*
G01Y114907D01*
X708315Y115015D01*
X708384Y115031D01*
G03Y117961I-333J1465D01*
G01X708315Y117977D01*
X708228Y118085D01*
Y122963D01*
X708328Y123076D01*
X708404Y123085D01*
G03Y126067I-181J1491D01*
G01X708328Y126076D01*
X708228Y126189D01*
Y159263D01*
G02X708232Y159301I200J-2D01*
G02X708285Y159403I196J-37D01*
G01X709152Y160270D01*
G02X709254Y160323I139J-143D01*
G02X709292Y160327I40J-196D01*
G01X744809D01*
G03X744951Y160386I0J200D01*
G01X748656Y164091D01*
G03X748715Y164233I-141J142D01*
G01Y201567D01*
G02X748737Y201657I200J-1D01*
G01X748746Y201676D01*
X748767Y201702D01*
X749344Y202279D01*
G02X749446Y202332I139J-143D01*
G02X749484Y202336I40J-196D01*
G01X759184D01*
G02X759360Y202230I-1J-200D01*
G01X759502Y201961D01*
G03X759504Y201959I142J140D01*
G01X759527Y201916D01*
G02X759548Y201815I-179J-90D01*
G01X759547Y201793D01*
X759544Y201756D01*
X759515Y201712D01*
G02X759513Y201710I-140J138D01*
G03X759252Y200864I1241J-846D01*
G03X762256I1502J0D01*
G03X761994Y201711I-1502J-1D01*
G01X761979Y201733D01*
X761962Y201783D01*
X761960Y201815D01*
G02X761983Y201917I200J9D01*
G01Y201918D01*
X762148Y202230D01*
G02X762324Y202336I177J-94D01*
G01X765836D01*
G02X765977Y202278I0J-200D01*
G01X768017Y200238D01*
X768032Y200207D01*
G03X768086Y200106I1351J657D01*
G01X768100Y200083D01*
X768124Y199997D01*
G02X768129Y199954I-195J-44D01*
G01Y197600D01*
G02X768096Y197490I-200J0D01*
G03Y195840I1254J-825D01*
G02X768129Y195730I-167J-110D01*
G01Y193600D01*
Y193596D01*
G02X768096Y193490I-200J4D01*
G03Y191840I1254J-825D01*
G02X768129Y191734I-167J-110D01*
G01Y187512D01*
G02X768128Y187492I-200J0D01*
G03X768108Y186103I1335J-714D01*
G02X768129Y186013I-179J-89D01*
G01Y181600D01*
Y181596D01*
G02X768096Y181490I-200J4D01*
G03Y179840I1254J-825D01*
G02X768129Y179734I-167J-110D01*
G01Y177600D01*
Y177596D01*
G02X768096Y177490I-200J4D01*
G03Y175840I1254J-825D01*
G02X768129Y175734I-167J-110D01*
G01Y173600D01*
Y173596D01*
G02X768096Y173490I-200J4D01*
G03Y171840I1254J-825D01*
G02X768129Y171734I-167J-110D01*
G01Y169600D01*
Y169596D01*
G02X768096Y169490I-200J4D01*
G03Y167840I1254J-825D01*
G02X768129Y167734I-167J-110D01*
G01Y163086D01*
G02X768127Y163057I-200J-1D01*
G02X768077Y162951I-198J29D01*
G01X768017Y162888D01*
G02X767974Y162853I-147J136D01*
G02X767960Y162846I-96J175D01*
G01X767868Y162801D01*
X767835Y162797D01*
G03Y159815I181J-1491D01*
G01X767868Y159811D01*
X767960Y159766D01*
G02X767974Y159759I-82J-182D01*
G02X768017Y159724I-104J-171D01*
G01X768077Y159661D01*
G02X768127Y159555I-148J-135D01*
G02X768129Y159526I-198J-28D01*
G01Y151308D01*
G02X767929Y151108I-200J0D01*
G37*
G36*
G01X785039Y1526936D02*
X785040D01*
G03X801653Y1535285I0J20702D01*
G01X801692Y1535338D01*
X801814Y1535377D01*
X802237Y1535237D01*
G02X802374Y1535047I-63J-190D01*
G01Y1480479D01*
G02X802290Y1480316I-200J0D01*
G01X801985Y1480099D01*
X801890Y1480085D01*
X801844Y1480101D01*
G03X801355Y1480183I-490J-1420D01*
G01X801354D01*
G03Y1477179I0J-1502D01*
G01X801355D01*
G03X801844Y1477261I-1J1502D01*
G01X801890Y1477277D01*
X801985Y1477263D01*
X802290Y1477046D01*
G02X802374Y1476883I-116J-163D01*
G01Y1467172D01*
G02X802235Y1466982I-200J1D01*
G01X802234D01*
G03Y1464116I450J-1433D01*
G01X802235D01*
G02X802374Y1463926I-61J-191D01*
G01Y1463397D01*
G02X802315Y1463255I-200J0D01*
G01X801749Y1462689D01*
X801721Y1462660D01*
X801647Y1462630D01*
X795523D01*
G02X795204Y1463271I0J400D01*
G03X795508Y1464177I-1199J906D01*
G01Y1464178D01*
G03X792502I-1503J0D01*
G01Y1464177D01*
G03X792852Y1463213I1503J0D01*
G02X792776Y1462630I-307J-256D01*
G01X792447D01*
X792043Y1462226D01*
G03X792007Y1462191I1028J-1094D01*
G01X787384Y1457567D01*
G02X787242Y1457508I-142J141D01*
G01X785538D01*
G03X785483Y1457507I0J-1502D01*
G01X784916D01*
X784513Y1457104D01*
G03X784476Y1457068I1029J-1094D01*
G01X779162Y1451753D01*
X779155Y1451745D01*
X779133Y1451723D01*
X779060Y1451694D01*
X777725D01*
G03Y1448692I0J-1501D01*
G01X780347D01*
X780750Y1449096D01*
G03X780787Y1449131I-1013J1108D01*
G01X784432Y1452776D01*
G02X784634Y1452825I141J-142D01*
G01X785027Y1452699D01*
X785100Y1452615D01*
X785109Y1452559D01*
G03X786591Y1451301I1482J244D01*
G03X788093Y1452803I0J1502D01*
G03X787300Y1454128I-1503J0D01*
G01X787251Y1454154D01*
X787195Y1454248D01*
Y1454304D01*
G02X787395Y1454504I200J0D01*
G01X787946D01*
G03X788001Y1454505I0J1502D01*
G01X788568D01*
X788971Y1454908D01*
G03X789008Y1454944I-1029J1094D01*
G01X789071Y1455007D01*
G02X789237Y1455064I141J-141D01*
G01X789541Y1455026D01*
G02X789554Y1455024I-24J-198D01*
G01X789605Y1455014D01*
X789675Y1454965D01*
X789697Y1454928D01*
G03X790989Y1454193I1292J768D01*
G03X792491Y1455695I0J1502D01*
G03X791755Y1456987I-1502J0D01*
G01X791715Y1457011D01*
X791665Y1457088D01*
X791620Y1457447D01*
G02X791677Y1457613I198J25D01*
G01X793632Y1459569D01*
G02X793634Y1459571I142J-140D01*
G02X793774Y1459628I140J-143D01*
G01X799582D01*
G03X799588I3J200D01*
G01X799648D01*
X799746Y1459568D01*
X799919Y1459200D01*
G02X799926Y1459048I-181J-85D01*
G01X799899Y1458974D01*
X799879Y1458948D01*
G03X799555Y1458016I1178J-932D01*
G03X799557Y1457936I1502J-2D01*
G02X799499Y1457785I-200J-10D01*
G01X799288Y1457574D01*
G02X799137Y1457516I-141J142D01*
G03X799057Y1457518I-78J-1500D01*
G03Y1454514I0J-1502D01*
G03X800080Y1454916I0J1503D01*
G01X800124Y1454957D01*
X800241Y1454977D01*
X800632Y1454806D01*
G02X800752Y1454623I-80J-183D01*
G01Y1450551D01*
G02X800632Y1450368I-200J0D01*
G01X800241Y1450197D01*
X800124Y1450217D01*
X800080Y1450258D01*
G03X799057Y1450660I-1023J-1101D01*
G03Y1447656I0J-1502D01*
G03X799137Y1447658I2J1502D01*
G02X799288Y1447600I10J-200D01*
G01X799499Y1447389D01*
G02X799557Y1447238I-142J-141D01*
G03X799555Y1447158I1500J-78D01*
G03X800611Y1445724I1502J0D01*
G01X800612D01*
G02X800752Y1445533I-60J-191D01*
G01Y1444070D01*
G03X800811Y1443928I200J0D01*
G01X802021Y1442718D01*
G03X802163Y1442659I142J141D01*
G01X803818D01*
G02X803835Y1442658I-3J-200D01*
G02X803974Y1442584I-17J-199D01*
G02X803984Y1442570I-158J-123D01*
G01X804152Y1442318D01*
G02X804185Y1442206I-167J-110D01*
G01Y1442105D01*
X804171Y1442069D01*
G03X804067Y1441520I1398J-549D01*
G01Y1441519D01*
G03X807071I1502J0D01*
G01Y1441520D01*
G03X806953Y1442105I-1502J1D01*
G01X806933Y1442151D01*
X806943Y1442251D01*
X807154Y1442569D01*
G02X807168Y1442589I170J-104D01*
G02X807303Y1442658I152J-130D01*
G02X807320Y1442659I20J-199D01*
G01X825851D01*
G02X825993Y1442318I0J-200D01*
G01X825851Y1442176D01*
G02X825773Y1442128I-141J142D01*
G01X825752Y1442121D01*
G03X824702Y1440689I451J-1432D01*
G03X826204Y1439187I1502J0D01*
G03X827635Y1440235I0J1501D01*
G02X827636Y1440238I190J-62D01*
G01X827650Y1440281D01*
X827675Y1440320D01*
X827692Y1440337D01*
X828857Y1441501D01*
G02X828999Y1441560I142J-141D01*
G01X834828D01*
G02X834981Y1441489I0J-200D01*
G01X835175Y1441260D01*
G02X835222Y1441131I-153J-129D01*
G01Y1441094D01*
X835220Y1441079D01*
G03X835202Y1440852I1484J-232D01*
G01Y1440849D01*
G03X836704Y1439347I1502J0D01*
G03X837896Y1439937I0J1499D01*
G01X837904Y1439947D01*
X837928Y1439971D01*
G02X837979Y1440008I141J-141D01*
G01X837980Y1440009D01*
G02X838069Y1440030I89J-179D01*
G01X838433Y1440032D01*
X838517Y1439991D01*
X838546Y1439953D01*
X838548Y1439951D01*
X838556Y1439941D01*
G03X839744Y1439357I1188J916D01*
G03X841246Y1440859I0J1502D01*
G03X841227Y1441096I-1502J-1D01*
G01X841220Y1441140D01*
X841244Y1441223D01*
X841471Y1441490D01*
G02X841623Y1441560I152J-130D01*
G01X856056D01*
G03X856976Y1441942I-1J1302D01*
G01X857636Y1442601D01*
G02X857777Y1442659I141J-142D01*
G01X879957D01*
G02X880143Y1442532I0J-200D01*
G01X880301Y1442127D01*
X880273Y1442007D01*
X880227Y1441965D01*
G03X879742Y1440860I1017J-1105D01*
G01Y1440859D01*
G03X882746I1502J0D01*
G01Y1440860D01*
G03X882261Y1441965I-1502J0D01*
G01X882215Y1442007D01*
X882187Y1442127D01*
X882345Y1442532D01*
G02X882531Y1442659I186J-73D01*
G01X890957D01*
G02X891143Y1442532I0J-200D01*
G01X891301Y1442127D01*
X891273Y1442007D01*
X891227Y1441965D01*
G03X890742Y1440860I1017J-1105D01*
G01Y1440859D01*
G03X893746I1502J0D01*
G01Y1440860D01*
G03X893261Y1441965I-1502J0D01*
G01X893215Y1442007D01*
X893187Y1442127D01*
X893345Y1442532D01*
G02X893531Y1442659I186J-73D01*
G01X917998D01*
G02X918031Y1442656I-2J-200D01*
G02X918138Y1442602I-32J-197D01*
G01X919147Y1441593D01*
G02X919206Y1441451I-141J-142D01*
G01Y1425537D01*
X919176Y1425463D01*
X919147Y1425435D01*
X918662Y1424950D01*
G02X918520Y1424891I-142J141D01*
G01X813587D01*
G02X813406Y1425004I-1J200D01*
G01X813253Y1425325D01*
G02X813252Y1425497I180J87D01*
G01X813272Y1425540D01*
X813286Y1425557D01*
G03X813606Y1426483I-1182J927D01*
G03X810602I-1502J0D01*
G03X810934Y1425543I1502J2D01*
G01X810970Y1425497D01*
X810983Y1425383D01*
X810802Y1425005D01*
G02X810622Y1424891I-181J86D01*
G01X801888D01*
G02X801699Y1425025I0J200D01*
G01X801553Y1425442D01*
X801588Y1425564D01*
X801638Y1425604D01*
G03X802205Y1426779I-934J1175D01*
G03X799201I-1502J0D01*
G03X799768Y1425604I1501J0D01*
G01X799818Y1425564D01*
X799853Y1425442D01*
X799707Y1425025D01*
G02X799518Y1424891I-189J66D01*
G01X787608D01*
G02X787568Y1424895I0J200D01*
G01X787529Y1424903D01*
G02X787490Y1424915I39J196D01*
G01X787455Y1424930D01*
X787236Y1425252D01*
G02X787203Y1425343I166J112D01*
G01X787198Y1425394D01*
X787217Y1425443D01*
G03X787322Y1425993I-1395J551D01*
G03X785820Y1427495I-1502J0D01*
G03X784369Y1426384I0J-1503D01*
G01Y1426383D01*
X784358Y1426344D01*
X784335Y1426313D01*
G02X784275Y1426261I-158J122D01*
G01X783993Y1426100D01*
X783914Y1426090D01*
X783875Y1426101D01*
G03X783469Y1426157I-406J-1446D01*
G03X782017Y1425040I0J-1502D01*
G01Y1425039D01*
G02X781824Y1424891I-193J52D01*
G01X736256D01*
G02X736114Y1424950I0J200D01*
G01X728497Y1432567D01*
X728468Y1432595D01*
X728438Y1432669D01*
Y1623474D01*
X728486Y1623562D01*
X728529Y1623590D01*
X728808Y1623773D01*
G02X728855Y1623796I111J-167D01*
G01X728856D01*
G02X728918Y1623806I62J-190D01*
G01X728999Y1623789D01*
G03X729600Y1623663I602J1375D01*
G03Y1626667I0J1502D01*
G01X729598D01*
G03X728997Y1626541I1J-1501D01*
G01X728950Y1626520D01*
X728850Y1626528D01*
X728529Y1626740D01*
X728486Y1626768D01*
X728438Y1626856D01*
Y1626968D01*
G02X728495Y1627108I200J0D01*
G01X731711Y1630324D01*
G02X731713Y1630326I142J-140D01*
G02X731853Y1630383I140J-143D01*
G01X760960D01*
G02X761342Y1629864I0J-400D01*
G03X761273Y1629415I1434J-450D01*
G03X764279I1503J0D01*
G03X764210Y1629864I-1503J-1D01*
G02X764592Y1630383I382J119D01*
G01X799696D01*
G02X799838Y1630324I0J-200D01*
G01X802315Y1627847D01*
G02X802317Y1627845I-140J-142D01*
G02X802374Y1627705I-143J-140D01*
G01Y1560229D01*
G02X802237Y1560039I-200J0D01*
G01X801814Y1559899D01*
X801692Y1559938D01*
X801653Y1559991D01*
G03X785040Y1568340I-16613J-12353D01*
G01X785039D01*
G03Y1526936I0J-20702D01*
G37*
G36*
G01X799468Y54588D02*
X827614D01*
X827756Y54446D01*
Y52733D01*
X827614Y52591D01*
X799468D01*
G03X793531Y46654I0J-5937D01*
G01Y7874D01*
G02X787657Y2000I-5874J0D01*
G01X740413D01*
G02X734539Y7874I0J5874D01*
G01Y46261D01*
X736536D01*
Y7874D01*
G03X740411Y3998I3876J0D01*
G01X787657D01*
G03X791534Y7874I0J3877D01*
G01Y46654D01*
G02X799468Y54588I7934J0D01*
G37*
G36*
G01X745121Y275932D02*
X767056D01*
X767130Y275902D01*
X767158Y275873D01*
X767769Y275262D01*
G02X767828Y275120I-141J-142D01*
G01Y205020D01*
X767798Y204946D01*
X767769Y204918D01*
X766248Y203397D01*
G02X766106Y203338I-142J141D01*
G01X745239D01*
X745165Y203368D01*
X745137Y203397D01*
X744979Y203555D01*
G02X744921Y203696I142J141D01*
G01Y204858D01*
G02X744981Y205001I200J0D01*
G01X745215Y205230D01*
X745289Y205259D01*
X745329Y205258D01*
X745363D01*
G03Y208262I0J1502D01*
G01X745329D01*
X745289Y208261D01*
X745215Y208290D01*
X744981Y208519D01*
G02X744921Y208661I140J143D01*
G01Y255107D01*
G02X745039Y255289I200J0D01*
G01X745363Y255436D01*
G02X745534Y255432I81J-183D01*
G01X745584Y255407D01*
X745603Y255392D01*
G03X746577Y255033I975J1143D01*
G03Y258037I0J1502D01*
G03X745603Y257678I1J-1502D01*
G01X745584Y257663D01*
X745534Y257638D01*
G02X745363Y257634I-90J179D01*
G01X745039Y257781D01*
G02X744921Y257963I82J182D01*
G01Y275732D01*
G02X745121Y275932I200J0D01*
G37*
G36*
G01X780650Y242420D02*
G03X780787Y242428I-2J1210D01*
G01X780799Y242429D01*
X783960D01*
X783972Y242428D01*
G03X784108Y242420I139J1202D01*
G01X788572D01*
G02X788608Y242417I1J-200D01*
G01X788625Y242414D01*
G02X788728Y242361I-36J-197D01*
G01X788917Y242180D01*
G02X788978Y242046I-139J-144D01*
G01Y242042D01*
G03X789378Y241077I1501J57D01*
G01X789380Y241075D01*
X789383Y241072D01*
G03X789389Y241065I1143J974D01*
G01X789391Y241063D01*
X789396Y241057D01*
G03X790498Y240576I1102J1022D01*
G03X792000Y242057I0J1502D01*
G01X792001Y242098D01*
X792032Y242170D01*
X792206Y242338D01*
X792229Y242360D01*
G02X792333Y242414I140J-143D01*
G01X792368Y242420D01*
X796233D01*
G03X796374Y242428I2J1210D01*
G01X799776D01*
G03X799917Y242420I139J1202D01*
G01X806509D01*
G02X806604Y242396I0J-200D01*
G01X806630Y242382D01*
X809104Y239908D01*
X809116Y239895D01*
X809157Y239854D01*
G02X809180Y239762I-177J-93D01*
G01Y153175D01*
G02X809177Y153139I-200J-1D01*
G01X809166Y153081D01*
X809133Y153023D01*
X809107Y153000D01*
G03X808803Y147733I2440J-2783D01*
G01X808821Y147713D01*
X808822Y147711D01*
G03X809012Y147517I2738J2492D01*
G03X809065Y147469I2511J2719D01*
G01X809066Y147468D01*
G03X809083Y147452I2545J2687D01*
G01X809099Y147437D01*
X809123Y147404D01*
X809163Y147312D01*
G02X809180Y147232I-183J-81D01*
G01Y125108D01*
X809169Y125076D01*
G03X809083Y124576I1416J-501D01*
G03X809169Y124076I1502J1D01*
G01X809180Y124044D01*
Y122986D01*
G03X809195Y122910I200J0D01*
G01X809215Y122863D01*
G02X809230Y122786I-185J-76D01*
G01Y117488D01*
G02X809193Y117371I-200J-1D01*
G03X808911Y116496I1220J-876D01*
G03X809193Y115621I1502J1D01*
G02X809230Y115504I-163J-116D01*
G01Y110681D01*
G03X809243Y110611I200J1D01*
G02X809255Y110527I-188J-70D01*
G01X809246Y110411D01*
G02X809207Y110306I-199J14D01*
G03X808911Y109410I1206J-895D01*
G03X810413Y107908I1502J0D01*
G03X811345Y108232I0J1502D01*
G01X811406Y108280D01*
X811556Y108272D01*
X812160Y107668D01*
G03X812302Y107609I142J141D01*
G01X812877D01*
X812898Y107605D01*
X812901D01*
G03X812915Y107602I259J1173D01*
G01X812918D01*
X812932Y107600D01*
X812933D01*
X812934D01*
G03X813003Y107592I173J1189D01*
G03X813100Y107588I98J1198D01*
G01X829027D01*
G02X829226Y107389I-1J-200D01*
G01Y104249D01*
G03X829244Y103999I1803J4D01*
G01Y103997D01*
G03X829248Y103974I1777J297D01*
G01Y103972D01*
G03X829258Y103915I1780J283D01*
G01X829263Y103886D01*
X829257Y103829D01*
X829246Y103802D01*
G02X829175Y103713I-185J75D01*
G01X829145Y103692D01*
X829042Y103620D01*
G03X828252Y103845I-790J-1274D01*
G03X826750Y102343I0J-1502D01*
G03X827171Y101300I1502J0D01*
G01X827174Y101297D01*
X827176Y101295D01*
G03X828271Y100821I1095J1028D01*
G03X829771Y102242I0J1502D01*
G01Y102244D01*
G02X829865Y102402I200J-12D01*
G01X830004Y102488D01*
X830184Y102600D01*
X830281Y102608D01*
X830326Y102589D01*
G03X831020Y102446I704J1660D01*
G01X831029D01*
G03X832832Y104249I0J1803D01*
G01Y107389D01*
G02X833031Y107588I200J-1D01*
G01X869275D01*
G02X869415Y107531I0J-200D01*
G01X869416Y107530D01*
X870830Y106116D01*
G02X870889Y105974I-141J-142D01*
G01Y98638D01*
G02X870827Y98493I-200J0D01*
G01X870587Y98264D01*
X870511Y98236D01*
X870469Y98238D01*
G03X870395Y98240I-78J-1500D01*
G03X868893Y96738I0J-1502D01*
G03X868945Y96345I1502J-1D01*
G01X868958Y96297D01*
X868936Y96201D01*
X868656Y95874D01*
X868564Y95838D01*
X868514Y95843D01*
G03X868344Y95853I-173J-1492D01*
G03X869846Y94351I0J-1502D01*
G03X869794Y94744I-1502J1D01*
G01X869781Y94792D01*
X869803Y94888D01*
X870083Y95215D01*
X870175Y95251D01*
X870225Y95246D01*
G03X870395Y95236I173J1492D01*
G03X870654Y95259I-3J1502D01*
G01X870672Y95262D01*
X870689D01*
G02X870889Y95062I0J-200D01*
G01Y94814D01*
X870877Y94781D01*
G03X870804Y94080I1416J-502D01*
G03X870829Y93938I1490J189D01*
G01X870830Y93937D01*
G03X870877Y93777I1463J343D01*
G01X870889Y93744D01*
Y87557D01*
X870822Y87457D01*
X870766Y87433D01*
G03Y84659I574J-1387D01*
G01X870822Y84635D01*
X870889Y84535D01*
Y62345D01*
Y62331D01*
X870882Y62237D01*
X870773Y62139D01*
G03X870765Y62131I137J-145D01*
G01X870606Y61971D01*
X870535Y61941D01*
X870495Y61940D01*
G03X869416Y61457I25J-1502D01*
G01X869386Y61425D01*
X869307Y61392D01*
X868919Y61402D01*
X868842Y61439D01*
X868814Y61473D01*
G03X867659Y62015I-1155J-960D01*
G03Y59011I0J-1502D01*
G03X868762Y59494I0J1501D01*
G01X868792Y59526D01*
X868871Y59559D01*
X869259Y59549D01*
X869336Y59512D01*
X869364Y59478D01*
G03X870495Y58936I1155J960D01*
G01X870534D01*
X870607Y58905D01*
X870782Y58728D01*
X870831Y58678D01*
G02X870888Y58552I-142J-140D01*
G01X870889Y58538D01*
Y54060D01*
G02X870830Y53918I-200J0D01*
G01X869628Y52716D01*
G02X869486Y52657I-142J141D01*
G01X850956D01*
G02X850814Y52716I0J200D01*
G01X845673Y57857D01*
G03X845576Y57911I-142J-141D01*
G01X845538Y57920D01*
X845477Y57962D01*
X845251Y58297D01*
X845241Y58395D01*
X845260Y58442D01*
G03X845882Y61614I-7780J3173D01*
G03X843562Y67411I-8403J0D01*
G03X837461Y70036I-6101J-5777D01*
G03X829059Y61634I0J-8402D01*
G03X829672Y58485I8402J1D01*
G01X829679Y58467D01*
X829687Y58425D01*
G02X829657Y58275I-196J-39D01*
G01X829474Y58004D01*
G02X829308Y57916I-166J112D01*
G01X822163D01*
G02X821985Y58026I1J200D01*
G01X821812Y58367D01*
X821821Y58479D01*
X821854Y58525D01*
G03X822563Y60519I-2988J2185D01*
G01X822566Y60588D01*
G03X822544Y61129I-3700J121D01*
G03X822465Y61575I-3678J-421D01*
G03X822431Y61706I-3599J-864D01*
G01Y61707D01*
X822426Y61723D01*
G03X822124Y62466I-3560J-1014D01*
G01X822100Y62511D01*
Y62611D01*
X822290Y62963D01*
X822374Y63018D01*
X822425Y63022D01*
G03X824838Y69456I-319J3789D01*
G01X824837Y69457D01*
G03X820618Y70338I-2750J-2626D01*
G03X818738Y65032I1469J-3507D01*
G01X818739Y65029D01*
X818745Y65017D01*
X818751Y65003D01*
G02X818736Y64817I-184J-79D01*
G01X818733Y64813D01*
X818563Y64528D01*
G02X818391Y64430I-172J102D01*
G01X811547D01*
G03X807846Y60729I0J-3701D01*
G01Y60727D01*
G03X808554Y58552I3701J2D01*
G01X808587Y58506D01*
X808596Y58393D01*
X808548Y58300D01*
X808410Y58027D01*
G02X808328Y57943I-178J92D01*
G01X808326Y57941D01*
G02X808228Y57916I-97J175D01*
G01X771534D01*
G02X771392Y57975I0J200D01*
G01X770627Y58740D01*
G02X770586Y58962I142J141D01*
G01Y58963D01*
X770736Y59302D01*
G02X770817Y59393I183J-81D01*
G01X770845Y59410D01*
X770901Y59424D01*
X770930Y59422D01*
X770936D01*
G03X771011Y59420I78J1500D01*
G03Y62424I0J1502D01*
G03X770329Y62260I0J-1502D01*
G01X770282Y62236D01*
X770179Y62240D01*
X769843Y62446D01*
G02X769748Y62616I105J170D01*
G01Y84597D01*
G02X769770Y84689I200J1D01*
G01X769822Y84789D01*
X769851Y84823D01*
X769870Y84837D01*
G03Y87255I-891J1209D01*
G01X769851Y87269D01*
X769822Y87303D01*
X769770Y87403D01*
G02X769748Y87495I178J91D01*
G01Y92536D01*
X769778Y92607D01*
X769806Y92636D01*
X769916Y92747D01*
X769982Y92777D01*
X770020Y92780D01*
G03X771433Y94279I-89J1499D01*
G03X770057Y95776I-1502J0D01*
G01X770053D01*
G02X769926Y95840I21J199D01*
G01X769742Y96039D01*
G02X769689Y96175I147J136D01*
G01Y108877D01*
G02X769802Y109058I200J1D01*
G01X769803D01*
G03X770348Y109500I-648J1355D01*
G01X770357Y109512D01*
X770367Y109522D01*
X770379Y109534D01*
G02X770491Y109590I141J-142D01*
G01X770535Y109597D01*
X770802Y109636D01*
X770879Y109616D01*
X770911Y109591D01*
G03X771824Y109282I913J1194D01*
G03X773111Y110009I0J1503D01*
G01X773125Y110031D01*
X773159Y110066D01*
X773261Y110125D01*
G02X773301Y110143I101J-172D01*
G02X773338Y110152I66J-189D01*
G02X773362Y110153I20J-199D01*
G01X773573D01*
G02X773670Y110128I0J-200D01*
G01X773771Y110072D01*
X773807Y110037D01*
X773821Y110015D01*
G03X774020Y109759I1279J789D01*
G01X774022Y109757D01*
X774024Y109755D01*
G03X775118Y109282I1094J1029D01*
G03X776620Y110784I0J1502D01*
G03X776199Y111827I-1502J0D01*
G01X776196Y111830D01*
X776189Y111837D01*
G03X775099Y112306I-1090J-1032D01*
G03X773798Y111555I0J-1502D01*
G02X773625Y111455I-173J100D01*
G01X773286D01*
G02X773114Y111553I0J200D01*
G03X772918Y111813I-1290J-769D01*
G01X772915Y111816D01*
X772911Y111821D01*
G03X772908Y111824I-1064J-1061D01*
G01X772907Y111825D01*
G03X771805Y112306I-1102J-1022D01*
G03X770613Y111718I0J-1502D01*
G01X770604Y111706D01*
X770594Y111696D01*
X770582Y111684D01*
G02X770470Y111628I-141J142D01*
G01X770194Y111587D01*
X770109Y111574D01*
G03X769998Y111658I-961J-1154D01*
G01X769979Y111671D01*
X769947Y111706D01*
X769891Y111807D01*
G02X769866Y111904I175J97D01*
G01Y111924D01*
G02X769891Y112021I200J0D01*
G01X769908Y112051D01*
G02X769974Y112122I175J-97D01*
G01X769976Y112123D01*
X769977D01*
G03X770677Y113394I-804J1271D01*
G03X770272Y114420I-1502J0D01*
G01X770270Y114422D01*
X770266Y114426D01*
G03X770262Y114431I-1175J-936D01*
G03X770260Y114433I-142J-140D01*
G03X769803Y114770I-1104J-1019D01*
G01X769750Y114795D01*
X769689Y114892D01*
Y115049D01*
G02X769805Y115231I200J0D01*
G03X770677Y116594I-629J1363D01*
G03X770642Y116921I-1502J5D01*
G03X770247Y117647I-1467J-328D01*
G01X770246Y117648D01*
G03X770080Y117797I-1083J-1040D01*
G01X770061Y117812D01*
X770032Y117848D01*
X770021Y117870D01*
G02X770002Y117956I181J85D01*
G01Y118190D01*
G02X770023Y118278I200J-1D01*
G01X770070Y118374D01*
X770097Y118408D01*
X770114Y118421D01*
G03X770677Y119594I-940J1173D01*
G03X770272Y120620I-1502J0D01*
G01X770270Y120622D01*
X770266Y120626D01*
G03X770262Y120631I-1175J-936D01*
G03X770260Y120633I-142J-140D01*
G03X769803Y120970I-1104J-1019D01*
G01X769750Y120995D01*
X769689Y121092D01*
Y122677D01*
X769784Y122789D01*
X769856Y122801D01*
G03X770695Y125321I-247J1482D01*
G01X770693Y125323D01*
X770691Y125326D01*
G03X769854Y125782I-1100J-1023D01*
G01X769782Y125795D01*
X769689Y125905D01*
Y131939D01*
G02X769810Y132123I200J0D01*
G01X770203Y132292D01*
X770320Y132271D01*
X770364Y132229D01*
G03X770512Y132105I1038J1088D01*
G01X770542Y132083D01*
X770581Y132024D01*
X770618Y131862D01*
X770648Y131735D01*
G02X770651Y131664I-195J-44D01*
G01X770647Y131630D01*
X770630Y131596D01*
X770629Y131594D01*
G03X770458Y130898I1331J-696D01*
G03X773462I1502J0D01*
G03X772847Y132110I-1502J0D01*
G01X772817Y132132D01*
X772778Y132191D01*
X772727Y132410D01*
Y132412D01*
X772711Y132482D01*
G02X772728Y132618I195J45D01*
G01X772729Y132619D01*
Y132620D01*
G03X772827Y132850I-1328J702D01*
G01Y132851D01*
X772828Y132853D01*
G02X772915Y132962I190J-62D01*
G01X773172Y133115D01*
X773204Y133121D01*
G03X773565Y133077I361J1459D01*
G03X775067Y134579I0J1502D01*
G03X774646Y135622I-1502J0D01*
G01X774643Y135625D01*
X774636Y135632D01*
G03X773546Y136101I-1090J-1032D01*
G03X772118Y135066I0J-1503D01*
G01X772117Y135064D01*
G02X772030Y134955I-190J62D01*
G01X771773Y134802D01*
X771703Y134789D01*
X771667Y134796D01*
G03X771400Y134820I-267J-1478D01*
G01X771399D01*
G03X770364Y134407I0J-1503D01*
G01X770320Y134365D01*
X770203Y134344D01*
X769810Y134513D01*
G02X769689Y134697I79J184D01*
G01Y167050D01*
G02X769725Y167163I200J-1D01*
G01Y167164D01*
G02X769825Y167240I165J-113D01*
G01X769826D01*
G03X770843Y168489I-475J1425D01*
G01X770846Y168520D01*
G03X770853Y168664I-1495J145D01*
G01Y168692D01*
G03X770430Y169710I-1502J-27D01*
G01X770427Y169713D01*
X770422Y169718D01*
G03X769835Y170100I-1090J-1033D01*
G01X769824Y170104D01*
X769800Y170116D01*
G02X769689Y170295I89J179D01*
G01Y171050D01*
G02X769725Y171163I200J-1D01*
G01Y171164D01*
G02X769825Y171240I165J-113D01*
G01X769826D01*
G03X770843Y172489I-475J1425D01*
G01X770846Y172520D01*
G03X770853Y172664I-1495J145D01*
G01Y172692D01*
G03X770430Y173710I-1502J-27D01*
G01X770427Y173713D01*
X770422Y173718D01*
G03X769835Y174100I-1090J-1033D01*
G01X769824Y174104D01*
X769800Y174116D01*
G02X769689Y174295I89J179D01*
G01Y175050D01*
G02X769725Y175163I200J-1D01*
G01Y175164D01*
G02X769825Y175240I165J-113D01*
G01X769826D01*
G03X770843Y176489I-475J1425D01*
G01X770846Y176520D01*
G03X770853Y176664I-1495J145D01*
G01Y176692D01*
G03X770430Y177710I-1502J-27D01*
G01X770427Y177713D01*
X770422Y177718D01*
G03X769835Y178100I-1090J-1033D01*
G01X769824Y178104D01*
X769800Y178116D01*
G02X769689Y178295I89J179D01*
G01Y179050D01*
G02X769725Y179163I200J-1D01*
G01Y179164D01*
G02X769825Y179240I165J-113D01*
G01X769826D01*
G03X770843Y180489I-475J1425D01*
G01X770846Y180520D01*
G03X770853Y180664I-1495J145D01*
G01Y180692D01*
G03X770430Y181710I-1502J-27D01*
G01X770427Y181713D01*
X770422Y181718D01*
G03X769835Y182100I-1090J-1033D01*
G01X769824Y182104D01*
X769800Y182116D01*
G02X769689Y182295I89J179D01*
G01Y185199D01*
X769772Y185306D01*
X769839Y185324D01*
G03X770966Y186778I-374J1454D01*
G03X770953Y186978I-1502J3D01*
G01X770952Y186988D01*
G03X770545Y187821I-1488J-211D01*
G01X770543Y187823D01*
X770536Y187831D01*
G03X769839Y188247I-1090J-1034D01*
G01X769837Y188248D01*
X769832Y188250D01*
G02X769689Y188441I57J192D01*
G01Y191050D01*
G02X769725Y191163I200J-1D01*
G01Y191164D01*
G02X769825Y191240I165J-113D01*
G01X769826D01*
G03X770843Y192489I-475J1425D01*
G01X770846Y192520D01*
G03X770853Y192664I-1495J145D01*
G01Y192692D01*
G03X770430Y193710I-1502J-27D01*
G01X770427Y193713D01*
X770422Y193718D01*
G03X769835Y194100I-1090J-1033D01*
G01X769824Y194104D01*
X769800Y194116D01*
G02X769689Y194295I89J179D01*
G01Y195015D01*
G02X769724Y195128I200J0D01*
G01X769797Y195236D01*
X769844Y195272D01*
X769873Y195284D01*
G03X769835Y198100I-541J1401D01*
G01X769824Y198104D01*
X769800Y198116D01*
G02X769689Y198295I89J179D01*
G01Y199305D01*
X769766Y199410D01*
X769830Y199430D01*
G03X770875Y200688I-447J1434D01*
G01X770880Y200732D01*
G03X770886Y200864I-1497J134D01*
G03X770467Y201905I-1503J0D01*
G01X770465Y201907D01*
X770453Y201919D01*
G03X769827Y202313I-1089J-1035D01*
G01X769797Y202323D01*
X769746Y202359D01*
X769728Y202385D01*
G02X769689Y202503I161J119D01*
G01Y203305D01*
X769766Y203410D01*
X769830Y203430D01*
G03X770875Y204688I-447J1434D01*
G01X770880Y204732D01*
G03X770886Y204864I-1497J134D01*
G03X770467Y205905I-1503J0D01*
G01X770465Y205907D01*
X770453Y205919D01*
G03X769827Y206313I-1089J-1035D01*
G01X769797Y206323D01*
X769746Y206359D01*
X769728Y206385D01*
G02X769689Y206503I161J119D01*
G01Y207305D01*
X769766Y207410D01*
X769830Y207430D01*
G03X770875Y208688I-447J1434D01*
G01X770880Y208732D01*
G03X770886Y208864I-1497J134D01*
G03X770467Y209905I-1503J0D01*
G01X770465Y209907D01*
X770453Y209919D01*
G03X769827Y210313I-1089J-1035D01*
G01X769797Y210323D01*
X769746Y210359D01*
X769728Y210385D01*
G02X769689Y210503I161J119D01*
G01Y211305D01*
X769766Y211410D01*
X769830Y211430D01*
G03X770875Y212688I-447J1434D01*
G01X770880Y212732D01*
G03X770886Y212864I-1497J134D01*
G03X770467Y213905I-1503J0D01*
G01X770465Y213907D01*
X770453Y213919D01*
G03X769827Y214313I-1089J-1035D01*
G01X769797Y214323D01*
X769746Y214359D01*
X769728Y214385D01*
G02X769689Y214503I161J119D01*
G01Y215305D01*
X769766Y215410D01*
X769830Y215430D01*
G03X770875Y216688I-447J1434D01*
G01X770880Y216732D01*
G03X770886Y216864I-1497J134D01*
G03X770467Y217905I-1503J0D01*
G01X770465Y217907D01*
X770453Y217919D01*
G03X769827Y218313I-1089J-1035D01*
G01X769797Y218323D01*
X769746Y218359D01*
X769728Y218385D01*
G02X769689Y218503I161J119D01*
G01Y220305D01*
X769766Y220410D01*
X769830Y220430D01*
G03X770875Y221688I-447J1434D01*
G01X770880Y221732D01*
G03X770886Y221864I-1497J134D01*
G03X770467Y222905I-1503J0D01*
G01X770465Y222907D01*
X770453Y222919D01*
G03X769827Y223313I-1089J-1035D01*
G01X769797Y223323D01*
X769746Y223359D01*
X769728Y223385D01*
G02X769689Y223503I161J119D01*
G01Y241469D01*
G02X769748Y241611I200J0D01*
G01X770531Y242394D01*
X770610Y242424D01*
X770653Y242422D01*
G03X770716Y242420I70J1208D01*
G01X780650D01*
G37*
G36*
G01X769822Y276294D02*
X844796D01*
G02X844938Y276235I0J-200D01*
G01X846222Y274951D01*
G02X846224Y274949I-140J-142D01*
G02X846281Y274809I-143J-140D01*
G01Y267385D01*
G02X846168Y267205I-200J0D01*
G01X845791Y267023D01*
X845678Y267036D01*
X845632Y267072D01*
G03X844698Y267398I-934J-1175D01*
G03Y264394I0J-1502D01*
G03X845632Y264720I0J1501D01*
G01X845678Y264756D01*
X845791Y264769D01*
X846168Y264587D01*
G02X846281Y264407I-87J-180D01*
G01Y257901D01*
X846227Y257809D01*
X846182Y257782D01*
X846180D01*
X845892Y257613D01*
G02X845818Y257588I-100J174D01*
G01X845777Y257583D01*
X845684Y257608D01*
X845662Y257620D01*
G03X844940Y257805I-723J-1319D01*
G01X844939D01*
G03Y254801I0J-1502D01*
G01X844940D01*
G03X845662Y254986I-1J1504D01*
G01X845684Y254998D01*
X845738Y255013D01*
G02X845818Y255018I52J-193D01*
G01X845857Y255013D01*
X846181Y254824D01*
G02X846184Y254822I-109J-167D01*
G02X846281Y254651I-103J-171D01*
G01Y207215D01*
G02X846279Y207189I-200J2D01*
G01X846274Y207148D01*
X846271Y207137D01*
G03X846223Y206760I1454J-377D01*
G01Y206690D01*
G03X846224Y206670I200J0D01*
G01X846231Y206603D01*
G03X846258Y206434I1495J152D01*
G01X846265Y206407D01*
X846266Y206405D01*
G03X846270Y206388I1464J335D01*
G01Y206384D01*
G03X846274Y206371I1437J435D01*
G01X846281Y206345D01*
Y202582D01*
G03X846340Y202440I200J0D01*
G01X846761Y202019D01*
G03X846903Y201960I142J141D01*
G01X849621D01*
G02X849654Y201957I-2J-200D01*
G02X849761Y201903I-32J-197D01*
G01X850076Y201588D01*
Y193725D01*
G02X849990Y193561I-200J0D01*
G01X849739Y193386D01*
G02X849625Y193350I-114J164D01*
G01X849538D01*
X849507Y193361D01*
G03X849017Y193443I-490J-1420D01*
G01X849001D01*
G03X847515Y191941I16J-1502D01*
G03X849017Y190439I1502J0D01*
G01X849020D01*
G03X849538Y190532I-2J1502D01*
G01X849584Y190549D01*
X849681Y190537D01*
X849990Y190321D01*
G02X850076Y190157I-114J-164D01*
G01Y165175D01*
G02X850017Y165034I-200J1D01*
G01X846550Y161567D01*
X846522Y161538D01*
X846448Y161508D01*
X839434D01*
G02X839263Y161604I0J200D01*
G01X839086Y161896D01*
G02X839070Y161930I172J102D01*
G02X839081Y162094I188J70D01*
G01X839084Y162100D01*
X839101Y162135D01*
G03X839253Y162788I-1350J658D01*
G01Y162790D01*
Y162815D01*
G03X838850Y163817I-1502J-22D01*
G01X838849Y163818D01*
G02X838793Y163957I144J139D01*
G01Y164268D01*
X838820Y164338D01*
X838847Y164366D01*
G03Y166420I-1096J1027D01*
G01X838820Y166448D01*
X838793Y166518D01*
Y166868D01*
X838820Y166938D01*
X838847Y166966D01*
G03X839253Y167993I-1096J1027D01*
G03X838883Y168980I-1501J0D01*
G01X838859Y169008D01*
X838834Y169074D01*
Y169412D01*
X838859Y169478D01*
X838883Y169506D01*
G03X839253Y170493I-1131J987D01*
G03X836249I-1502J0D01*
G03X836619Y169506I1501J0D01*
G01X836643Y169478D01*
X836668Y169412D01*
Y169074D01*
X836643Y169008D01*
X836619Y168980D01*
G03X836249Y167993I1131J-987D01*
G03X836655Y166966I1502J0D01*
G01X836682Y166938D01*
X836709Y166868D01*
Y166518D01*
X836682Y166448D01*
X836655Y166420D01*
G03Y164366I1096J-1027D01*
G01X836682Y164338D01*
X836709Y164268D01*
Y163918D01*
X836682Y163849D01*
X836655Y163820D01*
G03X836249Y162821I1096J-1027D01*
G01Y162812D01*
Y162793D01*
G03X836401Y162135I1502J0D01*
G01X836429Y162077D01*
G02X836432Y161930I-185J-77D01*
G02X836416Y161896I-188J68D01*
G01X836239Y161605D01*
X836212Y161559D01*
X836121Y161508D01*
X832497D01*
G02X832339Y161585I0J200D01*
G01X832116Y161870D01*
X832097Y161959D01*
X832108Y162005D01*
G03X832153Y162368I-1457J365D01*
G03X830651Y163870I-1502J0D01*
G03X829624Y163464I0J-1502D01*
G01X829596Y163437D01*
X829526Y163410D01*
X829176D01*
X829106Y163437D01*
X829078Y163464D01*
G03X828051Y163870I-1027J-1096D01*
G03X826549Y162368I0J-1502D01*
G03X826594Y162005I1502J2D01*
G01X826605Y161959D01*
X826586Y161870D01*
X826363Y161585D01*
G02X826205Y161508I-158J123D01*
G01X811057D01*
G02X810915Y161567I0J200D01*
G01X810259Y162223D01*
G02X810201Y162364I142J141D01*
G01Y240157D01*
G03X810142Y240298I-200J-1D01*
G01X809845Y240595D01*
X809843Y240598D01*
G03X809830Y240611I-856J-843D01*
G01X809829Y240612D01*
X807362Y243079D01*
G03X807332Y243108I-850J-849D01*
G01X807088Y243352D01*
G03X806948Y243410I-141J-142D01*
G01X806732D01*
X806715Y243413D01*
G03X806514Y243430I-201J-1185D01*
G01X799919D01*
G02X799761Y243507I0J200D01*
G01X799538Y243793D01*
X799519Y243882D01*
X799531Y243928D01*
G03X799577Y244297I-1457J369D01*
G03X798075Y245799I-1502J0D01*
G03X797708Y245753I2J-1502D01*
G01X797652Y245739D01*
X797545Y245773D01*
X797237Y246131D01*
X797219Y246242D01*
X797241Y246295D01*
G03X797357Y246874I-1387J579D01*
G03X795855Y248376I-1502J0D01*
G03X794826Y247968I0J-1502D01*
G01X794792Y247936D01*
X794706Y247909D01*
X794352Y247958D01*
G02X794344Y247959I21J199D01*
G02X794207Y248055I36J197D01*
G03X792913Y248794I-1294J-763D01*
G03Y245790I0J-1502D01*
G03X793942Y246198I0J1502D01*
G01X793976Y246230D01*
X794062Y246257D01*
X794462Y246201D01*
X794537Y246151D01*
X794561Y246111D01*
G03X795855Y245372I1294J763D01*
G03X795934Y245374I1J1502D01*
G01X795935D01*
G03X795997Y245378I-66J1501D01*
G01X796031Y245382D01*
G03X796113Y245394I-176J1492D01*
G01X796114D01*
G03X796222Y245418I-272J1477D01*
G01X796278Y245432D01*
X796385Y245398D01*
X796693Y245040D01*
X796710Y244930D01*
X796688Y244876D01*
G03X796582Y244474I1387J-581D01*
G01X796577Y244419D01*
G03X796572Y244297I1498J-122D01*
G01Y244295D01*
G03X796618Y243927I1503J1D01*
G01X796630Y243881D01*
X796611Y243792D01*
X796389Y243507D01*
G02X796231Y243430I-158J123D01*
G01X792379D01*
G03X792180Y243413I2J-1201D01*
G01X792163Y243410D01*
X791216D01*
X791170Y243422D01*
X791151Y243431D01*
X791149Y243432D01*
G03X790907Y243523I-648J-1355D01*
G03X790247Y243559I-410J-1445D01*
G03X789843Y243430I250J-1481D01*
G01X789823Y243420D01*
X789779Y243410D01*
X788795D01*
X788778Y243413D01*
G03X788579Y243430I-201J-1184D01*
G01X784110D01*
G02X783943Y243520I0J200D01*
G01X783744Y243824D01*
X783740Y243875D01*
X783736Y243924D01*
X783748Y243952D01*
Y243953D01*
X783757Y243973D01*
G03X783881Y244571I-1378J598D01*
G01Y244590D01*
G03X780877I-1502J-19D01*
G01Y244570D01*
G03X781002Y243971I1502J1D01*
G01X781022Y243925D01*
X781018Y243875D01*
X781014Y243824D01*
X780816Y243521D01*
X780788Y243478D01*
X780700Y243430D01*
X770718D01*
G02X770576Y243489I0J200D01*
G01X768987Y245078D01*
X768958Y245106D01*
X768928Y245180D01*
Y275400D01*
G02X768985Y275540I200J0D01*
G01X768986Y275541D01*
X769680Y276235D01*
G02X769682Y276237I142J-140D01*
G02X769822Y276294I140J-143D01*
G37*
G36*
G01X864686Y202336D02*
X868198D01*
G02X868339Y202278I0J-200D01*
G01X870379Y200238D01*
X870394Y200207D01*
G03X870433Y200132I1352J655D01*
G01X870434Y200131D01*
G03X870449Y200105I1308J738D01*
G01X870462Y200083D01*
X870478Y200027D01*
X870491Y199981D01*
Y197600D01*
G02X870458Y197490I-200J0D01*
G03Y195840I1254J-825D01*
G02X870491Y195730I-167J-110D01*
G01Y193600D01*
G02X870458Y193490I-200J0D01*
G03Y191840I1254J-825D01*
G02X870491Y191730I-167J-110D01*
G01Y187518D01*
X870481Y187475D01*
X870470Y187453D01*
G03Y186103I1355J-675D01*
G01X870481Y186081D01*
X870491Y186038D01*
Y181600D01*
G02X870458Y181490I-200J0D01*
G03Y179840I1254J-825D01*
G02X870491Y179730I-167J-110D01*
G01Y177600D01*
G02X870458Y177490I-200J0D01*
G03Y175840I1254J-825D01*
G02X870491Y175730I-167J-110D01*
G01Y173600D01*
G02X870458Y173490I-200J0D01*
G03Y171840I1254J-825D01*
G02X870491Y171730I-167J-110D01*
G01Y169600D01*
G02X870458Y169490I-200J0D01*
G03Y167840I1254J-825D01*
G02X870491Y167730I-167J-110D01*
G01Y117138D01*
X870379Y116958D01*
Y111688D01*
G03X870409Y111583I200J0D01*
G01X870460Y111504D01*
G02X870491Y111396I-169J-107D01*
G01Y109734D01*
G02X870432Y109592I-200J0D01*
G01X869489Y108649D01*
G02X869347Y108590I-142J141D01*
G01X832675D01*
G02X832511Y108676I0J200D01*
G03X829547I-1482J-1027D01*
G02X829383Y108590I-164J114D01*
G01X813102D01*
G02X812960Y108649I0J200D01*
G01X811901Y109708D01*
X811876Y109753D01*
X811869Y109780D01*
G03X810783Y110866I-1456J-370D01*
G01X810756Y110873D01*
X810711Y110898D01*
X810649Y110960D01*
G02X810590Y111102I141J142D01*
G01Y114907D01*
X810677Y115016D01*
X810746Y115031D01*
G03Y117961I-333J1465D01*
G01X810677Y117976D01*
X810590Y118085D01*
Y122963D01*
X810690Y123076D01*
X810766Y123085D01*
G03Y126067I-181J1491D01*
G01X810690Y126076D01*
X810590Y126189D01*
Y159263D01*
G02X810649Y159405I200J0D01*
G01X811512Y160268D01*
G02X811654Y160327I142J-141D01*
G01X847171D01*
G03X847313Y160386I0J200D01*
G01X851018Y164091D01*
G03X851077Y164233I-141J142D01*
G01Y201567D01*
G02X851136Y201709I200J0D01*
G01X851704Y202277D01*
G02X851846Y202336I142J-141D01*
G01X861546D01*
G02X861723Y202229I0J-200D01*
G01X861887Y201916D01*
G02X861876Y201711I-177J-93D01*
G01X861875Y201710D01*
G03X861614Y200873I1241J-846D01*
G01Y200845D01*
G03X864618I1502J19D01*
G01Y200865D01*
G03X864357Y201711I-1502J0D01*
G01X864325Y201757D01*
X864319Y201867D01*
X864509Y202229D01*
G02X864686Y202336I177J-93D01*
G37*
G36*
G01X805971Y1459628D02*
X822409D01*
G02X822594Y1459504I0J-200D01*
G01X822617Y1459447D01*
X822594Y1459330D01*
X822174Y1458910D01*
G03X822115Y1458768I141J-142D01*
G01Y1458505D01*
G02X822056Y1458363I-200J0D01*
G01X822029Y1458336D01*
X819764D01*
G03X819622Y1458277I0J-200D01*
G01X819287Y1457942D01*
G03X819228Y1457800I141J-142D01*
G01Y1446396D01*
G02X819169Y1446254I-200J0D01*
G01X818882Y1445967D01*
G02X818740Y1445908I-142J141D01*
G01X806246D01*
G02X806104Y1445967I0J200D01*
G01X805830Y1446241D01*
G02X805771Y1446383I141J142D01*
G01Y1459428D01*
G02X805971Y1459628I200J0D01*
G37*
G36*
G01X822554Y1626504D02*
X927703D01*
G02X927845Y1626445I0J-200D01*
G01X932332Y1621958D01*
G02X932391Y1621816I-141J-142D01*
G01Y1585734D01*
G03X932450Y1585592I200J0D01*
G01X940497Y1577545D01*
G03X940639Y1577486I142J141D01*
G01X956366D01*
G02X956508Y1577427I0J-200D01*
G01X960090Y1573845D01*
G02X960149Y1573703I-141J-142D01*
G01Y1545224D01*
G03X960208Y1545082I200J0D01*
G01X960222Y1545068D01*
Y1543190D01*
G03X960281Y1543048I200J0D01*
G01X964685Y1538644D01*
G03X964827Y1538585I142J141D01*
G01X1020051D01*
G02X1020193Y1538526I0J-200D01*
G01X1031736Y1526983D01*
G02X1031795Y1526841I-141J-142D01*
G01Y1492779D01*
G02X1031736Y1492637I-200J0D01*
G01X1031447Y1492348D01*
G02X1031305Y1492289I-142J141D01*
G01X957250D01*
X957246Y1492293D01*
X947172D01*
G02X947030Y1492352I0J200D01*
G01X944500Y1494882D01*
G03X944358Y1494941I-142J-141D01*
G01X933345D01*
G03X933203Y1494882I0J-200D01*
G01X917090Y1478769D01*
G03X917031Y1478627I141J-142D01*
G01Y1464953D01*
G02X916972Y1464811I-200J0D01*
G01X914131Y1461970D01*
G03X914072Y1461828I141J-142D01*
G01Y1460856D01*
G02X914013Y1460714I-200J0D01*
G01X913858Y1460559D01*
X913852D01*
X913446Y1460153D01*
G03X913387Y1460011I141J-142D01*
G01Y1446377D01*
G02X913328Y1446235I-200J0D01*
G01X913012Y1445919D01*
G02X912870Y1445860I-142J141D01*
G01X900424D01*
G02X900282Y1445919I0J200D01*
G01X900057Y1446144D01*
G02X899998Y1446286I141J142D01*
G01Y1459953D01*
G03X899939Y1460095I-200J0D01*
G01X899336Y1460698D01*
G02X899277Y1460840I141J142D01*
G01Y1462388D01*
G03X899218Y1462530I-200J0D01*
G01X894243Y1467505D01*
G02X894184Y1467647I141J142D01*
G01Y1473419D01*
G03X894125Y1473561I-200J0D01*
G01X888556Y1479130D01*
G03X888414Y1479189I-142J-141D01*
G01X880246D01*
G03X880104Y1479130I0J-200D01*
G01X872204Y1471230D01*
G03X872145Y1471088I141J-142D01*
G01Y1463614D01*
G02X871945Y1463414I-200J0D01*
G01X854476D01*
G02X854335Y1463473I1J200D01*
G01X853265Y1464543D01*
G03X853123Y1464602I-142J-141D01*
G01X828106D01*
G03X827964Y1464543I0J-200D01*
G01X826987Y1463566D01*
G03X826928Y1463424I141J-142D01*
G01Y1462830D01*
G02X826728Y1462630I-200J0D01*
G01X806535D01*
G02X806335Y1462830I0J200D01*
G01Y1467878D01*
G02X806429Y1468048I200J0D01*
G01X806762Y1468255D01*
X806865Y1468260D01*
X806912Y1468237D01*
G03X807576Y1468082I664J1347D01*
G03Y1471086I0J1502D01*
G03X806912Y1470931I0J-1502D01*
G01X806865Y1470908D01*
X806762Y1470913D01*
X806429Y1471120D01*
G02X806335Y1471290I106J170D01*
G01Y1474404D01*
G02X806394Y1474546I200J0D01*
G01X806713Y1474865D01*
G03X806772Y1475007I-141J142D01*
G01Y1523862D01*
G02X806831Y1524004I200J0D01*
G01X816897Y1534070D01*
G03X816956Y1534212I-141J142D01*
G01Y1620906D01*
G02X817015Y1621048I200J0D01*
G01X822412Y1626445D01*
G02X822554Y1626504I142J-141D01*
G37*
G36*
G01X993061Y831633D02*
G03X993144Y831635I5J1502D01*
G01X993145D01*
G02X993292Y831581I10J-200D01*
G01X993503Y831381D01*
G02X993566Y831236I-137J-146D01*
G01Y830480D01*
X993505Y830383D01*
X993452Y830358D01*
G03Y827642I642J-1358D01*
G01X993505Y827617D01*
X993566Y827520D01*
Y812449D01*
G02X993507Y812307I-200J0D01*
G01X993447Y812247D01*
X993415Y812232D01*
G03Y809510I636J-1361D01*
G01X993447Y809495D01*
X993507Y809435D01*
G02X993509Y809433I-140J-142D01*
G02X993566Y809293I-143J-140D01*
G01Y807502D01*
X993536Y807428D01*
X993507Y807400D01*
X987458Y801351D01*
X987430Y801322D01*
X987356Y801292D01*
X979056D01*
G02X978898Y801370I0J200D01*
G01X978676Y801659D01*
X978658Y801749D01*
X978670Y801794D01*
G03X978720Y802178I-1452J384D01*
G03X975716I-1502J0D01*
G03X975766Y801794I1502J0D01*
G01X975778Y801749D01*
X975760Y801659D01*
X975538Y801370D01*
G02X975380Y801292I-158J122D01*
G01X968899D01*
X968800Y801357D01*
X968776Y801412D01*
X968642Y801716D01*
G02X968626Y801859I178J92D01*
G02X968634Y801885I195J-46D01*
G01X968666Y801962D01*
X968689Y801988D01*
G03X969064Y802981I-1127J993D01*
G01Y803016D01*
G03X966060I-1502J-34D01*
G01Y802981D01*
G03X966435Y801988I1502J0D01*
G01X966458Y801962D01*
X966490Y801885D01*
G02X966501Y801847I-186J-74D01*
G02X966504Y801824I-197J-37D01*
G02X966488Y801729I-200J-15D01*
G01X966354Y801426D01*
G02X966223Y801300I-189J66D01*
G02X966165Y801292I-56J192D01*
G01X955947D01*
X955873Y801322D01*
X955845Y801351D01*
X949852Y807344D01*
X949823Y807372D01*
X949793Y807446D01*
Y809633D01*
G03X949734Y809775I-200J0D01*
G01X948090Y811419D01*
G03X947948Y811478I-142J-141D01*
G01X923336D01*
G02X923264Y811491I-1J200D01*
G01X923227Y811506D01*
X923170Y811559D01*
X923154Y811594D01*
G03X920426I-1364J-629D01*
G01X920401Y811541D01*
X920303Y811478D01*
X919403D01*
X919293Y811569D01*
X919279Y811641D01*
G03X916327I-1476J-275D01*
G01X916313Y811569D01*
X916203Y811478D01*
X915575D01*
X915500Y811510D01*
X915472Y811539D01*
X915471Y811540D01*
X915273Y811747D01*
G02X915231Y811814I145J138D01*
G01X915216Y811852D01*
X915217Y811899D01*
Y811900D01*
G03X915218Y811954I-1501J55D01*
G03X912214I-1502J0D01*
G03X912215Y811900I1502J1D01*
G01Y811899D01*
X912216Y811852D01*
X912201Y811814D01*
G02X912159Y811747I-187J71D01*
G01X911961Y811540D01*
X911960Y811539D01*
X911932Y811510D01*
X911857Y811478D01*
X911279D01*
X911227Y811479D01*
X911108Y811544D01*
G02X911038Y811609I97J175D01*
G01X911037Y811610D01*
G03X909786Y812280I-1251J-833D01*
G01X909785D01*
G03X908854Y811957I0J-1503D01*
G01X908809Y811921D01*
X908696Y811909D01*
X908319Y812091D01*
G02X908206Y812271I87J180D01*
G01Y812813D01*
G03X907824Y813735I-1306J-1D01*
G01X906093Y815466D01*
G02X906034Y815608I141J142D01*
G01Y826083D01*
G02X906074Y826203I200J0D01*
G01X906089Y826223D01*
X908249Y828383D01*
G02X908323Y828430I142J-141D01*
G01X908327Y828431D01*
G03X909386Y829866I-443J1435D01*
G03X907884Y831368I-1502J0D01*
G03X906450Y830313I0J-1502D01*
G01X906449Y830309D01*
X906448Y830305D01*
G02X906401Y830231I-188J68D01*
G01X903804Y827634D01*
G03X903422Y826712I924J-923D01*
G01Y814981D01*
G03X903804Y814059I1306J1D01*
G01X905384Y812479D01*
G02X905440Y812306I-141J-141D01*
G01X905433Y812259D01*
X905376Y812181D01*
X904966Y811974D01*
X904854Y811983D01*
X904808Y812017D01*
G03X903916Y812311I-893J-1208D01*
G03X902625Y811576I0J-1501D01*
G02X902453Y811478I-172J102D01*
G01X868435D01*
G02X868294Y811537I1J200D01*
G01X868118Y811713D01*
X868117D01*
X867894Y811936D01*
G02X867844Y812055I150J133D01*
G01Y815497D01*
G03X867258Y816912I-2001J0D01*
G01X863476Y820694D01*
G02X863426Y820813I150J133D01*
G01Y822751D01*
G02X863516Y822918I200J0D01*
G01X863771Y823086D01*
G02X863881Y823119I110J-167D01*
G01X863949D01*
X864021Y823105D01*
X864036Y823099D01*
G03X864575Y822998I541J1401D01*
G01X864593D01*
G03X866077Y824500I-18J1502D01*
G03X864575Y826002I-1502J0D01*
G03X863601Y825643I0J-1501D01*
G01X863569Y825616D01*
X863529Y825604D01*
X863490Y825591D01*
X863119Y825633D01*
X863048Y825673D01*
X863023Y825706D01*
X863021Y825708D01*
X863013Y825719D01*
G03X861425Y826502I-1588J-1219D01*
G03X860833Y826412I1J-2002D01*
G03X859424Y824500I593J-1912D01*
G01Y819903D01*
G02X859365Y819761I-200J0D01*
G01X859164Y819562D01*
G03X859162Y819560I140J-142D01*
G01X859135Y819533D01*
X859062Y819502D01*
X859000D01*
G03Y816498I0J-1502D01*
G03X860368Y817378I0J1503D01*
G01X860389Y817423D01*
X860465Y817483D01*
X860836Y817551D01*
G02X861013Y817496I36J-197D01*
G01X862264Y816245D01*
X863792Y814718D01*
G02X863842Y814599I-150J-133D01*
G01Y811678D01*
G02X863642Y811478I-200J0D01*
G01X859268D01*
X859251Y811481D01*
G03X859001Y811502I-250J-1481D01*
G01X859000D01*
G03X858750Y811481I0J-1502D01*
G01X858732Y811478D01*
X851297D01*
G02X851134Y811562I0J200D01*
G01X850956Y811813D01*
X850938Y811839D01*
X850919Y811897D01*
Y811961D01*
G02X850922Y811993I200J-3D01*
G01X850929Y812038D01*
X850933Y812051D01*
G03X851002Y812500I-1433J450D01*
G03X850632Y813487I-1501J0D01*
G01X850608Y813515D01*
X850583Y813581D01*
Y813919D01*
X850608Y813985D01*
X850632Y814013D01*
G03Y815987I-1131J987D01*
G01X850608Y816015D01*
X850583Y816081D01*
Y816419D01*
X850608Y816485D01*
X850632Y816513D01*
G03X851002Y817500I-1131J987D01*
G03X847998I-1502J0D01*
G03X848368Y816513I1501J0D01*
G01X848392Y816485D01*
X848417Y816419D01*
Y816081D01*
X848392Y816015D01*
X848368Y815987D01*
G03Y814013I1131J-987D01*
G01X848392Y813985D01*
X848417Y813919D01*
Y813581D01*
X848392Y813515D01*
X848368Y813487D01*
G03X847998Y812500I1131J-987D01*
G03X848081Y812010I1502J2D01*
G01X848097Y811964D01*
X848084Y811869D01*
X847866Y811562D01*
G02X847703Y811478I-163J116D01*
G01X845369D01*
G03X845227Y811419I0J-200D01*
G01X837891Y804083D01*
G03X837832Y803941I141J-142D01*
G01Y759136D01*
X837802Y759062D01*
X837773Y759034D01*
X832606Y753867D01*
X832578Y753838D01*
X832504Y753808D01*
X824220D01*
X824146Y753838D01*
X824118Y753867D01*
X823698Y754287D01*
G02X823662Y754522I141J142D01*
G02X823879Y754625I177J-93D01*
G01X823912Y754618D01*
X823930Y754611D01*
G03X824500Y754498I572J1389D01*
G03X822998Y756000I0J1502D01*
G01Y755962D01*
X823000Y755901D01*
X822934Y755798D01*
X822536Y755627D01*
G02X822316Y755669I-79J184D01*
G01X818883Y759102D01*
G02X818845Y759333I141J142D01*
G01X818852Y759346D01*
X818863Y759371D01*
X818864Y759373D01*
G03X819002Y760000I-1364J629D01*
G01Y760001D01*
G03X818921Y760487I-1502J-1D01*
G01X818916Y760502D01*
X818910Y760535D01*
Y760612D01*
X818919Y760641D01*
G03X818983Y761075I-1438J434D01*
G01Y761078D01*
G03X818379Y762282I-1502J0D01*
G01X818368Y762290D01*
X818345Y762313D01*
G02X818286Y762461I141J142D01*
G01X818298Y762838D01*
X818346Y762924D01*
X818389Y762950D01*
G03X819086Y764219I-807J1269D01*
G03X817584Y765721I-1502J0D01*
G03X817211Y765673I4J-1502D01*
G01X817165Y765661D01*
X817075Y765679D01*
X816786Y765904D01*
G02X816709Y766062I123J158D01*
G01Y798319D01*
G03X816650Y798461I-200J0D01*
G01X816258Y798853D01*
G02X816199Y798995I141J142D01*
G01Y816442D01*
G02X816267Y816592I200J0D01*
G01X816289Y816612D01*
X816646Y816775D01*
G02X816861Y816744I84J-182D01*
G03X817845Y816377I984J1136D01*
G03Y819381I0J1502D01*
G01X817844D01*
G03X816860Y819014I0J-1503D01*
G01X816815Y818975D01*
X816700Y818958D01*
X816316Y819134D01*
G02X816199Y819316I83J182D01*
G01Y822554D01*
G02X816279Y822714I200J0D01*
G01X816300Y822730D01*
X816306Y822734D01*
G03Y825266I-805J1266D01*
G01X816300Y825270D01*
X816279Y825286D01*
G02X816199Y825446I120J160D01*
G01Y828547D01*
X816274Y828651D01*
X816336Y828671D01*
G03X816337Y831523I-473J1426D01*
G01X816335D01*
G02X816199Y831713I64J190D01*
G01Y836378D01*
Y836382D01*
G02X816289Y836545I200J-4D01*
G01X816320Y836565D01*
X816355Y836574D01*
X816357D01*
G03X816368Y839496I-340J1462D01*
G01X816353Y839499D01*
X816323Y839512D01*
G02X816199Y839697I76J185D01*
G01Y843986D01*
X816287Y844095D01*
X816356Y844110D01*
G03Y847046I-319J1468D01*
G01X816287Y847061D01*
X816199Y847170D01*
Y848072D01*
G02X816258Y848214I200J0D01*
G01X816650Y848606D01*
G03X816709Y848748I-141J142D01*
G01Y871026D01*
G02X816766Y871166I200J0D01*
G01X816767Y871167D01*
X825901Y880301D01*
G02X825903Y880303I142J-140D01*
G02X826043Y880360I140J-143D01*
G01X833817D01*
G03X833869Y880358I84J1499D01*
G01X833871D01*
G03X833923Y880360I-32J1501D01*
G01X835610D01*
G02X835752Y880301I0J-200D01*
G01X835764Y880289D01*
X835900Y880118D01*
G02X835937Y879940I-156J-125D01*
G01X835930Y879915D01*
G03X835881Y879534I1453J-381D01*
G01Y879530D01*
G03X837383Y878028I1502J0D01*
G01X837384D01*
G03X837595Y878043I-1J1502D01*
G01X837615Y878046D01*
X837620D01*
G03X838507Y878457I-153J1494D01*
G01X838513Y878463D01*
X838543Y878487D01*
X838570Y878504D01*
G02X838685Y878537I110J-167D01*
G01X838966Y878529D01*
X839008Y878528D01*
X839083Y878493D01*
X839111Y878462D01*
G03X840234Y877957I1123J996D01*
G03X841736Y879459I0J1502D01*
G01Y879460D01*
G03X841683Y879853I-1502J-2D01*
G01Y879854D01*
X841671Y879899D01*
X841680Y879946D01*
G02X841717Y880029I196J-38D01*
G01X841909Y880281D01*
G02X841914Y880287I156J-125D01*
G01Y880288D01*
G02X842068Y880360I154J-128D01*
G01X844042D01*
G02X844201Y880281I0J-200D01*
G01X844386Y880038D01*
G02X844389Y880034I-158J-122D01*
G02X844427Y879917I-162J-117D01*
G01Y879855D01*
X844424Y879841D01*
X844423Y879838D01*
X844420Y879826D01*
G03X844374Y879460I1456J-369D01*
G01Y879459D01*
G03X845876Y877957I1502J0D01*
G03X846865Y878329I0J1502D01*
G01X846893Y878354D01*
X846960Y878379D01*
X847300D01*
X847367Y878354D01*
X847395Y878329D01*
G03X848384Y877957I989J1130D01*
G01X848385D01*
G03X849459Y878410I-1J1502D01*
G01X849460Y878411D01*
X849465Y878416D01*
G02X849525Y878457I141J-142D01*
G01X849636Y878507D01*
X849932D01*
X850043Y878457D01*
G02X850103Y878416I-81J-183D01*
G01X850108Y878411D01*
X850109Y878410D01*
G03X851184Y877957I1075J1049D01*
G01X851222D01*
G03X852686Y879447I-38J1502D01*
G01Y879460D01*
G03X852633Y879853I-1502J-2D01*
G01Y879854D01*
X852621Y879899D01*
X852630Y879946D01*
G02X852667Y880029I196J-38D01*
G01X852859Y880281D01*
G02X852864Y880287I156J-125D01*
G01Y880288D01*
G02X853018Y880360I154J-128D01*
G01X857365D01*
G02X857507Y880301I0J-200D01*
G01X857521Y880287D01*
X857746Y880015D01*
X857768Y879930D01*
X857759Y879885D01*
G03X857732Y879601I1475J-284D01*
G01Y879600D01*
G03X858847Y878149I1502J0D01*
G02X858989Y878008I-51J-193D01*
G01X859079Y877674D01*
G02X859075Y877558I-193J-51D01*
G01X859074Y877555D01*
X859072Y877550D01*
G02X859026Y877478I-188J69D01*
G01X853214Y871666D01*
X853112Y871638D01*
X853060Y871652D01*
X852773Y871726D01*
G02X852757Y871731I52J193D01*
G02X852638Y871845I67J189D01*
G01X852633Y871858D01*
X852630Y871868D01*
G03X851184Y872961I-1446J-410D01*
G01X851183D01*
G03X850109Y872508I1J-1502D01*
G01X850108Y872507D01*
X850103Y872502D01*
G02X850043Y872461I-141J142D01*
G01X849932Y872411D01*
X849636D01*
X849525Y872461D01*
G02X849465Y872502I81J183D01*
G01X849460Y872507D01*
X849459Y872508D01*
G03X848384Y872961I-1075J-1049D01*
G01X848346D01*
G03X846882Y871459I38J-1502D01*
G03X848384Y869957I1502J0D01*
G01X848385D01*
G03X849459Y870410I-1J1502D01*
G01X849460Y870411D01*
X849465Y870416D01*
G02X849525Y870457I141J-142D01*
G01X849636Y870507D01*
X849871D01*
G02X849909Y870503I-2J-200D01*
G01X849942Y870497D01*
X849967Y870493D01*
X850077Y870443D01*
X850104Y870415D01*
G03X850329Y870223I1083J1041D01*
G01X850374Y870192D01*
X850419Y870095D01*
X850385Y869740D01*
G02X850265Y869575I-199J19D01*
G03X849361Y868872I920J-2115D01*
G01X849359Y868870D01*
X849336Y868842D01*
X849308Y868824D01*
G02X849243Y868797I-108J168D01*
G01X849160Y868779D01*
X849116Y868789D01*
X849059Y868802D01*
X849039Y868812D01*
G03X848386Y868961I-652J-1353D01*
G01X848363D01*
G03X847353Y868551I21J-1502D01*
G01X847325Y868524D01*
X847288Y868510D01*
X847253Y868495D01*
X846980Y868492D01*
G02X846906Y868505I-3J200D01*
G01X846813Y868541D01*
X846787Y868563D01*
G03X845821Y868915I-966J-1151D01*
G01X845820D01*
G03Y865911I0J-1502D01*
G03X846878Y866347I0J1502D01*
G01X846915Y866362D01*
X846950Y866376D01*
X847224Y866380D01*
G02X847298Y866367I3J-200D01*
G01X847391Y866331D01*
X847417Y866309D01*
G03X848383Y865957I966J1151D01*
G01X848386D01*
G03X849039Y866106I1J1502D01*
G01X849059Y866116D01*
X849116Y866129D01*
X849160Y866139D01*
X849242Y866121D01*
G02X849341Y866067I-42J-195D01*
G01X849355Y866053D01*
X849363Y866043D01*
X849364Y866042D01*
G03X849681Y865710I1818J1419D01*
G01X849714Y865682D01*
X849750Y865606D01*
X849756Y865381D01*
G02X849742Y865302I-200J-5D01*
G01X849726Y865263D01*
X849553Y865090D01*
G03X849358Y864870I1625J-1637D01*
G01X849346Y864854D01*
X849329Y864840D01*
G02X849243Y864798I-128J153D01*
G01X849160Y864779D01*
X849116Y864789D01*
X849059Y864802D01*
X849039Y864812D01*
G03X848386Y864961I-652J-1353D01*
G01X848363D01*
G03X847353Y864551I21J-1502D01*
G01X847325Y864524D01*
X847288Y864510D01*
X847253Y864495D01*
X846980Y864492D01*
G02X846906Y864505I-3J200D01*
G01X846813Y864541D01*
X846787Y864563D01*
G03X845821Y864915I-966J-1151D01*
G01X845820D01*
G03Y861911I0J-1502D01*
G03X846878Y862347I0J1502D01*
G01X846915Y862362D01*
X846950Y862376D01*
X847224Y862380D01*
G02X847298Y862367I3J-200D01*
G01X847391Y862331D01*
X847417Y862309D01*
G03X848383Y861957I966J1151D01*
G01X848386D01*
G03X849039Y862106I1J1502D01*
G01X849059Y862116D01*
X849116Y862129D01*
X849160Y862139D01*
X849243Y862121D01*
G02X849308Y862094I-43J-195D01*
G01X849336Y862076D01*
X849359Y862048D01*
X849361Y862046D01*
G03X850265Y861343I1824J1412D01*
G02X850385Y861178I-79J-184D01*
G01X850419Y860823D01*
X850374Y860726D01*
X850329Y860695D01*
G03X850105Y860504I858J-1233D01*
G01X850077Y860475D01*
X849970Y860428D01*
X849931Y860411D01*
X849702D01*
G02X849663Y860415I1J200D01*
G01X849623Y860423D01*
G02X849583Y860435I37J197D01*
G01X849493Y860474D01*
X849465Y860503D01*
G03X848385Y860961I-1080J-1044D01*
G01X848383D01*
G03X847849Y860863I0J-1502D01*
G01X847832Y860857D01*
X847799Y860850D01*
G02X847723I-38J197D01*
G01X847690Y860857D01*
X847673Y860863D01*
G03X847140Y860961I-534J-1404D01*
G01X847138D01*
G03Y857957I0J-1502D01*
G01X847140D01*
G03X847673Y858055I-1J1502D01*
G01X847690Y858061D01*
X847723Y858068D01*
G02X847799I38J-197D01*
G01X847832Y858061D01*
X847849Y858055D01*
G03X848383Y857957I534J1404D01*
G01X848385D01*
G03X849464Y858414I0J1502D01*
G01X849491Y858443D01*
X849597Y858490D01*
G02X849678Y858507I81J-183D01*
G01X849871D01*
G02X849909Y858503I-2J-200D01*
G01X849942Y858497D01*
X849967Y858493D01*
X850077Y858443D01*
X850104Y858414D01*
G03X851183Y857957I1079J1045D01*
G01X851184D01*
G03X852686Y859459I0J1502D01*
G03X852039Y860694I-1502J0D01*
G01X851994Y860725D01*
X851949Y860822D01*
X851983Y861179D01*
G02X852062Y861320I199J-19D01*
G01X852081Y861334D01*
G03X852815Y861828I-897J2125D01*
G01X857281Y866294D01*
G02X857343Y866336I141J-142D01*
G02X857494Y866340I80J-183D01*
G01X857891Y866190D01*
X857960Y866095D01*
X857964Y866036D01*
G03X858409Y865055I1499J89D01*
G01X858410Y865054D01*
G02X858468Y864924I-142J-141D01*
G01X858485Y864618D01*
X858462Y864547D01*
X858438Y864518D01*
G03X858101Y863570I1165J-948D01*
G03X861105I1502J0D01*
G03X860657Y864640I-1502J0D01*
G01X860656Y864641D01*
G02X860598Y864771I142J141D01*
G01X860581Y865077D01*
X860604Y865148D01*
X860628Y865177D01*
G03X860965Y866125I-1165J948D01*
G03X859552Y867624I-1502J0D01*
G01X859493Y867628D01*
X859398Y867697D01*
X859248Y868094D01*
G02X859251Y868244I187J71D01*
G01X859267Y868280D01*
X871227Y880240D01*
G03X871250Y880263I-1619J1642D01*
G01Y880264D01*
X871254Y880268D01*
G02X871317Y880312I144J-139D01*
G01X871387Y880343D01*
G02X871468Y880360I81J-183D01*
G01X882817D01*
G02X882956Y880304I0J-200D01*
G01X882958Y880302D01*
X883159Y880098D01*
G02X883161Y880096I-140J-142D01*
G02X883217Y879957I-144J-139D01*
G01Y879937D01*
G03X885821I1302J0D01*
G01Y879940D01*
G03X885811Y880104I-1302J3D01*
G01X885809Y880116D01*
Y880117D01*
X885805Y880145D01*
Y880160D01*
G02X886005Y880360I200J0D01*
G01X886183D01*
G02X886383Y880160I0J-200D01*
G01Y880145D01*
X886379Y880117D01*
Y880116D01*
X886377Y880104D01*
G03X886367Y879940I1292J-161D01*
G01Y879937D01*
G03X888971I1302J0D01*
G01Y879940D01*
G03X888961Y880104I-1302J3D01*
G01X888959Y880116D01*
Y880117D01*
X888955Y880145D01*
Y880160D01*
G02X889155Y880360I200J0D01*
G01X889332D01*
G02X889532Y880160I0J-200D01*
G01Y880145D01*
X889528Y880117D01*
Y880116D01*
X889526Y880104D01*
G03X889516Y879940I1292J-161D01*
G01Y879937D01*
G03X892120I1302J0D01*
G01Y879940D01*
G03X892110Y880104I-1302J3D01*
G01X892108Y880116D01*
Y880117D01*
X892104Y880145D01*
Y880160D01*
G02X892304Y880360I200J0D01*
G01X892482D01*
G02X892682Y880160I0J-200D01*
G01Y880145D01*
X892678Y880117D01*
Y880116D01*
X892676Y880104D01*
G03X892666Y879940I1292J-161D01*
G01Y879937D01*
G03X895270I1302J0D01*
G01Y879940D01*
G03X895260Y880104I-1302J3D01*
G01X895258Y880116D01*
Y880117D01*
X895254Y880145D01*
Y880160D01*
G02X895454Y880360I200J0D01*
G01X895632D01*
G02X895832Y880160I0J-200D01*
G01Y880145D01*
X895828Y880117D01*
Y880116D01*
X895826Y880104D01*
G03X895816Y879940I1292J-161D01*
G01Y879937D01*
G03X898420I1302J0D01*
G01Y879940D01*
G03X898410Y880104I-1302J3D01*
G01X898408Y880116D01*
Y880117D01*
X898404Y880145D01*
Y880160D01*
G02X898604Y880360I200J0D01*
G01X898781D01*
G02X898981Y880160I0J-200D01*
G01Y880145D01*
X898977Y880117D01*
Y880116D01*
X898975Y880104D01*
G03X898965Y879940I1292J-161D01*
G01Y879937D01*
G03X901569I1302J0D01*
G01Y879957D01*
G02X901626Y880097I200J0D01*
G01X901826Y880300D01*
G02X901969Y880360I143J-140D01*
G01X904863D01*
G02X905002Y880304I0J-200D01*
G01X905004Y880302D01*
X905205Y880098D01*
G02X905207Y880096I-140J-142D01*
G02X905263Y879957I-144J-139D01*
G01Y879937D01*
G03X907867I1302J0D01*
G01Y879940D01*
G03X907857Y880104I-1302J3D01*
G01X907855Y880116D01*
Y880117D01*
X907851Y880145D01*
Y880160D01*
G02X908051Y880360I200J0D01*
G01X908228D01*
G02X908428Y880160I0J-200D01*
G01Y880145D01*
X908424Y880117D01*
Y880116D01*
X908422Y880104D01*
G03X908412Y879940I1292J-161D01*
G01Y879937D01*
G03X911016I1302J0D01*
G01Y879940D01*
G03X911006Y880104I-1302J3D01*
G01X911004Y880116D01*
Y880117D01*
X911000Y880145D01*
Y880160D01*
G02X911200Y880360I200J0D01*
G01X911378D01*
G02X911578Y880160I0J-200D01*
G01Y880145D01*
X911574Y880117D01*
Y880116D01*
X911572Y880104D01*
G03X911562Y879940I1292J-161D01*
G01Y879937D01*
G03X914166I1302J0D01*
G01Y879940D01*
G03X914156Y880104I-1302J3D01*
G01X914154Y880116D01*
Y880117D01*
X914150Y880145D01*
Y880160D01*
G02X914350Y880360I200J0D01*
G01X914528D01*
G02X914728Y880160I0J-200D01*
G01Y880145D01*
X914724Y880117D01*
Y880116D01*
X914722Y880104D01*
G03X914712Y879940I1292J-161D01*
G01Y879937D01*
G03X917316I1302J0D01*
G01Y879940D01*
G03X917306Y880104I-1302J3D01*
G01X917304Y880116D01*
Y880117D01*
X917300Y880145D01*
Y880160D01*
G02X917500Y880360I200J0D01*
G01X917677D01*
G02X917877Y880160I0J-200D01*
G01Y880145D01*
X917873Y880117D01*
Y880116D01*
X917871Y880104D01*
G03X917861Y879940I1292J-161D01*
G01Y879937D01*
G03X920465I1302J0D01*
G01Y879940D01*
G03X920455Y880104I-1302J3D01*
G01X920453Y880116D01*
Y880117D01*
X920449Y880145D01*
Y880160D01*
G02X920649Y880360I200J0D01*
G01X920827D01*
G02X921027Y880160I0J-200D01*
G01Y880145D01*
X921023Y880117D01*
Y880116D01*
X921021Y880104D01*
G03X921011Y879940I1292J-161D01*
G01Y879937D01*
G03X923615I1302J0D01*
G01Y879940D01*
G03X923605Y880104I-1302J3D01*
G01X923603Y880116D01*
Y880117D01*
X923599Y880145D01*
Y880160D01*
G02X923799Y880360I200J0D01*
G01X923976D01*
G02X924176Y880160I0J-200D01*
G01Y880145D01*
X924172Y880117D01*
Y880116D01*
X924170Y880104D01*
G03X924160Y879940I1292J-161D01*
G01Y879937D01*
G03X926764I1302J0D01*
G01Y879940D01*
G03X926754Y880104I-1302J3D01*
G01X926752Y880116D01*
Y880117D01*
X926748Y880145D01*
Y880160D01*
G02X926948Y880360I200J0D01*
G01X927126D01*
G02X927326Y880160I0J-200D01*
G01Y880145D01*
X927322Y880117D01*
Y880116D01*
X927320Y880104D01*
G03X927310Y879940I1292J-161D01*
G01Y879937D01*
G03X929914I1302J0D01*
G01Y879957D01*
G02X929971Y880097I200J0D01*
G01X930171Y880300D01*
G02X930314Y880360I143J-140D01*
G01X944726D01*
X944834Y880277D01*
X944851Y880211D01*
G03X947757I1453J381D01*
G01X947774Y880277D01*
X947882Y880360D01*
X972340D01*
G02X972373Y880357I-2J-200D01*
G02X972480Y880303I-32J-197D01*
G01X983400Y869383D01*
G02X983459Y869241I-141J-142D01*
G01Y869172D01*
X983450Y869140D01*
G03X983390Y868727I1442J-420D01*
G01Y868706D01*
G03X984878Y867218I1502J14D01*
G01X984895D01*
G03X985344Y867287I-1J1502D01*
G01X985398Y867304D01*
X985506Y867277D01*
X993507Y859276D01*
G02X993509Y859274I-140J-142D01*
G02X993566Y859134I-143J-140D01*
G01Y835035D01*
G02X993504Y834890I-200J0D01*
G01X993293Y834690D01*
G02X993225Y834648I-137J146D01*
G01X993191Y834635D01*
X993130D01*
G03X993063Y834637I-78J-1500D01*
G01X993061D01*
G03Y831633I0J-1502D01*
G37*
G36*
G01X949468Y54588D02*
X978644D01*
X978785Y54447D01*
Y52732D01*
X978644Y52591D01*
X949468D01*
G03X943531Y46654I0J-5937D01*
G01Y7874D01*
G02X937657Y2000I-5874J0D01*
G01X842776D01*
G02X836902Y7874I0J5874D01*
G01Y46658D01*
G03X836896Y46925I-5938J0D01*
G01X838895D01*
G02X838900Y46654I-7930J-282D01*
G01Y7874D01*
G03X842776Y3998I3876J0D01*
G01X937657D01*
G03X941534Y7874I0J3877D01*
G01Y46654D01*
G02X949468Y54588I7934J0D01*
G37*
G36*
G01X847483Y275932D02*
X869418D01*
X869492Y275902D01*
X869520Y275873D01*
X870131Y275262D01*
G02X870190Y275120I-141J-142D01*
G01Y205020D01*
X870160Y204946D01*
X870131Y204918D01*
X868610Y203397D01*
G02X868468Y203338I-142J141D01*
G01X847601D01*
X847527Y203368D01*
X847499Y203397D01*
X847341Y203555D01*
G02X847283Y203696I142J141D01*
G01Y204858D01*
G02X847343Y205001I200J0D01*
G01X847577Y205230D01*
X847651Y205259D01*
X847691Y205258D01*
X847725D01*
G03Y208262I0J1502D01*
G01X847691D01*
X847651Y208261D01*
X847577Y208290D01*
X847343Y208519D01*
G02X847283Y208661I140J143D01*
G01Y255107D01*
G02X847401Y255289I200J0D01*
G01X847725Y255436D01*
G02X847896Y255432I81J-183D01*
G01X847946Y255407D01*
X847965Y255392D01*
G03X848939Y255033I975J1143D01*
G03Y258037I0J1502D01*
G03X847965Y257678I1J-1502D01*
G01X847946Y257663D01*
X847896Y257638D01*
G02X847725Y257634I-90J179D01*
G01X847401Y257781D01*
G02X847283Y257963I82J182D01*
G01Y275732D01*
G02X847483Y275932I200J0D01*
G37*
G36*
G01X928534Y1329170D02*
G03X927146Y1330099I-1388J-572D01*
G03X926158Y1329728I1J-1503D01*
G02X925915Y1329713I-131J151D01*
G03X924651Y1330096I-1264J-1894D01*
G01X924650D01*
G03X922374Y1327819I0J-2276D01*
G03X922809Y1326480I2276J-1D01*
G02X922848Y1326361I-161J-119D01*
G01Y1325877D01*
G02X922809Y1325758I-200J0D01*
G03X922374Y1324420I1841J-1338D01*
G01Y1324419D01*
G03X924650Y1322142I2277J0D01*
G01X924651D01*
G03X925915Y1322525I0J2277D01*
G02X926158Y1322510I112J-166D01*
G03X927146Y1322139I989J1132D01*
G03X928534Y1323068I0J1501D01*
G02X928719Y1323192I185J-76D01*
G01X930939D01*
G02X931081Y1323133I0J-200D01*
G01X950181Y1304033D01*
G02X950240Y1303891I-141J-142D01*
G01Y1298161D01*
G02X950131Y1297983I-200J0D01*
G01X949765Y1297795D01*
X949653Y1297804D01*
X949607Y1297837D01*
G03X948259Y1298272I-1348J-1871D01*
G03X945952Y1295965I0J-2307D01*
G01Y1276916D01*
G02X945893Y1276774I-200J0D01*
G01X945739Y1276620D01*
G02X945521Y1276576I-142J141D01*
G01X945465Y1276599D01*
X945398Y1276699D01*
Y1306608D01*
G03X942384I-1507J0D01*
G01Y1276772D01*
G02X942325Y1276630I-200J0D01*
G01X938991Y1273295D01*
G02X938849Y1273236I-142J141D01*
G01X921329D01*
G03X920264Y1272795I0J-1506D01*
G01X916221Y1268752D01*
G03X915780Y1267687I1065J-1065D01*
G01Y1216589D01*
G02X915690Y1216423I-200J1D01*
G01X915412Y1216238D01*
G02X915223Y1216221I-110J167D01*
G03X914637Y1216340I-586J-1383D01*
G03Y1213336I0J-1502D01*
G03X915223Y1213455I0J1502D01*
G02X915412Y1213438I79J-184D01*
G01X915690Y1213253D01*
G02X915780Y1213087I-110J-167D01*
G01Y1212319D01*
G02X915690Y1212153I-200J1D01*
G01X915412Y1211968D01*
G02X915223Y1211951I-110J167D01*
G03X914637Y1212070I-586J-1383D01*
G03Y1209066I0J-1502D01*
G03X915223Y1209185I0J1502D01*
G02X915412Y1209168I79J-184D01*
G01X915690Y1208983D01*
G02X915780Y1208817I-110J-167D01*
G01Y1113497D01*
G02X915721Y1113355I-200J0D01*
G01X904084Y1101718D01*
G03X903642Y1100653I1065J-1066D01*
G01Y1083323D01*
G02X903597Y1083280I-159J121D01*
G01X903288Y1083094D01*
G02X903189Y1083067I-100J173D01*
G01X903095Y1083090D01*
X903075Y1083101D01*
G03X902389Y1083266I-685J-1337D01*
G01X902367D01*
G03X900887Y1081764I22J-1502D01*
G03X902389Y1080262I1502J0D01*
G03X903094Y1080438I0J1502D01*
G01X903095D01*
G02X903281Y1080439I94J-177D01*
G01X903598Y1080248D01*
G02X903642Y1080205I-116J-163D01*
G01Y1078230D01*
G02X903482Y1078149I-161J119D01*
G01X902971D01*
X902860Y1078244D01*
X902848Y1078316D01*
G03X899884I-1482J-248D01*
G01X899872Y1078244D01*
X899761Y1078149D01*
X899416D01*
X899305Y1078241D01*
X899292Y1078313D01*
G03X896338I-1477J-271D01*
G01X896325Y1078241D01*
X896214Y1078149D01*
X867406D01*
G02X867206Y1078349I0J200D01*
G01Y1087208D01*
G02X867259Y1087344I200J0D01*
G01X867445Y1087544D01*
G02X867574Y1087607I146J-136D01*
G01X867575D01*
G03X868484Y1088008I-118J1497D01*
G01X868511Y1088034D01*
X868582Y1088062D01*
X868932D01*
X869003Y1088034D01*
X869030Y1088008D01*
G03X871084I1027J1096D01*
G01X871111Y1088034D01*
X871182Y1088062D01*
X871532D01*
X871603Y1088034D01*
X871630Y1088008D01*
G03X873684I1027J1096D01*
G01X873711Y1088034D01*
X873782Y1088062D01*
X874132D01*
X874203Y1088034D01*
X874230Y1088008D01*
G03X875257Y1087602I1027J1096D01*
G03X876759Y1089104I0J1502D01*
G03X876389Y1090091I-1501J0D01*
G01Y1090092D01*
X876388D01*
G02X876340Y1090222I152J130D01*
G01Y1090486D01*
G02X876388Y1090616I200J0D01*
G01X876389Y1090617D01*
G03X876759Y1091604I-1131J987D01*
G03X875257Y1093106I-1502J0D01*
G03X874230Y1092700I0J-1502D01*
G01X874203Y1092674D01*
X874132Y1092646D01*
X873782D01*
X873711Y1092674D01*
X873684Y1092700D01*
G03X871630I-1027J-1096D01*
G01X871603Y1092674D01*
X871532Y1092646D01*
X871182D01*
X871111Y1092674D01*
X871084Y1092700D01*
G03X869030I-1027J-1096D01*
G01X869003Y1092674D01*
X868932Y1092646D01*
X868582D01*
X868511Y1092674D01*
X868484Y1092700D01*
G03X867576Y1093101I-1027J-1096D01*
G01X867574D01*
G02X867445Y1093164I17J199D01*
G01X867259Y1093364D01*
G02X867206Y1093500I147J136D01*
G01Y1094202D01*
G03X866531Y1095832I-2306J0D01*
G01X838999Y1123364D01*
G02X838940Y1123506I141J142D01*
G01Y1232589D01*
G02X838999Y1232731I200J0D01*
G01X853498Y1247230D01*
G03X854174Y1248861I-1631J1632D01*
G01Y1265029D01*
G02X854233Y1265171I200J0D01*
G01X857696Y1268635D01*
G02X857838Y1268694I142J-141D01*
G01X883301D01*
G03X884931Y1269369I0J2306D01*
G01X898305Y1282743D01*
G02X898445Y1282801I141J-142D01*
G01X898566Y1282802D01*
G02X898699Y1282751I0J-200D01*
G03X899699Y1282370I1000J1122D01*
G03X901201Y1283872I0J1502D01*
G03X900769Y1284926I-1502J0D01*
G01X900768Y1284927D01*
G02X900770Y1285208I143J139D01*
G01X910331Y1294769D01*
G03X910983Y1296069I-1631J1631D01*
G01X910987Y1296101D01*
X911016Y1296159D01*
X911569Y1296712D01*
G03X911628Y1296854I-141J142D01*
G01Y1298109D01*
G02X911706Y1298267I200J0D01*
G03Y1300645I-918J1189D01*
G02X911628Y1300803I122J158D01*
G01Y1312643D01*
X911691Y1312741D01*
X911744Y1312765D01*
G03Y1315495I-627J1365D01*
G01X911691Y1315519D01*
X911628Y1315617D01*
Y1318234D01*
G03X911569Y1318376I-200J0D01*
G01X910444Y1319501D01*
G02Y1319783I142J141D01*
G01X923006Y1332345D01*
G02X923148Y1332404I142J-141D01*
G01X933033D01*
G02X933175Y1332345I0J-200D01*
G01X941841Y1323678D01*
G02X941900Y1323536I-141J-142D01*
G01Y1321075D01*
G02X941777Y1320890I-200J0D01*
G01X941721Y1320867D01*
X941603Y1320890D01*
X934114Y1328379D01*
G03X932504Y1329046I-1610J-1610D01*
G01X928719D01*
G02X928534Y1329170I0J200D01*
G37*
G36*
G01X857817Y1460412D02*
X871251D01*
G02X871436Y1460288I0J-200D01*
G01X871459Y1460231D01*
X871436Y1460114D01*
X871408Y1460086D01*
G03X871349Y1459944I141J-142D01*
G01Y1446298D01*
G02X871290Y1446156I-200J0D01*
G01X871040Y1445906D01*
G02X870898Y1445847I-142J141D01*
G01X858576D01*
G02X858434Y1445906I0J200D01*
G01X857939Y1446401D01*
G02X857880Y1446543I141J142D01*
G01Y1459845D01*
G03X857821Y1459987I-200J0D01*
G01X857738Y1460070D01*
G02X857694Y1460288I141J142D01*
G01X857718Y1460345D01*
X857817Y1460412D01*
G37*
G36*
G01X973275Y938095D02*
X973267D01*
G03X973179Y938092I7J-1502D01*
G02X973013Y938166I-10J200D01*
G01X972933Y938264D01*
G02X972894Y938441I155J127D01*
G03X972945Y938828I-1451J388D01*
G03X969941I-1502J0D01*
G03X971405Y937326I1502J0D01*
G01X971449Y937325D01*
X971527Y937287D01*
X971774Y936984D01*
X971796Y936900D01*
X971788Y936856D01*
G03X971765Y936593I1479J-262D01*
G03X971830Y936155I1502J-1D01*
G02X971821Y936013I-191J-59D01*
G01X971770Y935902D01*
G02X971669Y935802I-182J83D01*
G03X970776Y934429I609J-1373D01*
G03X972278Y932927I1502J0D01*
G03X972978Y933100I0J1503D01*
G01X973025Y933125D01*
X973130Y933122D01*
X973468Y932918D01*
G02X973565Y932747I-103J-171D01*
G01Y925839D01*
X973535Y925765D01*
X973506Y925737D01*
X952693Y904924D01*
G02X952551Y904865I-142J141D01*
G01X932675D01*
G02X932510Y904952I0J200D01*
G01X932324Y905224D01*
G02X932302Y905409I165J113D01*
G03X932403Y905949I-1401J542D01*
G01Y905952D01*
G03X929399I-1502J0D01*
G01Y905949D01*
G03X929443Y905589I1502J1D01*
G02X929431Y905459I-194J-48D01*
G03X929311Y905039I1369J-618D01*
G01X929301Y904963D01*
X929189Y904865D01*
X923070D01*
X922955Y904974D01*
X922951Y905054D01*
G03X919951I-1500J-81D01*
G01X919947Y904974D01*
X919832Y904865D01*
X910741D01*
X910661Y904903D01*
X910632Y904938D01*
X910407Y905211D01*
X910385Y905297D01*
X910394Y905341D01*
G03X910422Y905625I-1474J289D01*
G01Y905634D01*
G03X907418I-1502J-4D01*
G01Y905629D01*
G03X907446Y905341I1502J1D01*
G01X907455Y905297D01*
X907433Y905211D01*
X907208Y904938D01*
X907207Y904937D01*
G02X907053Y904865I-154J128D01*
G01X891048D01*
G02X890894Y904937I0J200D01*
G01X890697Y905174D01*
G02X890654Y905338I154J128D01*
G01Y905340D01*
G03X890680Y905616I-1476J278D01*
G01Y905619D01*
G03X887676I-1502J0D01*
G01Y905616D01*
G03X887702Y905340I1502J2D01*
G01Y905338D01*
G02X887659Y905174I-197J-36D01*
G01X887462Y904937D01*
G02X887308Y904865I-154J128D01*
G01X875358D01*
X875284Y904895D01*
X875256Y904924D01*
X871961Y908219D01*
G02X871902Y908360I141J142D01*
G01Y913409D01*
G02X871976Y913563I200J-1D01*
G01X872209Y913755D01*
X872295Y913777D01*
X872339Y913768D01*
G03X872632Y913740I289J1474D01*
G03X874130Y915242I-4J1502D01*
G03X872628Y916744I-1502J0D01*
G01X872627D01*
G03X872339Y916716I1J-1502D01*
G01X872295Y916707D01*
X872209Y916729D01*
X871976Y916921D01*
G02X871902Y917075I126J155D01*
G01Y928396D01*
G02X871961Y928537I200J-1D01*
G01X873757Y930333D01*
G03X874432Y931964I-1631J1630D01*
G01Y934766D01*
G03X873065Y936873I-2307J0D01*
G01X873019Y936893D01*
X872958Y936971D01*
X872901Y937296D01*
G02X872956Y937472I197J35D01*
G01X875360Y939876D01*
G02X875616Y939898I141J-142D01*
G03X876481Y939624I865J1228D01*
G03X877983Y941088I0J1502D01*
G01Y941121D01*
Y941126D01*
G03X877725Y941968I-1503J0D01*
G01X877708Y941993D01*
X877689Y942053D01*
G02X877722Y942236I191J60D01*
G01X877730Y942246D01*
X888299Y952815D01*
G03X888358Y952957I-141J142D01*
G01Y957470D01*
G02X888393Y957584I200J1D01*
G03X888802Y958894I-1898J1311D01*
G01Y991937D01*
G02X888860Y992078I200J0D01*
G01X889601Y992819D01*
G02X889603Y992821I142J-140D01*
G02X889743Y992878I140J-143D01*
G01X891270D01*
G03X891343Y992876I78J1500D01*
G03X891420Y992878I0J1502D01*
G01X891427D01*
G03X892642Y993623I-84J1500D01*
G01Y993624D01*
X892643Y993625D01*
G02X892818Y993723I172J-102D01*
G01X893222Y993718D01*
X893313Y993663D01*
X893340Y993614D01*
G03X894660Y992828I1320J715D01*
G03X895932Y993531I0J1502D01*
G01X895959Y993574D01*
X896045Y993623D01*
X896479Y993634D01*
X896568Y993590D01*
X896597Y993548D01*
G03X897825Y992911I1228J865D01*
G03Y995915I0J1502D01*
G03X896553Y995212I0J-1502D01*
G01X896526Y995169D01*
X896440Y995120D01*
X896006Y995109D01*
X895918Y995153D01*
X895888Y995195D01*
G03X894830Y995823I-1229J-865D01*
G01X894827D01*
G02X894662Y995956I24J199D01*
G01X894643Y996011D01*
X894669Y996122D01*
X894955Y996408D01*
G02X895097Y996467I142J-141D01*
G01X895578D01*
G03X895720Y996526I0J200D01*
G01X897621Y998427D01*
G02X897623Y998429I142J-140D01*
G02X897763Y998486I140J-143D01*
G01X972607D01*
G02X972747Y998429I0J-200D01*
G01X972748Y998428D01*
X973471Y997705D01*
G02X973473Y997703I-140J-142D01*
G02X973530Y997563I-143J-140D01*
G01Y997265D01*
X973506Y997241D01*
Y991641D01*
Y991640D01*
G03X973521Y991564I200J0D01*
G01X973565Y991460D01*
Y938378D01*
G02X973502Y938233I-200J1D01*
G01X973414Y938150D01*
G02X973275Y938095I-138J145D01*
G37*
G36*
G01X959229Y110681D02*
G03X959242Y110611I200J1D01*
G02X959251Y110578I-188J-69D01*
G02X959254Y110527I-197J-37D01*
G01X959248Y110439D01*
G02X959236Y110384I-199J15D01*
G01X959208Y110307D01*
G02X959207Y110305I-177J87D01*
G03X958911Y109410I1206J-895D01*
G03X960413Y107908I1502J0D01*
G03X961345Y108232I0J1502D01*
G01X961346Y108233D01*
G02X961586Y108237I123J-158D01*
G02X961610Y108217I-116J-163D01*
G01X962159Y107668D01*
G03X962301Y107609I142J141D01*
G01X962878D01*
X962895Y107606D01*
G03X962967Y107596I201J1185D01*
G01X962977Y107595D01*
X962979D01*
G03X962994Y107593I166J1190D01*
G01X962998D01*
G03X963100Y107588I110J1197D01*
G01X979027D01*
G02X979226Y107389I-1J-200D01*
G01Y104243D01*
G03X979245Y103989I1803J7D01*
G01Y103985D01*
G03X979248Y103967I1779J287D01*
G02X979249Y103961I-196J-36D01*
G01X979250Y103958D01*
Y103957D01*
G03X979253Y103943I1763J370D01*
G01Y103939D01*
X979254Y103938D01*
G03X979255Y103932I197J30D01*
G03X979258Y103915I1776J305D01*
G01X979263Y103886D01*
X979258Y103831D01*
X979245Y103799D01*
G02X979183Y103719I-184J79D01*
G01X979164Y103706D01*
X979138Y103688D01*
G02X978956Y103670I-109J168D01*
G01X978939Y103679D01*
G03X978253Y103845I-686J-1335D01*
G01X978251D01*
G03X976749Y102343I0J-1502D01*
G03X977195Y101275I1502J0D01*
G01X977196Y101274D01*
G03X978271Y100821I1075J1049D01*
G03X979771Y102242I0J1502D01*
G01X979774Y102293D01*
X979797Y102332D01*
G02X979837Y102381I173J-100D01*
G02X979864Y102401I132J-150D01*
G01X980004Y102488D01*
X980154Y102581D01*
G02X980234Y102605I96J-175D01*
G01X980280Y102608D01*
X980325Y102589D01*
X980327D01*
G03X981018Y102446I704J1660D01*
G01X981029D01*
G03X982832Y104249I0J1803D01*
G01Y107389D01*
G02X983031Y107588I200J-1D01*
G01X1019274D01*
G02X1019311Y107584I-3J-200D01*
G01X1019313D01*
G02X1019414Y107531I-39J-196D01*
G01X1020831Y106114D01*
G02X1020884Y106013I-143J-140D01*
G01Y106011D01*
G02X1020888Y105974I-196J-40D01*
G01Y98955D01*
G02X1020820Y98805I-200J0D01*
G01X1020649Y98654D01*
X1020596Y98607D01*
G02X1020521Y98565I-133J150D01*
G01X1020483Y98554D01*
X1020440Y98559D01*
G03X1020254Y98570I-182J-1491D01*
G03X1018752Y97068I0J-1502D01*
G03X1018901Y96416I1501J0D01*
G01X1018912Y96392D01*
X1018922Y96341D01*
X1018920Y96315D01*
G02X1018884Y96214I-199J14D01*
G01X1018676Y95920D01*
G02X1018520Y95844I-157J124D01*
G01X1018499Y95845D01*
G03X1018344Y95853I-155J-1494D01*
G03X1018342I-1J-1502D01*
G03X1016842Y94351I2J-1502D01*
G03X1019846I1502J0D01*
G03X1019697Y95003I-1501J0D01*
G01X1019686Y95027D01*
X1019676Y95078D01*
X1019678Y95104D01*
G02X1019714Y95205I199J-14D01*
G01X1019922Y95499D01*
G02X1020078Y95575I157J-124D01*
G01X1020099Y95574D01*
G03X1020254Y95566I155J1494D01*
G01X1020264D01*
G03X1020440Y95577I-6J1502D01*
G01X1020483Y95582D01*
X1020521Y95571D01*
G02X1020596Y95529I-58J-192D01*
G01X1020649Y95482D01*
X1020820Y95331D01*
G02X1020888Y95181I-132J-150D01*
G01Y94811D01*
X1020877Y94779D01*
G03X1020791Y94279I1416J-501D01*
G03X1020877Y93779I1502J1D01*
G01X1020888Y93747D01*
Y87617D01*
G02X1020854Y87506I-200J0D01*
G01X1020839Y87482D01*
X1020794Y87445D01*
X1020791Y87444D01*
G03X1019839Y86046I550J-1398D01*
G03X1020765Y84659I1502J0D01*
G01X1020767Y84658D01*
G02X1020855Y84585I-78J-184D01*
G01X1020871Y84561D01*
X1020879Y84535D01*
G02X1020888Y84476I-191J-59D01*
G01Y62332D01*
X1020887Y62321D01*
G02X1020837Y62205I-199J17D01*
G01X1020781Y62148D01*
X1020633Y61998D01*
G02X1020571Y61956I-141J142D01*
G01X1020536Y61941D01*
X1020493Y61940D01*
X1020492D01*
G03X1020410Y61936I32J-1502D01*
G03X1019416Y61458I109J-1498D01*
G02X1019415Y61456I-172J85D01*
G02X1019346Y61408I-146J137D01*
G01X1019308Y61392D01*
X1019164Y61396D01*
X1018962Y61401D01*
G02X1018880Y61421I5J200D01*
G01X1018842Y61439D01*
X1018814Y61473D01*
G03X1017659Y62015I-1155J-960D01*
G03Y59011I0J-1502D01*
G01X1017661D01*
G03X1018762Y59493I-1J1501D01*
G02X1018763Y59495I172J-85D01*
G02X1018832Y59543I146J-137D01*
G01X1018870Y59559D01*
X1019014Y59555D01*
X1019216Y59550D01*
G02X1019298Y59530I-5J-200D01*
G01X1019336Y59512D01*
X1019364Y59478D01*
G03X1020494Y58936I1155J960D01*
G01X1020495D01*
X1020536Y58935D01*
X1020571Y58920D01*
G02X1020633Y58878I-79J-184D01*
G01X1020781Y58728D01*
X1020837Y58671D01*
G02X1020887Y58555I-149J-133D01*
G01X1020888Y58544D01*
Y54060D01*
G02X1020866Y53969I-200J0D01*
G02X1020830Y53919I-178J90D01*
G01X1019626Y52715D01*
G02X1019576Y52679I-140J142D01*
G02X1019485Y52657I-91J178D01*
G01X1000955D01*
G02X1000864Y52679I0J200D01*
G02X1000814Y52715I90J178D01*
G01X995672Y57857D01*
G03X995656Y57872I-145J-138D01*
G01X995631Y57892D01*
X995596Y57946D01*
X995529Y58207D01*
G02X995537Y58333I193J51D01*
G03X996180Y61614I-8057J3282D01*
G03X978780I-8700J0D01*
G01Y61613D01*
G03X979400Y58388I8699J0D01*
G01X979410Y58363D01*
X979164Y58003D01*
G02X978999Y57916I-165J113D01*
G01X972161D01*
G02X972127Y57919I1J200D01*
G02X972066Y57940I34J197D01*
G01Y57941D01*
G02X971984Y58025I96J175D01*
G01X971971Y58051D01*
X971817Y58356D01*
G02X971801Y58449I183J79D01*
G01Y58451D01*
X971854Y58524D01*
G03X972568Y60708I-2988J2185D01*
G01Y60731D01*
G03X972124Y62466I-3702J-23D01*
G01Y62467D01*
G02X972100Y62561I176J95D01*
G01Y62611D01*
X972195Y62787D01*
X972268Y62924D01*
G02X972332Y62991I173J-101D01*
G01X972373Y63018D01*
X972424Y63022D01*
G03X974720Y69573I-318J3789D01*
G03X968738Y65029I-2634J-2742D01*
G01X968744Y65017D01*
X968752Y64998D01*
G02X968739Y64824I-186J-74D01*
G01X968732Y64813D01*
X968562Y64528D01*
G02X968512Y64472I-171J103D01*
G02X968390Y64430I-123J158D01*
G01X961546D01*
G03X957845Y60729I0J-3701D01*
G01Y60727D01*
G03X958553Y58551I3701J1D01*
G01X958570Y58528D01*
X958588Y58478D01*
X958591Y58449D01*
G02X958569Y58343I-199J-14D01*
G01X958547Y58300D01*
X958401Y58012D01*
G02X958339Y57950I-169J107D01*
G01X958316Y57937D01*
G02X958228Y57916I-89J179D01*
G01X921533D01*
G02X921442Y57938I0J200D01*
G02X921392Y57974I90J178D01*
G01X919805Y59561D01*
G02X919769Y59611I142J140D01*
G02X919747Y59702I178J91D01*
G01Y95699D01*
G03X919718Y95803I-200J0D01*
G01X919703Y95827D01*
X919696Y95852D01*
G02X919688Y95907I192J56D01*
G01Y108878D01*
G02X919719Y108985I200J0D01*
G01X919734Y109008D01*
X919775Y109045D01*
X919802Y109058D01*
G03X920347Y109499I-646J1356D01*
G01Y109500D01*
X920354Y109509D01*
G02X920362Y109518I153J-128D01*
G01X920396Y109552D01*
G02X920478Y109588I119J-160D01*
G01X920506Y109593D01*
X920784Y109632D01*
G02X920845Y109627I14J-199D01*
G01X920874Y109619D01*
X920912Y109590D01*
G03X921815Y109282I911J1194D01*
G01X921855D01*
G03X923080Y109960I-31J1502D01*
G03X923083Y109964I-1198J902D01*
G01X923116Y110016D01*
G02X923144Y110050I168J-109D01*
G02X923146Y110052I143J-141D01*
G02X923185Y110081I138J-145D01*
G01X923261Y110125D01*
X923267Y110128D01*
G02X923307Y110145I98J-174D01*
G02X923345Y110152I55J-192D01*
G01X923349D01*
G02X923362Y110153I22J-198D01*
G01X923573D01*
G02X923600Y110151I-1J-200D01*
G02X923617Y110148I-26J-198D01*
G02X923672Y110127I-43J-195D01*
G01X923769Y110072D01*
X923806Y110037D01*
X923819Y110015D01*
G03X923943Y109844I1275J794D01*
G03X924043Y109735I1156J960D01*
G02X924045Y109733I-140J-142D01*
G03X925118Y109282I1073J1051D01*
G03X926620Y110784I0J1502D01*
G03X926167Y111859I-1502J0D01*
G01X926166Y111860D01*
G03X925098Y112306I-1068J-1056D01*
G03X923794Y111549I0J-1502D01*
G02X923635Y111455I-170J106D01*
G01X923336D01*
G02X923242Y111479I1J200D01*
G01X923122Y111543D01*
X923107Y111566D01*
X923093Y111588D01*
G03X923016Y111698I-1268J-806D01*
G03X922929Y111801I-1190J-917D01*
G02X922928Y111803I177J90D01*
G03X922924Y111807I-1062J-1058D01*
G02X922922Y111809I140J142D01*
G02X922918Y111813I139J143D01*
G03X922875Y111857I-1095J-1028D01*
G02X922873Y111859I140J142D01*
G03X921804Y112306I-1069J-1055D01*
G03X920612Y111718I0J-1502D01*
G01X920604Y111708D01*
G02X920597Y111700I-154J128D01*
G01X920563Y111666D01*
G02X920472Y111628I-120J160D01*
G01X920193Y111587D01*
G02X920053Y111618I-30J198D01*
G01X920046Y111623D01*
G03X920024Y111639I-894J-1207D01*
G01X920020Y111641D01*
X920007Y111651D01*
G03X919997Y111658I-866J-1226D01*
G01X919975Y111674D01*
X919963Y111687D01*
G02X919942Y111714I147J136D01*
G01X919896Y111797D01*
X919885Y111817D01*
G02X919865Y111903I180J87D01*
G01Y111925D01*
G02X919884Y112008I200J-2D01*
G01X919910Y112058D01*
G02X919934Y112090I171J-104D01*
G01X919949Y112106D01*
X919974Y112122D01*
G03X920677Y113358I-799J1272D01*
G01Y113394D01*
G03X920221Y114473I-1502J1D01*
G01X920220Y114474D01*
G03X919802Y114770I-1065J-1061D01*
G01X919801Y114771D01*
G02X919718Y114844I85J181D01*
G01X919703Y114867D01*
X919695Y114895D01*
G02X919688Y114947I193J52D01*
G01Y115053D01*
G02X919689Y115071I200J-2D01*
G02X919720Y115158I199J-22D01*
G01X919736Y115182D01*
X919776Y115217D01*
X919777D01*
X919783Y115220D01*
G03X920677Y116594I-609J1374D01*
G03X920225Y117668I-1502J0D01*
G02X920223Y117670I140J142D01*
G03X920078Y117799I-1069J-1055D01*
G02X920003Y117927I123J158D01*
G02X920001Y117954I198J28D01*
G01Y118237D01*
G02X920046Y118363I200J0D01*
G02X920069Y118387I156J-126D01*
G03X920677Y119582I-894J1207D01*
G01Y119610D01*
G03X920676Y119671I-1503J6D01*
G01Y119675D01*
G03X920220Y120674I-1501J-81D01*
G02X920218Y120676I140J142D01*
G03X919802Y120970I-1063J-1063D01*
G01X919801Y120971D01*
G02X919718Y121044I85J181D01*
G01X919703Y121067D01*
X919695Y121095D01*
G02X919688Y121147I193J52D01*
G01Y122604D01*
G02X919736Y122734I200J0D01*
G01X919759Y122761D01*
X919819Y122795D01*
X919855Y122801D01*
G03X921111Y124283I-246J1482D01*
G03X920660Y125356I-1502J0D01*
G03X920637Y125378I-1050J-1074D01*
G02X920635Y125380I140J142D01*
G03X919855Y125782I-1048J-1076D01*
G01X919853D01*
X919838Y125785D01*
G02X919689Y125961I50J194D01*
G01Y125963D01*
G02X919688Y125978I199J21D01*
G01Y131942D01*
G02X919689Y131961I200J-1D01*
G02X919699Y132005I199J-22D01*
G02X919800Y132119I189J-66D01*
G01X920005Y132207D01*
X920147Y132268D01*
G02X920263Y132280I78J-184D01*
G01X920296Y132273D01*
X920343Y132248D01*
X920362Y132230D01*
X920366Y132226D01*
G03X921418Y131796I1052J1072D01*
G03X921618Y131809I3J1502D01*
G03X922857Y132865I-200J1489D01*
G01X922868Y132903D01*
X922890Y132931D01*
G02X922935Y132974I159J-121D01*
G01X923171Y133115D01*
X923204Y133121D01*
G03X923565Y133077I361J1459D01*
G03X925067Y134579I0J1502D01*
G03X924614Y135654I-1502J0D01*
G01X924613Y135655D01*
G03X923545Y136101I-1068J-1056D01*
G03X922117Y135066I0J-1503D01*
G01X922105Y135030D01*
X922084Y135003D01*
G02X922030Y134956I-156J125D01*
G01X921916Y134888D01*
X921791Y134814D01*
G02X921737Y134795I-93J177D01*
G01X921705Y134789D01*
X921666Y134796D01*
G03X921399Y134820I-267J-1478D01*
G01X921398D01*
G03X920363Y134407I0J-1503D01*
G01X920362Y134406D01*
X920357Y134402D01*
G02X920260Y134354I-134J149D01*
G01X920232Y134349D01*
X920203Y134353D01*
G02X920148Y134367I21J199D01*
G01X919809Y134513D01*
G02X919688Y134696I79J184D01*
G01Y229314D01*
G02X919737Y229445I200J0D01*
G01X919759Y229467D01*
G02X919846Y229511I131J-151D01*
G01X919862Y229513D01*
G03X921154Y231000I-210J1487D01*
G03X920613Y232155I-1503J0D01*
G01X920611Y232156D01*
X920580Y232183D01*
X920560Y232221D01*
G02X920539Y232305I179J89D01*
G01X920530Y232604D01*
G02X920546Y232689I200J6D01*
G01X920561Y232722D01*
X920595Y232753D01*
G03X921079Y233858I-1019J1105D01*
G03X920522Y235025I-1501J0D01*
G01X920498Y235045D01*
X920473Y235077D01*
X920465Y235096D01*
G02X920448Y235186I183J81D01*
G01X920457Y235367D01*
X920464Y235517D01*
G02X920491Y235601I200J-18D01*
G01X920502Y235620D01*
X920531Y235651D01*
X920554Y235666D01*
G03X921230Y236921I-827J1255D01*
G03X919962Y238405I-1502J0D01*
G01X919949Y238407D01*
X919940Y238409D01*
X919842Y238460D01*
G02X919796Y238497I101J173D01*
G01X919775Y238519D01*
X919733Y238565D01*
G02X919702Y238618I155J126D01*
G01Y238620D01*
G02X919688Y238692I186J73D01*
G01Y239273D01*
G02X919734Y239400I200J-1D01*
G01X919756Y239427D01*
X919812Y239461D01*
X919851Y239468D01*
G03X921079Y240945I-274J1477D01*
G03X920809Y241804I-1501J0D01*
G01X920788Y241834D01*
G02X920771Y241903I183J82D01*
G01X920768Y241957D01*
X920857Y242127D01*
X920967Y242336D01*
G02X921077Y242420I169J-107D01*
G01X940060D01*
X940079Y242428D01*
X940917D01*
X940936Y242420D01*
X947108D01*
G02X947239Y242371I0J-200D01*
G01X947258Y242355D01*
X947292Y242294D01*
X947299Y242249D01*
G03X950116Y241769I1486J214D01*
G03X950272Y242255I-1331J695D01*
G01Y242256D01*
X950278Y242294D01*
X950312Y242355D01*
X950331Y242371D01*
G02X950462Y242420I131J-151D01*
G01X956512D01*
Y242419D01*
G02X956543Y242417I3J-191D01*
G01X956564Y242413D01*
X956576Y242411D01*
X956602Y242397D01*
G02X956649Y242362I-95J-176D01*
G01X959155Y239856D01*
G02X959179Y239762I-176J-95D01*
G01Y153169D01*
G02X959177Y153146I-200J6D01*
G01X959167Y153092D01*
G02X959158Y153063I-195J45D01*
G01X959147Y153036D01*
X959144Y153033D01*
X959108Y153002D01*
X959107Y153001D01*
G03X957876Y149736I2439J-2784D01*
G03X958872Y147658I3669J481D01*
G01X958874Y147656D01*
X958883Y147646D01*
X958885Y147644D01*
X958886Y147642D01*
G03X958951Y147577I2650J2585D01*
G02X958953Y147575I-140J-142D01*
G03X959054Y147477I2628J2607D01*
G03X959058Y147475I88J171D01*
G03X959073Y147461I2532J2698D01*
G03X959076Y147458I143J140D01*
G03X959085Y147450I2461J2760D01*
G01X959093Y147443D01*
X959116Y147421D01*
X959156Y147329D01*
X959162Y147315D01*
G02X959179Y147235I-183J-81D01*
G01Y122986D01*
G03X959194Y122910I200J0D01*
G01X959214Y122862D01*
G02X959229Y122786I-185J-76D01*
G01Y117486D01*
G02X959198Y117378I-200J-1D01*
G03Y115614I1214J-882D01*
G02X959229Y115506I-169J-107D01*
G01Y110681D01*
G37*
G36*
G01X995571Y201788D02*
X995714Y201645D01*
G02X995716Y201643I-140J-142D01*
G01X996067Y201280D01*
G03X996135Y201233I145J137D01*
G01X997077Y200851D01*
G03X997152Y200836I76J185D01*
G01X999876D01*
G02X1000076Y200636I0J-200D01*
G01Y193717D01*
G02X1000014Y193581I-200J9D01*
G01X1000002Y193570D01*
X999722Y193374D01*
G02X999633Y193339I-116J163D01*
G01X999602Y193335D01*
X999555Y193344D01*
X999538Y193350D01*
X999537D01*
G03X999017Y193443I-520J-1409D01*
G01X999001D01*
G03Y190439I16J-1502D01*
G01X999019D01*
G03X999522Y190526I-1J1502D01*
G01X999538Y190532D01*
X999575Y190539D01*
G02X999725Y190506I35J-197D01*
G01X999997Y190316D01*
G02X1000005Y190309I-128J-154D01*
G01X1000017Y190298D01*
G02X1000076Y190165I-141J-142D01*
G01Y165173D01*
X1000075Y165167D01*
G02X1000032Y165051I-200J8D01*
G01X1000024Y165041D01*
X996549Y161566D01*
G02X996499Y161530I-140J142D01*
G02X996408Y161508I-91J178D01*
G01X989433D01*
G02X989335Y161534I1J200D01*
G01X989315Y161545D01*
X989278Y161580D01*
X989174Y161750D01*
Y161752D01*
X989086Y161897D01*
G02X989077Y161914I172J102D01*
G02X989081Y162094I181J86D01*
G01X989091Y162114D01*
G03X989253Y162781I-1340J679D01*
G01Y162815D01*
G03X988847Y163820I-1502J-22D01*
G01X988820Y163849D01*
X988807Y163883D01*
G02X988793Y163956I186J73D01*
G01Y164231D01*
G02X988806Y164302I200J0D01*
G01X988819Y164336D01*
X988847Y164366D01*
G03Y166420I-1096J1027D01*
G01X988819Y166450D01*
X988806Y166484D01*
G02X988793Y166555I187J71D01*
G01Y166831D01*
G02X988806Y166902I200J0D01*
G01X988819Y166936D01*
X988847Y166966D01*
G03X989253Y167993I-1096J1027D01*
G03X988883Y168980I-1501J0D01*
G01X988859Y169008D01*
X988847Y169040D01*
G02X988834Y169111I187J71D01*
G01Y169375D01*
G02X988847Y169446I200J0D01*
G01X988859Y169478D01*
X988883Y169506D01*
G03X989253Y170493I-1131J987D01*
G03X986249I-1502J0D01*
G03X986619Y169506I1501J0D01*
G01X986643Y169478D01*
X986655Y169446D01*
G02X986668Y169375I-187J-71D01*
G01Y169111D01*
G02X986655Y169040I-200J0D01*
G01X986643Y169008D01*
X986619Y168980D01*
G03X986249Y167993I1131J-987D01*
G03X986655Y166966I1502J0D01*
G01X986683Y166936D01*
X986696Y166902D01*
G02X986709Y166831I-187J-71D01*
G01Y166555D01*
G02X986696Y166484I-200J0D01*
G01X986683Y166450D01*
X986655Y166420D01*
G03Y164366I1096J-1027D01*
G01X986683Y164336D01*
X986696Y164302D01*
G02X986709Y164231I-187J-71D01*
G01Y163956D01*
G02X986695Y163883I-200J0D01*
G01X986682Y163849D01*
X986655Y163820D01*
G03X986249Y162821I1096J-1027D01*
G01Y162792D01*
G03X986410Y162116I1502J1D01*
G01X986421Y162094D01*
X986435Y162036D01*
G02X986411Y161890I-195J-43D01*
G01X986379Y161837D01*
Y161835D01*
X986237Y161604D01*
G02X986067Y161508I-171J104D01*
G01X982496D01*
G02X982408Y161528I-1J200D01*
G01X982389Y161538D01*
X982354Y161566D01*
X982339Y161585D01*
X982144Y161834D01*
G02X982106Y161915I158J123D01*
G01X982097Y161959D01*
X982108Y162004D01*
G03X982153Y162368I-1457J365D01*
G03X980651Y163870I-1502J0D01*
G03X979624Y163464I0J-1502D01*
G01X979594Y163436D01*
X979560Y163423D01*
G02X979489Y163410I-71J187D01*
G01X979213D01*
G02X979142Y163423I0J200D01*
G01X979108Y163436D01*
X979078Y163464D01*
G03X978051Y163870I-1027J-1096D01*
G03X976549Y162368I0J-1502D01*
G03X976594Y162004I1502J1D01*
G01X976605Y161959D01*
X976596Y161915D01*
G02X976558Y161834I-196J42D01*
G01X976363Y161585D01*
X976362Y161584D01*
G02X976293Y161528I-157J123D01*
G01X976273Y161518D01*
X976229Y161508D01*
X961057D01*
G02X960966Y161530I0J200D01*
G02X960916Y161566I90J178D01*
G01X960259Y162223D01*
G02X960201Y162364I142J141D01*
G01Y240157D01*
G03X960142Y240298I-200J-1D01*
G01X957360Y243080D01*
G03X957348Y243092I-855J-843D01*
G01X957088Y243352D01*
G03X956948Y243410I-141J-142D01*
G01X956731D01*
X956714Y243413D01*
G03X956513Y243430I-201J-1185D01*
G03X956510I-1J-1202D01*
G01X950068D01*
G02X950007Y243439I-2J200D01*
G02X949994Y243444I65J189D01*
G01X949880Y243493D01*
X949853Y243521D01*
G03X948785Y243966I-1067J-1057D01*
G03X948781I-2J-1502D01*
G01X948727D01*
X948692Y243963D01*
G03X948601Y243955I86J-1500D01*
G03X948488Y243937I180J-1491D01*
G01X948486D01*
G03X948082Y243792I300J-1472D01*
G03X947715Y243519I703J-1328D01*
G01X947687Y243491D01*
X947580Y243446D01*
G02X947502Y243430I-78J184D01*
G01X941153D01*
X941113Y243448D01*
G03X940498Y243580I-616J-1370D01*
G03X939883Y243448I1J-1502D01*
G01X939843Y243430D01*
X920718D01*
G02X920593Y243474I0J200D01*
G01X920583Y243482D01*
X920294Y243771D01*
G02X920236Y243926I141J141D01*
G01X920274Y244248D01*
G02X920303Y244331I199J-23D01*
G01X920324Y244365D01*
X920366Y244391D01*
G03X921079Y245669I-789J1278D01*
G03X919577Y247171I-1502J0D01*
G01X919573D01*
G03X919489Y247168I12J-1502D01*
G01X919487D01*
G03X919379Y247158I84J-1499D01*
G01X919335Y247153D01*
X919295Y247165D01*
G02X919222Y247207I61J190D01*
G01X919194Y247231D01*
G03X919192Y247233I-142J-140D01*
G01X918990Y247411D01*
G02X918928Y247555I138J145D01*
G01Y248508D01*
G02X918990Y248652I200J-1D01*
G01X919192Y248830D01*
G03X919194Y248832I-140J142D01*
G01X919222Y248856D01*
G02X919295Y248898I134J-148D01*
G01X919335Y248910D01*
X919379Y248905D01*
G03X919487Y248895I192J1489D01*
G01X919489D01*
G03X919573Y248892I96J1499D01*
G01X919577D01*
G03Y251896I0J1502D01*
G01X919573D01*
G03X919489Y251893I12J-1502D01*
G01X919487D01*
G03X919379Y251883I84J-1499D01*
G01X919335Y251878D01*
X919295Y251890D01*
G02X919222Y251932I61J190D01*
G01X919194Y251956D01*
G03X919192Y251958I-142J-140D01*
G01X918990Y252136D01*
G02X918928Y252280I138J145D01*
G01Y253232D01*
G02X918990Y253376I200J-1D01*
G01X919192Y253554D01*
G03X919194Y253556I-140J142D01*
G01X919222Y253580D01*
G02X919295Y253622I134J-148D01*
G01X919335Y253634D01*
X919379Y253629D01*
G03X919487Y253619I192J1489D01*
G01X919489D01*
G03X919573Y253616I96J1499D01*
G01X919577D01*
G03Y256620I0J1502D01*
G01X919573D01*
G03X919489Y256617I12J-1502D01*
G01X919487D01*
G03X919379Y256607I84J-1499D01*
G01X919335Y256602D01*
X919295Y256614D01*
G02X919222Y256656I61J190D01*
G01X919194Y256680D01*
G03X919192Y256682I-142J-140D01*
G01X918990Y256860D01*
G02X918928Y257004I138J145D01*
G01Y257957D01*
G02X918990Y258101I200J-1D01*
G01X919192Y258279D01*
G03X919194Y258281I-140J142D01*
G01X919222Y258305D01*
G02X919295Y258347I134J-148D01*
G01X919335Y258359D01*
X919379Y258354D01*
G03X919487Y258344I192J1489D01*
G01X919489D01*
G03X919573Y258341I96J1499D01*
G01X919577D01*
G03Y261345I0J1502D01*
G01X919573D01*
G03X919489Y261342I12J-1502D01*
G01X919487D01*
G03X919379Y261332I84J-1499D01*
G01X919335Y261327D01*
X919295Y261339D01*
G02X919222Y261381I61J190D01*
G01X919194Y261405D01*
G03X919192Y261407I-142J-140D01*
G01X918990Y261585D01*
G02X918928Y261729I138J145D01*
G01Y262681D01*
G02X918990Y262825I200J-1D01*
G01X919192Y263003D01*
G03X919194Y263005I-140J142D01*
G01X919222Y263029D01*
G02X919295Y263071I134J-148D01*
G01X919335Y263083D01*
X919379Y263078D01*
G03X919487Y263068I192J1489D01*
G01X919489D01*
G03X919573Y263065I96J1499D01*
G01X919577D01*
G03Y266069I0J1502D01*
G01X919573D01*
G03X919489Y266066I12J-1502D01*
G01X919487D01*
G03X919379Y266056I84J-1499D01*
G01X919335Y266051D01*
X919295Y266063D01*
G02X919222Y266105I61J190D01*
G01X919194Y266129D01*
G03X919192Y266131I-142J-140D01*
G01X918990Y266309D01*
G02X918928Y266453I138J145D01*
G01Y266589D01*
G02X918930Y266615I200J-2D01*
G02X918993Y266737I198J-25D01*
G01X919236Y266942D01*
G02X919310Y266979I125J-157D01*
G01X919335Y266986D01*
X919386Y266978D01*
G03X919616Y266960I232J1484D01*
G01X919658D01*
G03X919662I2J1502D01*
G03X921164Y268462I0J1502D01*
G03X920444Y269744I-1501J0D01*
G02X920440Y269746I87J179D01*
G02X920376Y269813I109J168D01*
G01X920374Y269816D01*
G02X920347Y269912I173J100D01*
G01X920337Y270250D01*
G02X920401Y270398I200J1D01*
G01X920424Y270414D01*
G03X921079Y271654I-846J1240D01*
G01Y271655D01*
G03X920608Y272747I-1502J0D01*
G01X920606Y272749D01*
G02X920554Y272825I135J148D01*
G01X920542Y272857D01*
X920552Y273010D01*
Y273012D01*
X920566Y273209D01*
G02X920585Y273281I199J-14D01*
G01X920600Y273312D01*
X920630Y273345D01*
X920649Y273359D01*
G03X921277Y274580I-873J1221D01*
G03X920861Y275618I-1503J0D01*
G02X920809Y275719I145J138D01*
G01X920804Y275749D01*
X920810Y275806D01*
X920875Y275960D01*
X920966Y276172D01*
G02X920978Y276196I184J-77D01*
G01X921047Y276265D01*
G02X921150Y276294I104J-171D01*
G01X921717D01*
G02X921821Y276265I0J-200D01*
G03X923336Y275838I1515J2474D01*
G03X924851Y276265I-1J2903D01*
G02X924955Y276294I104J-171D01*
G01X943123D01*
G02X943250Y276248I-1J-200D01*
G01X943458Y276056D01*
G02X943501Y275998I-136J-146D01*
G01X943518Y275965D01*
X943521Y275925D01*
G03X946515I1497J126D01*
G01X946518Y275965D01*
X946535Y275998D01*
G02X946578Y276056I179J-88D01*
G01X946786Y276248D01*
G02X946913Y276294I128J-154D01*
G01X994386D01*
G02X994531Y276232I0J-200D01*
G01X994759Y275992D01*
X994787Y275914D01*
X994785Y275873D01*
G03X994782Y275732I2698J-128D01*
G01Y267673D01*
G02X994728Y267536I-200J0D01*
G01X994647Y267450D01*
G02X994524Y267387I-147J136D01*
G03Y264405I174J-1491D01*
G02X994647Y264342I-24J-199D01*
G01X994728Y264256D01*
G02X994782Y264119I-146J-137D01*
G01Y257896D01*
X994693Y257786D01*
X994664Y257780D01*
G03X994662Y254826I275J-1477D01*
G01X994666D01*
X994693Y254820D01*
X994782Y254710D01*
Y208659D01*
G03X995443Y206891I2701J2D01*
G02Y206629I-151J-131D01*
G03X994782Y204859I2040J-1770D01*
G01Y203695D01*
G03X995571Y201788I2701J1D01*
G37*
G36*
G01X1202045Y1121948D02*
G03X1203247Y1120746I1202J0D01*
G03X1203605Y1120800I2J1202D01*
G01X1203617Y1120804D01*
X1203627Y1120806D01*
G03X1203647Y1120812I-47J194D01*
G01X1203660Y1120817D01*
X1203743Y1120835D01*
X1203779D01*
G02X1203979Y1120635I0J-200D01*
G01Y1120561D01*
X1203959Y1120497D01*
X1203939Y1120470D01*
G03X1203795Y1120262I3048J-2264D01*
G03X1203546Y1119811I3192J-2056D01*
G01X1203521Y1119756D01*
G03X1203456Y1119600I3471J-1538D01*
G01X1203455Y1119597D01*
X1203452Y1119590D01*
G02X1203385Y1119503I-186J74D01*
G01X1203357Y1119483D01*
X1203313Y1119455D01*
G02X1203267Y1119433I-109J168D01*
G01X1203193Y1119409D01*
X1203168Y1119408D01*
G03X1202045Y1118208I80J-1200D01*
G03X1203167Y1117008I1203J0D01*
G01X1203193Y1117007D01*
X1203263Y1116984D01*
X1203296Y1116972D01*
X1203383Y1116913D01*
X1203403Y1116885D01*
X1203445Y1116835D01*
X1203463Y1116798D01*
X1203466Y1116791D01*
X1203467Y1116789D01*
G03X1203606Y1116483I3522J1415D01*
G03X1203625Y1116446I3387J1716D01*
G03X1203921Y1115973I3357J1772D01*
G01X1203939Y1115948D01*
X1203979Y1115828D01*
Y1115766D01*
G02X1203896Y1115604I-200J0D01*
G01X1203857Y1115576D01*
X1203762Y1115561D01*
X1203703Y1115581D01*
X1203697Y1115583D01*
G03X1203253Y1115670I-449J-1115D01*
G01X1203230D01*
G03X1202201Y1113875I17J-1202D01*
G03X1202965Y1113299I1046J593D01*
G01X1202992D01*
X1203055Y1113282D01*
G03X1203074Y1113278I51J194D01*
G01X1203129Y1113269D01*
G03X1203162Y1113266I35J197D01*
G01X1203251D01*
G03X1203473Y1113287I-2J1202D01*
G01X1203488Y1113290D01*
X1203499Y1113292D01*
X1203542Y1113301D01*
X1203628Y1113280D01*
X1203833Y1113114D01*
X1203836Y1113111D01*
X1203904Y1113057D01*
G02X1203980Y1112898I-124J-157D01*
G01X1203979Y1112809D01*
Y1112295D01*
G02X1203903Y1112138I-200J0D01*
G01X1203879Y1112119D01*
X1203625Y1111912D01*
X1203580Y1111905D01*
X1203539Y1111895D01*
X1203494Y1111904D01*
G03X1203250Y1111930I-249J-1176D01*
G03X1203241I-5J-1202D01*
G01X1203238D01*
G03X1202045Y1110784I8J-1202D01*
G01X1202044Y1110755D01*
X1202025Y1110700D01*
X1201947Y1110591D01*
G02X1201858Y1110521I-163J116D01*
G01X1201857D01*
G03X1201636Y1110425I1401J-3528D01*
G01X1201634D01*
G03X1201491Y1110355I1598J-3445D01*
G01X1201469Y1110343D01*
X1201426Y1110334D01*
X1201382Y1110323D01*
X1201285Y1110344D01*
X1201259Y1110357D01*
X1201258Y1110358D01*
G03X1200896Y1110522I-1746J-3372D01*
G01X1200853Y1110539D01*
X1200807Y1110589D01*
X1200799Y1110600D01*
X1200753Y1110665D01*
G02X1200721Y1110733I162J118D01*
G01X1200708Y1110785D01*
X1200707Y1110803D01*
G03X1199507Y1111929I-1200J-76D01*
G01X1199506D01*
G03X1198305Y1110786I0J-1202D01*
G01X1198302Y1110729D01*
X1198220Y1110609D01*
G02X1198208Y1110594I-162J117D01*
G01X1198197Y1110580D01*
G02X1198133Y1110529I-154J128D01*
G01X1198116Y1110521D01*
G03X1197794Y1110376I1396J-3531D01*
G01X1197787Y1110370D01*
X1197765Y1110360D01*
G03X1197757Y1110356I1693J-3397D01*
G01X1197755Y1110355D01*
X1197730Y1110342D01*
X1197683Y1110331D01*
G02X1197589Y1110332I-45J195D01*
G01X1197543Y1110344D01*
X1197523Y1110355D01*
G03X1197439Y1110397I-1740J-3375D01*
G01X1197396Y1110418D01*
G03X1197355Y1110437I-1617J-3435D01*
G01X1197308Y1110458D01*
X1197307D01*
X1197034Y1110578D01*
X1196969Y1110676D01*
Y1110736D01*
G03X1195767Y1111929I-1202J-9D01*
G01X1195766D01*
G03X1194565Y1110785I0J-1202D01*
G01X1194563Y1110728D01*
X1194453Y1110569D01*
X1194408Y1110534D01*
X1194380Y1110522D01*
G03X1194250Y1110468I1391J-3533D01*
G03X1194140Y1110418I1516J-3481D01*
G03X1194045Y1110371I1636J-3426D01*
G03X1193897Y1110291I1731J-3379D01*
G03X1193817Y1110335I-1869J-3304D01*
G03X1193415Y1110522I-1800J-3343D01*
G01X1193413Y1110523D01*
G02X1193325Y1110592I74J186D01*
G01X1193248Y1110699D01*
X1193229Y1110753D01*
X1193228Y1110782D01*
G03X1193175Y1111084I-1201J-55D01*
G01X1193168Y1111105D01*
X1193167Y1111107D01*
G03X1192057Y1111929I-1141J-380D01*
G01X1192026D01*
G03X1190825Y1110784I0J-1202D01*
G01X1190824Y1110755D01*
X1190806Y1110701D01*
X1190715Y1110570D01*
X1190670Y1110535D01*
X1190642Y1110524D01*
G03X1190278Y1110355I1415J-3523D01*
G02X1190262Y1110347I-97J175D01*
G03X1190250Y1110342I71J-187D01*
G02X1190070Y1110341I-91J178D01*
G01X1190028Y1110362D01*
X1190025Y1110365D01*
G03X1189775Y1110481I-1722J-3384D01*
G01X1189753Y1110490D01*
X1189743Y1110495D01*
G03X1189674Y1110524I-1505J-3485D01*
G01X1189647Y1110535D01*
X1189602Y1110571D01*
X1189538Y1110665D01*
G02X1189513Y1110714I164J114D01*
G01X1189489Y1110783D01*
X1189487Y1110811D01*
G03X1187810Y1111831I-1199J-84D01*
G01X1187808Y1111830D01*
X1187793Y1111823D01*
X1187792Y1111822D01*
G03X1187085Y1110767I494J-1095D01*
G01X1187083Y1110719D01*
X1187013Y1110592D01*
X1186962Y1110547D01*
X1186930Y1110534D01*
G03X1186906Y1110524I1448J-3509D01*
G01X1186904Y1110523D01*
X1186857Y1110505D01*
X1186853Y1110503D01*
X1186849Y1110501D01*
X1186842Y1110498D01*
G03X1186511Y1110342I1451J-3508D01*
G01X1186489Y1110331D01*
X1186442Y1110319D01*
X1186390D01*
X1186343Y1110331D01*
X1186321Y1110342D01*
G03X1185879Y1110542I-1783J-3351D01*
G02X1185749Y1110729I70J187D01*
G03X1184589Y1111928I-1202J-2D01*
G01X1184554Y1111929D01*
X1184546D01*
G03X1183344Y1110772I0J-1203D01*
G01X1183343Y1110741D01*
X1183322Y1110683D01*
X1183252Y1110591D01*
G02X1183214Y1110553I-159J121D01*
G01X1183187Y1110532D01*
X1183162Y1110522D01*
G03X1182796Y1110355I1391J-3533D01*
G01X1182774Y1110343D01*
X1182724Y1110332D01*
G02X1182635Y1110331I-47J195D01*
G01X1182584Y1110343D01*
X1182561Y1110355D01*
G03X1182304Y1110478I-1766J-3361D01*
G03X1182193Y1110524I-1509J-3484D01*
G01X1182165Y1110535D01*
X1182120Y1110571D01*
X1182027Y1110703D01*
X1182009Y1110756D01*
X1182008Y1110785D01*
G03X1180839Y1111930I-1201J-57D01*
G01X1180809D01*
G03X1179605Y1110783I-3J-1202D01*
G01X1179604Y1110754D01*
X1179586Y1110701D01*
X1179512Y1110597D01*
X1179497Y1110576D01*
X1179461Y1110544D01*
X1179426Y1110527D01*
X1179415Y1110522D01*
X1179411Y1110520D01*
G03X1179051Y1110354I1408J-3526D01*
G01X1179030Y1110343D01*
X1178939Y1110321D01*
X1178867Y1110329D01*
X1178834Y1110347D01*
G03X1178654Y1110437I-1787J-3350D01*
G01X1178652D01*
G03X1178458Y1110520I-1590J-3448D01*
G01X1178431Y1110530D01*
X1178405Y1110550D01*
G02X1178365Y1110592I123J158D01*
G01X1178305Y1110676D01*
X1178288Y1110699D01*
X1178268Y1110756D01*
X1178267Y1110786D01*
G03X1177079Y1111930I-1201J-58D01*
G01X1177066D01*
G03X1175865Y1110783I0J-1202D01*
G02X1175825Y1110670I-200J7D01*
G01X1175783Y1110613D01*
Y1110611D01*
X1175730Y1110540D01*
G02X1175570Y1110459I-161J119D01*
G01X1175531D01*
G03X1175312Y1110354I1531J-3474D01*
G01X1175311Y1110353D01*
X1175281Y1110338D01*
X1175249Y1110330D01*
G02X1175160Y1110329I-47J195D01*
G01X1175110Y1110340D01*
X1175085Y1110353D01*
G03X1174826Y1110478I-1779J-3355D01*
G03X1174713Y1110525I-1515J-3482D01*
G01X1174685Y1110536D01*
X1174640Y1110572D01*
X1174547Y1110705D01*
X1174529Y1110757D01*
X1174528Y1110786D01*
G03X1172850Y1111832I-1201J-58D01*
G03X1172125Y1110785I476J-1104D01*
G01X1172124Y1110756D01*
X1172106Y1110704D01*
X1172033Y1110599D01*
G03X1172031Y1110597I138J-140D01*
G01X1172018Y1110577D01*
X1171980Y1110544D01*
X1171946Y1110527D01*
X1171935Y1110522D01*
X1171931Y1110520D01*
G03X1171571Y1110354I1408J-3526D01*
G01X1171550Y1110343D01*
X1171459Y1110321D01*
X1171387Y1110329D01*
X1171354Y1110347D01*
G03X1171174Y1110437I-1787J-3350D01*
G01X1171172D01*
G03X1170978Y1110520I-1590J-3448D01*
G01X1170951Y1110530D01*
X1170925Y1110550D01*
G02X1170885Y1110592I123J158D01*
G01X1170825Y1110676D01*
X1170808Y1110699D01*
X1170788Y1110756D01*
X1170787Y1110786D01*
G03X1169599Y1111930I-1201J-58D01*
G01X1169586D01*
G03X1168385Y1110783I0J-1202D01*
G02X1168347Y1110672I-200J6D01*
G01X1168289Y1110593D01*
X1168286Y1110590D01*
X1168257Y1110548D01*
G02X1168093Y1110462I-164J114D01*
G01X1168055D01*
G03X1167836Y1110355I1556J-3463D01*
G01X1167813Y1110343D01*
X1167763Y1110332D01*
X1167670D01*
X1167622Y1110344D01*
X1167599Y1110356D01*
X1167598D01*
G03X1167429Y1110441I-1790J-3349D01*
G01X1167403Y1110453D01*
X1167361Y1110489D01*
X1167293Y1110594D01*
G02X1167261Y1110703I168J109D01*
G01Y1110728D01*
G03X1166158Y1112107I-1414J0D01*
G01X1166156D01*
X1166119Y1112116D01*
X1166089Y1112136D01*
G02X1166035Y1112189I111J167D01*
G01X1165840Y1112471D01*
X1165538Y1112904D01*
G02X1165525Y1113111I164J114D01*
G01X1165551Y1113160D01*
X1165646Y1113218D01*
X1165720D01*
X1165742Y1113216D01*
G03X1165845Y1113212I100J1253D01*
G01X1165847D01*
G03X1164591Y1114468I0J1256D01*
G01Y1114467D01*
G03X1164693Y1113972I1256J1D01*
G01X1164701Y1113953D01*
X1164712Y1113899D01*
G02X1164714Y1113835I-196J-38D01*
G01X1164695Y1113689D01*
X1164673Y1113653D01*
G03X1164645Y1113552I172J-102D01*
G01Y1111526D01*
X1164622Y1111436D01*
X1164608Y1111410D01*
G03X1164433Y1110728I1240J-682D01*
G03X1164435Y1110659I1414J6D01*
G01Y1110656D01*
X1164437Y1110588D01*
X1164372Y1110487D01*
X1164316Y1110462D01*
G03X1164093Y1110354I1542J-3469D01*
G01X1164069Y1110342D01*
X1163974Y1110321D01*
X1163928Y1110332D01*
X1163883Y1110343D01*
X1163862Y1110354D01*
G03X1163439Y1110543I-1757J-3365D01*
G02X1163309Y1110730I70J187D01*
G03X1162149Y1111929I-1202J-2D01*
G01X1162114Y1111930D01*
X1162106D01*
G03X1160904Y1110773I0J-1203D01*
G01X1160903Y1110742D01*
X1160882Y1110684D01*
X1160808Y1110588D01*
G02X1160784Y1110561I-161J119D01*
G02X1160718Y1110521I-135J148D01*
G03X1160670Y1110503I1309J-3564D01*
G03X1160668Y1110501I129J-131D01*
G03X1160360Y1110359I1434J-3515D01*
G01X1160348Y1110352D01*
X1160319Y1110342D01*
X1160303Y1110336D01*
X1160273Y1110329D01*
G02X1160210Y1110326I-41J196D01*
G01X1160167Y1110330D01*
X1160132Y1110349D01*
G03X1160077Y1110378I-1798J-3344D01*
G01X1160076D01*
X1160034Y1110399D01*
G03X1159752Y1110525I-1689J-3401D01*
G01X1159725Y1110535D01*
X1159679Y1110571D01*
X1159663Y1110594D01*
X1159605Y1110673D01*
X1159595Y1110704D01*
X1159581Y1110746D01*
G02X1159575Y1110767I189J65D01*
G01X1159566Y1110809D01*
X1159565Y1110823D01*
G03X1158370Y1111930I-1199J-96D01*
G01X1158363D01*
G03X1157164Y1110784I2J-1202D01*
G01X1157163Y1110755D01*
X1157144Y1110702D01*
X1157085Y1110618D01*
G02X1157045Y1110576I-163J115D01*
G01X1156977Y1110522D01*
X1156951Y1110511D01*
G03X1156620Y1110358I1425J-3518D01*
G01X1156616Y1110356D01*
X1156586Y1110342D01*
X1156563Y1110337D01*
X1156541Y1110332D01*
G02X1156446I-47J194D01*
G01X1156402Y1110343D01*
X1156381Y1110354D01*
G03X1155958Y1110543I-1757J-3365D01*
G02X1155828Y1110730I70J187D01*
G03X1154668Y1111929I-1202J-2D01*
G01X1154633Y1111930D01*
X1154625D01*
G03X1153423Y1110773I0J-1203D01*
G01X1153422Y1110742D01*
X1153401Y1110684D01*
X1153327Y1110587D01*
G02X1153246Y1110524I-159J121D01*
G01X1153234Y1110519D01*
X1153232Y1110518D01*
G03X1152872Y1110355I1384J-3535D01*
G01X1152847Y1110342D01*
X1152796Y1110331D01*
G02X1152717Y1110332I-37J197D01*
G01X1152665Y1110342D01*
X1152640Y1110355D01*
G03X1152565Y1110393I-1753J-3367D01*
G01X1152563D01*
G03X1152218Y1110543I-1684J-3402D01*
G01X1152159Y1110565D01*
X1152088Y1110667D01*
Y1110732D01*
G03X1150886Y1111930I-1202J-4D01*
G01X1150885D01*
G03X1149684Y1110785I0J-1202D01*
G01X1149681Y1110728D01*
X1149572Y1110569D01*
X1149525Y1110533D01*
X1149497Y1110522D01*
G03X1148525Y1109962I1389J-3534D01*
G02X1148488Y1109938I-127J155D01*
G03X1147934Y1109384I527J-1081D01*
G02X1147911Y1109347I-180J86D01*
G03X1147353Y1108378I2975J-2359D01*
G01X1147341Y1108347D01*
X1147320Y1108322D01*
X1147302Y1108300D01*
X1147198Y1108226D01*
X1147171Y1108207D01*
X1147114Y1108189D01*
X1147065Y1108187D01*
X1147043Y1108185D01*
X1147041D01*
X1147031Y1108184D01*
G03X1146923Y1108169I111J-1197D01*
G01X1146875Y1108160D01*
X1146780Y1108189D01*
X1146476Y1108492D01*
X1146447Y1108587D01*
X1146456Y1108636D01*
G03X1146477Y1108858I-1181J224D01*
G03X1144073I-1202J0D01*
G03X1144082Y1108714I1202J3D01*
G01X1144087Y1108667D01*
X1144056Y1108579D01*
X1143755Y1108291D01*
X1143666Y1108264D01*
X1143618Y1108272D01*
G03X1143403Y1108290I-216J-1285D01*
G03X1143191Y1108273I-2J-1303D01*
G01X1143143Y1108265D01*
X1143055Y1108292D01*
X1142754Y1108580D01*
X1142723Y1108667D01*
X1142728Y1108715D01*
G03X1142737Y1108858I-1193J147D01*
G03X1141535Y1107656I-1202J0D01*
G03X1141676Y1107664I3J1202D01*
G01X1141724Y1107670D01*
X1141811Y1107638D01*
X1142098Y1107338D01*
X1142126Y1107249D01*
X1142118Y1107201D01*
G03X1142100Y1106987I1285J-216D01*
G01Y1106710D01*
G02X1142034Y1106562I-200J0D01*
G01X1141781Y1106334D01*
X1141702Y1106308D01*
X1141659Y1106313D01*
G03X1141535Y1106319I-120J-1196D01*
G03Y1103915I0J-1202D01*
G03X1141659Y1103921I4J1202D01*
G01X1141702Y1103926D01*
X1141781Y1103900D01*
X1142034Y1103672D01*
G02X1142100Y1103524I-134J-148D01*
G01Y1103247D01*
G03X1142118Y1103033I1303J2D01*
G01X1142125Y1102986D01*
X1142098Y1102897D01*
X1141811Y1102597D01*
X1141724Y1102565D01*
X1141676Y1102571D01*
G03X1141535Y1102579I-138J-1194D01*
G03Y1100175I0J-1202D01*
G03X1141757Y1100196I-2J1202D01*
G01X1141806Y1100205D01*
X1141899Y1100176D01*
X1142204Y1099871D01*
X1142233Y1099778D01*
X1142224Y1099729D01*
G03Y1099285I1181J-222D01*
G01X1142233Y1099236D01*
X1142204Y1099143D01*
X1141899Y1098838D01*
X1141806Y1098809D01*
X1141757Y1098818D01*
G03X1141535Y1098839I-224J-1181D01*
G03Y1096435I0J-1202D01*
G03X1141757Y1096456I-2J1202D01*
G01X1141806Y1096465D01*
X1141899Y1096436D01*
X1142204Y1096131D01*
X1142233Y1096038D01*
X1142224Y1095989D01*
G03Y1095545I1181J-222D01*
G01X1142233Y1095496D01*
X1142204Y1095403D01*
X1141899Y1095098D01*
X1141806Y1095069D01*
X1141757Y1095078D01*
G03X1141535Y1095099I-224J-1181D01*
G03Y1092695I0J-1202D01*
G03X1141757Y1092716I-2J1202D01*
G01X1141806Y1092725D01*
X1141899Y1092696D01*
X1142204Y1092391D01*
X1142233Y1092298D01*
X1142224Y1092249D01*
G03Y1091805I1181J-222D01*
G01X1142233Y1091756D01*
X1142204Y1091663D01*
X1141899Y1091358D01*
X1141806Y1091329D01*
X1141757Y1091338D01*
G03X1141535Y1091359I-224J-1181D01*
G03Y1088955I0J-1202D01*
G03X1141757Y1088976I-2J1202D01*
G01X1141806Y1088985D01*
X1141899Y1088956D01*
X1142204Y1088651D01*
X1142233Y1088558D01*
X1142224Y1088509D01*
G03Y1088065I1181J-222D01*
G01X1142233Y1088016D01*
X1142204Y1087923D01*
X1141899Y1087618D01*
X1141806Y1087589D01*
X1141757Y1087598D01*
G03X1141535Y1087619I-224J-1181D01*
G03Y1085215I0J-1202D01*
G03X1141676Y1085223I3J1202D01*
G01X1141724Y1085229D01*
X1141811Y1085197D01*
X1142098Y1084897D01*
X1142126Y1084808D01*
X1142118Y1084760D01*
G03X1142100Y1084547I1285J-216D01*
G01Y1084270D01*
G02X1142034Y1084122I-200J0D01*
G01X1141781Y1083894D01*
X1141702Y1083868D01*
X1141659Y1083873D01*
G03X1141535Y1083879I-120J-1196D01*
G03Y1081475I0J-1202D01*
G03X1141659Y1081481I4J1202D01*
G01X1141702Y1081486D01*
X1141781Y1081460D01*
X1142034Y1081232D01*
G02X1142100Y1081084I-134J-148D01*
G01Y1080806D01*
G03X1142108Y1080659I1302J-3D01*
G01X1142113Y1080614D01*
X1142084Y1080529D01*
X1141800Y1080242D01*
X1141715Y1080212D01*
X1141669Y1080216D01*
G03X1141535Y1080224I-144J-1279D01*
G03Y1077648I0J-1288D01*
G03X1141750Y1077667I-5J1288D01*
G01X1141797Y1077674D01*
X1141887Y1077647D01*
X1142188Y1077357D01*
X1142219Y1077268D01*
X1142213Y1077221D01*
G03Y1076911I1192J-155D01*
G01X1142219Y1076864D01*
X1142188Y1076775D01*
X1141887Y1076485D01*
X1141797Y1076458D01*
X1141750Y1076465D01*
G03X1141535Y1076484I-220J-1269D01*
G03Y1073908I0J-1288D01*
G03X1141750Y1073927I-5J1288D01*
G01X1141797Y1073934D01*
X1141887Y1073907D01*
X1142188Y1073617D01*
X1142219Y1073528D01*
X1142213Y1073481D01*
G03X1142224Y1073103I1192J-154D01*
G01X1142233Y1073055D01*
X1142204Y1072960D01*
X1141900Y1072656D01*
X1141805Y1072627D01*
X1141757Y1072636D01*
G03X1141534Y1072657I-224J-1181D01*
G03Y1070253I0J-1202D01*
G03X1142571Y1070847I0J1202D01*
G01X1142598Y1070893D01*
X1142690Y1070946D01*
X1142744D01*
G02X1142944Y1070746I0J-200D01*
G01Y1070244D01*
X1142930Y1070209D01*
G03X1142664Y1068787I3660J-1421D01*
G01Y1047860D01*
G02X1142653Y1047796I-200J1D01*
G01X1131569Y1015049D01*
G02X1131521Y1014972I-189J65D01*
G01X1117182Y1000633D01*
G02X1117040Y1000574I-142J141D01*
G01X1097496D01*
G03X1097392Y1000544I1J-200D01*
G01X1097368Y1000530D01*
X1097343Y1000523D01*
G02X1097288Y1000515I-56J192D01*
G01X983307D01*
X983292Y1000517D01*
G03X983118Y1000530I-177J-1203D01*
G01X978980D01*
G03X978875Y1000525I5J-1216D01*
G03X978807Y1000517I108J-1211D01*
G01X978792Y1000515D01*
X975377D01*
X975363Y1000517D01*
G03X975294Y1000525I-175J-1204D01*
G03X975190Y1000530I-110J-1211D01*
G01X922297D01*
G02X922167Y1000585I2J185D01*
G01X921335Y1001416D01*
G02X921276Y1001558I141J142D01*
G01Y1005060D01*
G03X920209Y1006267I-1216J0D01*
G01X920172Y1006272D01*
X920118Y1006301D01*
G02X920065Y1006341I92J177D01*
G01X920009Y1006401D01*
X919982Y1006429D01*
X919955Y1006499D01*
Y1040790D01*
G02X920014Y1040932I200J0D01*
G01X920231Y1041149D01*
G03X920906Y1042780I-1631J1630D01*
G01Y1043572D01*
G03X920438Y1044965I-2307J0D01*
G02Y1045207I160J121D01*
G03X920906Y1046600I-1839J1393D01*
G01Y1047392D01*
G03X920438Y1048785I-2307J0D01*
G02Y1049027I160J121D01*
G03X920906Y1050420I-1839J1393D01*
G01Y1051212D01*
G03X920438Y1052605I-2307J0D01*
G02Y1052847I160J121D01*
G03X920906Y1054240I-1839J1393D01*
G01Y1055032D01*
G03X920438Y1056425I-2307J0D01*
G02Y1056667I160J121D01*
G03X920906Y1058060I-1839J1393D01*
G01Y1058852D01*
G03X920231Y1060483I-2306J1D01*
G01X920025Y1060689D01*
G02X919966Y1060831I141J142D01*
G01Y1067547D01*
G02X920025Y1067689I200J0D01*
G01X920779Y1068443D01*
G02X920781Y1068445I142J-140D01*
G02X920921Y1068502I140J-143D01*
G01X976650D01*
G03X976792Y1068561I0J200D01*
G01X978703Y1070472D01*
G02X978755Y1070510I143J-140D01*
G01X978808Y1070536D01*
X978823Y1070541D01*
G03X978905Y1070591I-60J191D01*
G01X983158Y1074844D01*
G03X983217Y1074986I-141J142D01*
G01Y1076777D01*
G02X983280Y1076923I200J0D01*
G01X983525Y1077152D01*
X983603Y1077180D01*
X983645Y1077177D01*
G03X983751Y1077173I110J1498D01*
G03X985253Y1078660I0J1502D01*
G01Y1078676D01*
G03X985175Y1079153I-1502J-1D01*
G01X985160Y1079198D01*
X985167Y1079247D01*
G02X985185Y1079308I198J-25D01*
G01X985308Y1079558D01*
G02X985420Y1079658I179J-88D01*
G03X986411Y1081071I-512J1413D01*
G03X984909Y1082573I-1502J0D01*
G03X983889Y1082174I0J-1503D01*
G01X983845Y1082133D01*
X983728Y1082113D01*
X983522Y1082203D01*
X983337Y1082284D01*
X983282Y1082308D01*
X983217Y1082407D01*
Y1156727D01*
G02X983276Y1156869I200J0D01*
G01X984702Y1158295D01*
G02X984844Y1158354I142J-141D01*
G01X988674D01*
X988708Y1158341D01*
G03X993504Y1157446I4797J12407D01*
G03X998300Y1158341I-1J13302D01*
G02X998372Y1158354I71J-187D01*
G01X1056649D01*
G02X1056754Y1158325I1J-200D01*
G03X1057381Y1158148I628J1025D01*
G03X1058008Y1158325I-1J1202D01*
G02X1058113Y1158354I104J-171D01*
G01X1060389D01*
G02X1060494Y1158325I1J-200D01*
G03X1061121Y1158148I628J1025D01*
G03X1061748Y1158325I-1J1202D01*
G02X1061853Y1158354I104J-171D01*
G01X1064130D01*
G02X1064235Y1158325I1J-200D01*
G03X1064862Y1158148I628J1025D01*
G03X1065489Y1158325I-1J1202D01*
G02X1065594Y1158354I104J-171D01*
G01X1075350D01*
G02X1075455Y1158325I1J-200D01*
G03X1076082Y1158148I628J1025D01*
G03X1076709Y1158325I-1J1202D01*
G02X1076814Y1158354I104J-171D01*
G01X1078718D01*
G02X1078791Y1158340I0J-200D01*
G01X1078890Y1158302D01*
X1078916Y1158280D01*
G03X1080728I906J1070D01*
G01X1080754Y1158302D01*
X1080853Y1158340D01*
G02X1080926Y1158354I73J-186D01*
G01X1082830D01*
G02X1082935Y1158325I1J-200D01*
G03X1083562Y1158148I628J1025D01*
G03X1084189Y1158325I-1J1202D01*
G02X1084294Y1158354I104J-171D01*
G01X1086570D01*
G02X1086675Y1158325I1J-200D01*
G03X1087302Y1158148I628J1025D01*
G03X1087929Y1158325I-1J1202D01*
G02X1088034Y1158354I104J-171D01*
G01X1090311D01*
G02X1090416Y1158325I1J-200D01*
G03X1091043Y1158148I628J1025D01*
G03X1091670Y1158325I-1J1202D01*
G02X1091775Y1158354I104J-171D01*
G01X1094051D01*
G02X1094156Y1158325I1J-200D01*
G03X1094783Y1158148I628J1025D01*
G03X1095410Y1158325I-1J1202D01*
G02X1095515Y1158354I104J-171D01*
G01X1097791D01*
G02X1097896Y1158325I1J-200D01*
G03X1098523Y1158148I628J1025D01*
G03X1099150Y1158325I-1J1202D01*
G02X1099255Y1158354I104J-171D01*
G01X1101533D01*
X1101592Y1158353D01*
G03X1102934I671J996D01*
G01X1102993Y1158354D01*
X1105273D01*
X1105332Y1158353D01*
G03X1106674I671J996D01*
G01X1106733Y1158354D01*
X1109013D01*
X1109072Y1158353D01*
G03X1110414I671J996D01*
G01X1110473Y1158354D01*
X1112754D01*
X1112813Y1158353D01*
G03X1114155I671J996D01*
G01X1114214Y1158354D01*
X1116494D01*
X1116553Y1158353D01*
G03X1117895I671J996D01*
G01X1117954Y1158354D01*
X1120234D01*
X1120293Y1158353D01*
G03X1121635I671J996D01*
G01X1121694Y1158354D01*
X1123974D01*
X1124033Y1158353D01*
G03X1125375I671J996D01*
G01X1125434Y1158354D01*
X1127714D01*
X1127773Y1158353D01*
G03X1129115I671J996D01*
G01X1129174Y1158354D01*
X1131454D01*
X1131513Y1158353D01*
G03X1132855I671J996D01*
G01X1132914Y1158354D01*
X1135194D01*
X1135253Y1158353D01*
G03X1136595I671J996D01*
G01X1136654Y1158354D01*
X1138935D01*
X1138994Y1158353D01*
G03X1140336I671J996D01*
G01X1140395Y1158354D01*
X1142675D01*
X1142734Y1158353D01*
G03X1143405Y1158148I671J996D01*
G03X1144032Y1158324I1J1202D01*
G01X1144056Y1158339D01*
X1144083Y1158347D01*
G02X1144137Y1158354I52J-193D01*
G01X1144427D01*
G03X1144569Y1158413I0J200D01*
G01X1150882Y1164726D01*
G03X1150941Y1164868I-141J142D01*
G01Y1165451D01*
G02X1151105Y1165648I200J0D01*
G01X1151108Y1165649D01*
G03Y1168011I-223J1181D01*
G01X1151105Y1168012D01*
G02X1150941Y1168209I36J197D01*
G01Y1169191D01*
G02X1151105Y1169388I200J0D01*
G01X1151108Y1169389D01*
G03Y1171751I-223J1181D01*
G01X1151105Y1171752D01*
G02X1150941Y1171949I36J197D01*
G01Y1172931D01*
G02X1151105Y1173128I200J0D01*
G01X1151108Y1173129D01*
G03Y1175491I-223J1181D01*
G01X1151105Y1175492D01*
G02X1150941Y1175689I36J197D01*
G01Y1176672D01*
G02X1151105Y1176869I200J0D01*
G01X1151108Y1176870D01*
G03Y1179232I-223J1181D01*
G01X1151105Y1179233D01*
G02X1150941Y1179430I36J197D01*
G01Y1180412D01*
G02X1151105Y1180609I200J0D01*
G01X1151108Y1180610D01*
G03Y1182972I-223J1181D01*
G01X1151105Y1182973D01*
G02X1150941Y1183170I36J197D01*
G01Y1184152D01*
G02X1151105Y1184349I200J0D01*
G01X1151108Y1184350D01*
G03Y1186712I-223J1181D01*
G01X1151105Y1186713D01*
G02X1150941Y1186910I36J197D01*
G01Y1187892D01*
G02X1151105Y1188089I200J0D01*
G01X1151108Y1188090D01*
G03Y1190452I-223J1181D01*
G01X1151105Y1190453D01*
G02X1150941Y1190650I36J197D01*
G01Y1191706D01*
X1151032Y1191816D01*
X1151104Y1191829D01*
G03X1152087Y1192991I-219J1182D01*
G01Y1193008D01*
G03X1151921Y1193621I-1202J3D01*
G02X1151952Y1193864I172J101D01*
G01X1152942Y1194854D01*
G03X1153001Y1194996I-141J142D01*
G01Y1196376D01*
G03X1152942Y1196518I-200J0D01*
G01X1152360Y1197100D01*
X1152335Y1197143D01*
X1152328Y1197168D01*
G03X1151302Y1198194I-1443J-417D01*
G01X1151261Y1198205D01*
X1151244Y1198209D01*
X1151241Y1198210D01*
G03X1151108Y1198236I-354J-1459D01*
G01X1151107D01*
G03X1150885Y1198252I-219J-1485D01*
G03X1150540Y1198212I-1J-1501D01*
G01X1150517Y1198207D01*
X1113827D01*
G02X1113685Y1198266I0J200D01*
G01X1111158Y1200793D01*
X1111129Y1200821D01*
X1111099Y1200895D01*
Y1215724D01*
G02X1111163Y1215870I200J-1D01*
G01X1111408Y1216099D01*
X1111486Y1216126D01*
X1111527Y1216123D01*
G03X1111613Y1216120I85J1199D01*
G03Y1218524I0J1202D01*
G03X1111527Y1218521I-1J-1202D01*
G01X1111486Y1218518D01*
X1111408Y1218545D01*
X1111163Y1218774D01*
G02X1111099Y1218920I136J147D01*
G01Y1219464D01*
G02X1111163Y1219610I200J-1D01*
G01X1111408Y1219839D01*
X1111486Y1219866D01*
X1111527Y1219863D01*
G03X1111613Y1219860I85J1199D01*
G03Y1222264I0J1202D01*
G03X1111527Y1222261I-1J-1202D01*
G01X1111486Y1222258D01*
X1111408Y1222285D01*
X1111163Y1222514D01*
G02X1111099Y1222660I136J147D01*
G01Y1223205D01*
G02X1111163Y1223351I200J-1D01*
G01X1111408Y1223580D01*
X1111486Y1223607D01*
X1111527Y1223604D01*
G03X1111613Y1223601I85J1199D01*
G03Y1226005I0J1202D01*
G03X1111527Y1226002I-1J-1202D01*
G01X1111486Y1225999D01*
X1111408Y1226026D01*
X1111163Y1226255D01*
G02X1111099Y1226401I136J147D01*
G01Y1226945D01*
G02X1111163Y1227091I200J-1D01*
G01X1111408Y1227320D01*
X1111486Y1227347D01*
X1111527Y1227344D01*
G03X1111613Y1227341I85J1199D01*
G03Y1229745I0J1202D01*
G03X1111527Y1229742I-1J-1202D01*
G01X1111486Y1229739D01*
X1111408Y1229766D01*
X1111163Y1229995D01*
G02X1111099Y1230141I136J147D01*
G01Y1230685D01*
G02X1111163Y1230831I200J-1D01*
G01X1111408Y1231060D01*
X1111486Y1231087D01*
X1111527Y1231084D01*
G03X1111613Y1231081I85J1199D01*
G03Y1233485I0J1202D01*
G03X1111527Y1233482I-1J-1202D01*
G01X1111486Y1233479D01*
X1111408Y1233506D01*
X1111163Y1233735D01*
G02X1111099Y1233881I136J147D01*
G01Y1234425D01*
G02X1111163Y1234571I200J-1D01*
G01X1111408Y1234800D01*
X1111486Y1234827D01*
X1111527Y1234824D01*
G03X1111613Y1234821I85J1199D01*
G03Y1237225I0J1202D01*
G03X1111527Y1237222I-1J-1202D01*
G01X1111486Y1237219D01*
X1111408Y1237246D01*
X1111163Y1237475D01*
G02X1111099Y1237621I136J147D01*
G01Y1238101D01*
G02X1111156Y1238241I200J0D01*
G01X1111157Y1238242D01*
X1111448Y1238533D01*
X1111525Y1238563D01*
X1111567Y1238562D01*
G03X1111613Y1238561I49J1201D01*
G03X1112815Y1239763I0J1202D01*
G03X1112814Y1239809I-1202J-3D01*
G01X1112813Y1239851D01*
X1112843Y1239928D01*
X1113169Y1240254D01*
X1113305Y1240271D01*
X1113365Y1240234D01*
G03X1114022Y1239916I1988J3270D01*
G02X1114152Y1239733I-70J-187D01*
G03X1116556I1202J30D01*
G02X1116686Y1239916I200J-4D01*
G03X1117292Y1240204I-1333J3587D01*
G01X1117341Y1240232D01*
X1117450Y1240231D01*
X1117847Y1239988D01*
X1117898Y1239891D01*
X1117894Y1239835D01*
G03X1117892Y1239763I1200J-69D01*
G03X1120296I1202J0D01*
G03X1120294Y1239835I-1202J3D01*
G01X1120290Y1239891D01*
X1120341Y1239988D01*
X1120738Y1240231D01*
X1120847Y1240232D01*
X1120896Y1240204D01*
G03X1121502Y1239916I1939J3299D01*
G02X1121632Y1239733I-70J-187D01*
G03X1124036I1202J30D01*
G02X1124166Y1239916I200J-4D01*
G03X1124772Y1240204I-1333J3587D01*
G01X1124821Y1240232D01*
X1124930Y1240231D01*
X1125327Y1239988D01*
X1125378Y1239891D01*
X1125374Y1239835D01*
G03X1125372Y1239763I1200J-69D01*
G03X1127776I1202J0D01*
G03X1127774Y1239835I-1202J3D01*
G01X1127770Y1239891D01*
X1127821Y1239988D01*
X1128218Y1240231D01*
X1128327Y1240232D01*
X1128376Y1240204D01*
G03X1128982Y1239916I1939J3299D01*
G02X1129112Y1239733I-70J-187D01*
G03X1131516I1202J30D01*
G02X1131646Y1239916I200J-4D01*
G03X1132252Y1240204I-1333J3587D01*
G01X1132301Y1240232D01*
X1132410Y1240231D01*
X1132807Y1239988D01*
X1132858Y1239891D01*
X1132854Y1239835D01*
G03X1132852Y1239763I1200J-69D01*
G03X1135256I1202J0D01*
G03X1135254Y1239835I-1202J3D01*
G01X1135250Y1239891D01*
X1135301Y1239989D01*
X1135698Y1240232D01*
X1135807Y1240233D01*
X1135856Y1240204D01*
G03X1136463Y1239916I1937J3300D01*
G02X1136593Y1239733I-70J-187D01*
G03X1138997I1202J30D01*
G02X1139127Y1239916I200J-4D01*
G03X1139733Y1240204I-1333J3587D01*
G01X1139782Y1240232D01*
X1139891Y1240231D01*
X1140288Y1239988D01*
X1140339Y1239891D01*
X1140335Y1239835D01*
G03X1140333Y1239763I1200J-69D01*
G03X1142737I1202J0D01*
G03X1142735Y1239835I-1202J3D01*
G01X1142731Y1239891D01*
X1142782Y1239988D01*
X1143179Y1240231D01*
X1143288Y1240232D01*
X1143337Y1240204D01*
G03X1143943Y1239916I1939J3299D01*
G02X1144073Y1239733I-70J-187D01*
G03X1146477I1202J30D01*
G02X1146607Y1239916I200J-4D01*
G03X1147213Y1240204I-1333J3587D01*
G01X1147262Y1240232D01*
X1147371Y1240231D01*
X1147768Y1239988D01*
X1147819Y1239891D01*
X1147815Y1239835D01*
G03X1147813Y1239763I1200J-69D01*
G03X1150217I1202J0D01*
G03X1150215Y1239835I-1202J3D01*
G01X1150211Y1239891D01*
X1150262Y1239988D01*
X1150659Y1240231D01*
X1150768Y1240232D01*
X1150817Y1240204D01*
G03X1151423Y1239916I1939J3299D01*
G02X1151553Y1239733I-70J-187D01*
G03X1153957I1202J30D01*
G02X1154087Y1239916I200J-4D01*
G03X1154693Y1240204I-1333J3587D01*
G01X1154742Y1240232D01*
X1154851Y1240231D01*
X1155248Y1239988D01*
X1155299Y1239891D01*
X1155295Y1239835D01*
G03X1155293Y1239763I1200J-69D01*
G03X1157697I1202J0D01*
G03X1157695Y1239835I-1202J3D01*
G01X1157691Y1239891D01*
X1157742Y1239988D01*
X1158139Y1240231D01*
X1158248Y1240232D01*
X1158297Y1240204D01*
G03X1158903Y1239916I1939J3299D01*
G02X1159033Y1239733I-70J-187D01*
G03X1161437I1202J30D01*
G02X1161567Y1239916I200J-4D01*
G03X1162174Y1240204I-1330J3588D01*
G01X1162223Y1240233D01*
X1162332Y1240232D01*
X1162729Y1239989D01*
X1162780Y1239891D01*
X1162776Y1239835D01*
G03X1162774Y1239763I1200J-69D01*
G03X1165178I1202J0D01*
G03X1165176Y1239835I-1202J3D01*
G01X1165172Y1239891D01*
X1165223Y1239988D01*
X1165620Y1240231D01*
X1165729Y1240232D01*
X1165778Y1240204D01*
G03X1166384Y1239916I1939J3299D01*
G02X1166514Y1239733I-70J-187D01*
G03X1168918I1202J30D01*
G02X1169048Y1239916I200J-4D01*
G03X1169654Y1240204I-1333J3587D01*
G01X1169703Y1240232D01*
X1169812Y1240231D01*
X1170209Y1239988D01*
X1170260Y1239891D01*
X1170256Y1239835D01*
G03X1170254Y1239763I1200J-69D01*
G03X1172658I1202J0D01*
G03X1172637Y1239985I-1202J-2D01*
G01X1172628Y1240034D01*
X1172657Y1240128D01*
X1172961Y1240432D01*
X1173056Y1240461D01*
X1173104Y1240452D01*
G03X1173548I222J1181D01*
G01X1173596Y1240461D01*
X1173691Y1240432D01*
X1173995Y1240128D01*
X1174024Y1240034D01*
X1174015Y1239985D01*
G03X1173994Y1239763I1181J-224D01*
G03X1176398I1202J0D01*
G03X1176377Y1239985I-1202J-2D01*
G01X1176368Y1240034D01*
X1176397Y1240128D01*
X1176701Y1240432D01*
X1176796Y1240461D01*
X1176844Y1240452D01*
G03X1177288I222J1181D01*
G01X1177336Y1240461D01*
X1177431Y1240432D01*
X1177735Y1240128D01*
X1177764Y1240034D01*
X1177755Y1239985D01*
G03X1177734Y1239763I1181J-224D01*
G03X1180138I1202J0D01*
G03X1180117Y1239985I-1202J-2D01*
G01X1180108Y1240034D01*
X1180137Y1240128D01*
X1180441Y1240432D01*
X1180536Y1240461D01*
X1180584Y1240452D01*
G03X1181028I222J1181D01*
G01X1181076Y1240461D01*
X1181171Y1240432D01*
X1181475Y1240128D01*
X1181504Y1240034D01*
X1181495Y1239985D01*
G03X1181474Y1239763I1181J-224D01*
G03X1183878I1202J0D01*
G03X1183857Y1239985I-1202J-2D01*
G01X1183848Y1240034D01*
X1183877Y1240128D01*
X1184181Y1240432D01*
X1184276Y1240461D01*
X1184324Y1240452D01*
G03X1184769I223J1181D01*
G01X1184817Y1240461D01*
X1184912Y1240432D01*
X1185216Y1240128D01*
X1185245Y1240034D01*
X1185236Y1239985D01*
G03X1185215Y1239763I1181J-224D01*
G03X1187619I1202J0D01*
G03X1187598Y1239985I-1202J-2D01*
G01X1187589Y1240034D01*
X1187618Y1240128D01*
X1187922Y1240432D01*
X1188017Y1240461D01*
X1188065Y1240452D01*
G03X1188509I222J1181D01*
G01X1188557Y1240461D01*
X1188652Y1240432D01*
X1188956Y1240128D01*
X1188985Y1240034D01*
X1188976Y1239985D01*
G03X1188955Y1239763I1181J-224D01*
G03X1191359I1202J0D01*
G03X1191338Y1239985I-1202J-2D01*
G01X1191329Y1240034D01*
X1191358Y1240128D01*
X1191662Y1240432D01*
X1191757Y1240461D01*
X1191805Y1240452D01*
G03X1192249I222J1181D01*
G01X1192297Y1240461D01*
X1192392Y1240432D01*
X1192696Y1240128D01*
X1192725Y1240034D01*
X1192716Y1239985D01*
G03X1192695Y1239763I1181J-224D01*
G03X1195099I1202J0D01*
G03X1195078Y1239985I-1202J-2D01*
G01X1195069Y1240034D01*
X1195098Y1240128D01*
X1195402Y1240432D01*
X1195497Y1240461D01*
X1195545Y1240452D01*
G03X1195989I222J1181D01*
G01X1196037Y1240461D01*
X1196132Y1240432D01*
X1196436Y1240128D01*
X1196465Y1240034D01*
X1196456Y1239985D01*
G03X1196435Y1239763I1181J-224D01*
G03X1198839I1202J0D01*
G03X1198818Y1239985I-1202J-2D01*
G01X1198809Y1240034D01*
X1198838Y1240128D01*
X1199142Y1240432D01*
X1199237Y1240461D01*
X1199285Y1240452D01*
G03X1199729I222J1181D01*
G01X1199777Y1240461D01*
X1199872Y1240432D01*
X1200176Y1240128D01*
X1200205Y1240034D01*
X1200196Y1239985D01*
G03X1200175Y1239763I1181J-224D01*
G03X1202579I1202J0D01*
G03X1202558Y1239985I-1202J-2D01*
G01X1202549Y1240034D01*
X1202578Y1240128D01*
X1202882Y1240432D01*
X1202977Y1240461D01*
X1203025Y1240452D01*
G03X1203469I222J1181D01*
G01X1203517Y1240461D01*
X1203612Y1240432D01*
X1203916Y1240128D01*
X1203945Y1240034D01*
X1203936Y1239985D01*
G03X1203915Y1239763I1181J-224D01*
G03X1206319I1202J0D01*
G03X1206298Y1239985I-1202J-2D01*
G01X1206289Y1240034D01*
X1206318Y1240128D01*
X1206622Y1240432D01*
X1206717Y1240461D01*
X1206765Y1240452D01*
G03X1207210I222J1181D01*
G01X1207258Y1240461D01*
X1207353Y1240432D01*
X1207657Y1240128D01*
X1207686Y1240034D01*
X1207677Y1239985D01*
G03X1207656Y1239763I1181J-224D01*
G03X1210060I1202J0D01*
G03X1210039Y1239985I-1202J-2D01*
G01X1210030Y1240034D01*
X1210059Y1240128D01*
X1210363Y1240432D01*
X1210458Y1240461D01*
X1210506Y1240452D01*
G03X1210950I222J1181D01*
G01X1210998Y1240461D01*
X1211093Y1240432D01*
X1211397Y1240128D01*
X1211426Y1240034D01*
X1211417Y1239985D01*
G03X1211396Y1239763I1181J-224D01*
G03X1213800I1202J0D01*
G03X1213779Y1239985I-1202J-2D01*
G01X1213770Y1240034D01*
X1213799Y1240128D01*
X1214103Y1240432D01*
X1214198Y1240461D01*
X1214246Y1240452D01*
G03X1214690I222J1181D01*
G01X1214738Y1240461D01*
X1214833Y1240432D01*
X1215137Y1240128D01*
X1215166Y1240034D01*
X1215157Y1239985D01*
G03X1215136Y1239763I1181J-224D01*
G03X1217540I1202J0D01*
G03X1217519Y1239985I-1202J-2D01*
G01X1217510Y1240034D01*
X1217539Y1240128D01*
X1217843Y1240432D01*
X1217938Y1240461D01*
X1217986Y1240452D01*
G03X1218430I222J1181D01*
G01X1218478Y1240461D01*
X1218573Y1240432D01*
X1218877Y1240128D01*
X1218906Y1240034D01*
X1218897Y1239985D01*
G03X1218876Y1239763I1181J-224D01*
G03X1221280I1202J0D01*
G03X1221259Y1239985I-1202J-2D01*
G01X1221250Y1240034D01*
X1221279Y1240128D01*
X1221583Y1240432D01*
X1221678Y1240461D01*
X1221726Y1240452D01*
G03X1222170I222J1181D01*
G01X1222218Y1240461D01*
X1222313Y1240432D01*
X1222617Y1240128D01*
X1222646Y1240034D01*
X1222637Y1239985D01*
G03X1222616Y1239763I1181J-224D01*
G03X1225020I1202J0D01*
G03X1224999Y1239985I-1202J-2D01*
G01X1224990Y1240034D01*
X1225019Y1240128D01*
X1225323Y1240432D01*
X1225418Y1240461D01*
X1225466Y1240452D01*
G03X1225910I222J1181D01*
G01X1225958Y1240461D01*
X1226053Y1240432D01*
X1226357Y1240128D01*
X1226386Y1240034D01*
X1226377Y1239985D01*
G03X1226356Y1239763I1181J-224D01*
G03X1228760I1202J0D01*
G03X1228739Y1239985I-1202J-2D01*
G01X1228730Y1240034D01*
X1228759Y1240128D01*
X1229063Y1240432D01*
X1229158Y1240461D01*
X1229206Y1240452D01*
G03X1229650I222J1181D01*
G01X1229698Y1240461D01*
X1229793Y1240432D01*
X1230097Y1240128D01*
X1230126Y1240034D01*
X1230117Y1239985D01*
G03X1230096Y1239763I1181J-224D01*
G03X1232500I1202J0D01*
G03X1232479Y1239985I-1202J-2D01*
G01X1232470Y1240034D01*
X1232499Y1240128D01*
X1232803Y1240432D01*
X1232898Y1240461D01*
X1232946Y1240452D01*
G03X1233391I223J1181D01*
G01X1233439Y1240461D01*
X1233534Y1240432D01*
X1233838Y1240128D01*
X1233867Y1240034D01*
X1233858Y1239985D01*
G03X1233837Y1239763I1181J-224D01*
G03X1236241I1202J0D01*
G03X1236233Y1239906I-1202J4D01*
G01X1236227Y1239953D01*
X1236258Y1240041D01*
X1236559Y1240328D01*
X1236648Y1240356D01*
X1236695Y1240348D01*
G03X1236909Y1240330I216J1284D01*
G01X1237186D01*
G02X1237334Y1240264I0J-200D01*
G01X1237562Y1240011D01*
X1237588Y1239931D01*
X1237584Y1239888D01*
G03X1237577Y1239763I1195J-130D01*
G03X1239981I1202J0D01*
G03X1239974Y1239888I-1202J-5D01*
G01X1239970Y1239931D01*
X1239996Y1240011D01*
X1240224Y1240264D01*
G02X1240372Y1240330I148J-134D01*
G01X1240649D01*
G03X1240864Y1240348I-1J1302D01*
G01X1240911Y1240356D01*
X1241000Y1240328D01*
X1241301Y1240041D01*
X1241332Y1239953D01*
X1241327Y1239906D01*
G03X1241318Y1239762I1193J-147D01*
G03X1243722I1202J0D01*
G03X1243629Y1240225I-1202J-1D01*
G02X1243624Y1240366I185J77D01*
G01X1243664Y1240484D01*
G02X1243753Y1240593I189J-64D01*
G03X1243927Y1240716I-605J1041D01*
G01X1243953Y1240738D01*
X1244052Y1240776D01*
G02X1244121Y1240789I71J-187D01*
G01X1244203Y1240790D01*
G02X1244345Y1240733I2J-200D01*
G01X1244346Y1240732D01*
X1251035Y1234043D01*
G02X1251037Y1234041I-140J-142D01*
G02X1251094Y1233901I-143J-140D01*
G01Y1197134D01*
X1250995Y1197022D01*
X1250920Y1197012D01*
G03Y1194032I191J-1490D01*
G01X1250995Y1194022D01*
X1251094Y1193910D01*
Y1187511D01*
G02X1251001Y1187341I-200J-1D01*
G03Y1184801I800J-1270D01*
G02X1251094Y1184631I-107J-169D01*
G01Y1174423D01*
G02X1251061Y1174313I-200J0D01*
G02X1250974Y1174240I-167J110D01*
G01X1250972Y1174239D01*
X1250651Y1174105D01*
X1250649D01*
X1250615Y1174090D01*
X1250534Y1174089D01*
X1250415Y1174138D01*
X1250388Y1174163D01*
G03X1249363Y1174567I-1025J-1098D01*
G03Y1171563I0J-1502D01*
G03X1250388Y1171967I0J1502D01*
G01X1250415Y1171992D01*
X1250498Y1172026D01*
G02X1250650Y1172025I75J-186D01*
G01X1250970Y1171892D01*
G02X1250975Y1171890I-72J-187D01*
G02X1251062Y1171815I-82J-183D01*
G02X1251094Y1171707I-168J-108D01*
G01Y1167423D01*
G02X1251061Y1167313I-200J0D01*
G02X1250974Y1167240I-167J110D01*
G01X1250972Y1167239D01*
X1250651Y1167105D01*
X1250649D01*
X1250615Y1167090D01*
X1250534Y1167089D01*
X1250415Y1167138D01*
X1250388Y1167163D01*
G03X1249363Y1167567I-1025J-1098D01*
G03X1247861Y1166093I0J-1502D01*
G01Y1166078D01*
Y1166065D01*
G03X1248403Y1164910I1502J0D01*
G01X1248441Y1164878D01*
X1248479Y1164785D01*
X1248431Y1164353D01*
X1248375Y1164271D01*
X1248330Y1164248D01*
G03X1247521Y1162915I694J-1333D01*
G03X1249023Y1161413I1502J0D01*
G03X1250524Y1162867I0J1502D01*
G01X1250525Y1162895D01*
Y1162915D01*
G03X1249984Y1164069I-1501J0D01*
G02X1249913Y1164245I128J154D01*
G01X1249955Y1164627D01*
X1250011Y1164709D01*
X1250056Y1164732D01*
G03X1250388Y1164967I-694J1332D01*
G01X1250415Y1164992D01*
X1250498Y1165026D01*
G02X1250650Y1165025I75J-186D01*
G01X1250970Y1164892D01*
G02X1250975Y1164890I-72J-187D01*
G02X1251062Y1164815I-82J-183D01*
G02X1251094Y1164707I-168J-108D01*
G01Y1145373D01*
G02X1250936Y1145177I-200J0D01*
G01X1250935D01*
G03X1249748Y1143810I312J-1470D01*
G02X1249710Y1143707I-200J15D01*
G03X1249426Y1142828I1218J-879D01*
G03X1249508Y1142337I1502J-1D01*
G01X1249527Y1142283D01*
X1249502Y1142172D01*
X1246859Y1139529D01*
G02X1246717Y1139470I-142J141D01*
G01X1244597D01*
G03X1243199Y1139210I1J-3891D01*
G01X1243183Y1139204D01*
X1243129Y1139194D01*
G02X1243091Y1139190I-40J196D01*
G01X1241827D01*
X1241802Y1139196D01*
G02X1241669Y1139307I49J194D01*
G01Y1139308D01*
X1241527Y1139624D01*
G02X1241522Y1139776I182J82D01*
G01X1241550Y1139852D01*
X1241572Y1139879D01*
X1241573Y1139880D01*
G03X1241851Y1140649I-925J769D01*
G03X1239447I-1202J0D01*
G03X1239725Y1139880I1203J0D01*
G01X1239726Y1139879D01*
X1239748Y1139852D01*
X1239776Y1139776D01*
G02X1239771Y1139624I-187J-70D01*
G01X1239629Y1139308D01*
Y1139307D01*
G02X1239496Y1139196I-182J83D01*
G01X1239471Y1139190D01*
X1238087D01*
X1238062Y1139196D01*
G02X1237929Y1139307I49J194D01*
G01Y1139308D01*
X1237787Y1139624D01*
G02X1237782Y1139776I182J82D01*
G01X1237810Y1139852D01*
X1237832Y1139879D01*
X1237833Y1139880D01*
G03X1238111Y1140649I-925J769D01*
G03X1235707I-1202J0D01*
G03X1235985Y1139880I1203J0D01*
G01X1235986Y1139879D01*
X1236008Y1139852D01*
X1236036Y1139776D01*
G02X1236031Y1139624I-187J-70D01*
G01X1235889Y1139308D01*
Y1139307D01*
G02X1235756Y1139196I-182J83D01*
G01X1235731Y1139190D01*
X1234347D01*
X1234322Y1139196D01*
G02X1234189Y1139307I49J194D01*
G01Y1139308D01*
X1234047Y1139624D01*
G02X1234042Y1139776I182J82D01*
G01X1234070Y1139852D01*
X1234092Y1139879D01*
X1234093Y1139880D01*
G03X1234371Y1140649I-925J769D01*
G03X1231967I-1202J0D01*
G03X1232245Y1139880I1203J0D01*
G01X1232246Y1139879D01*
X1232268Y1139852D01*
X1232296Y1139776D01*
G02X1232291Y1139624I-187J-70D01*
G01X1232149Y1139308D01*
Y1139307D01*
G02X1232016Y1139196I-182J83D01*
G01X1231991Y1139190D01*
X1230606D01*
X1230581Y1139196D01*
G02X1230448Y1139307I49J194D01*
G01Y1139308D01*
X1230306Y1139624D01*
G02X1230301Y1139776I182J82D01*
G01X1230329Y1139852D01*
X1230351Y1139879D01*
X1230352Y1139880D01*
G03X1230630Y1140649I-925J769D01*
G03X1228226I-1202J0D01*
G03X1228504Y1139880I1203J0D01*
G01X1228505Y1139879D01*
X1228527Y1139852D01*
X1228555Y1139776D01*
G02X1228550Y1139624I-187J-70D01*
G01X1228408Y1139308D01*
Y1139307D01*
G02X1228275Y1139196I-182J83D01*
G01X1228250Y1139190D01*
X1226866D01*
X1226841Y1139196D01*
G02X1226708Y1139307I49J194D01*
G01Y1139308D01*
X1226566Y1139624D01*
G02X1226561Y1139776I182J82D01*
G01X1226589Y1139852D01*
X1226611Y1139879D01*
X1226612Y1139880D01*
G03X1226890Y1140649I-925J769D01*
G03X1224486I-1202J0D01*
G03X1224492Y1140532I1202J3D01*
G01X1224497Y1140476D01*
X1224448Y1140374D01*
X1224106Y1140157D01*
G02X1224013Y1140126I-108J169D01*
G02X1223944Y1140133I-15J200D01*
G01X1223889Y1140149D01*
X1223866Y1140162D01*
X1223865Y1140163D01*
G03X1223821Y1140188I-1888J-3271D01*
G03X1223335Y1140422I-1877J-3277D01*
G01X1223307Y1140433D01*
X1223262Y1140469D01*
X1223168Y1140604D01*
X1223150Y1140659D01*
X1223149Y1140688D01*
G03X1221948Y1141851I-1201J-39D01*
G03X1220776Y1140914I0J-1201D01*
G01X1220771Y1140884D01*
X1220751Y1140848D01*
G02X1220712Y1140800I-173J101D01*
G01X1220605Y1140703D01*
X1220544Y1140677D01*
X1220511Y1140674D01*
G03X1220357Y1140659I289J-3765D01*
G03X1220114Y1140622I447J-3750D01*
G02X1220042I-36J197D01*
G03X1219799Y1140659I-690J-3713D01*
G03X1219645Y1140674I-443J-3750D01*
G01X1219612Y1140677D01*
X1219551Y1140703D01*
X1219444Y1140800D01*
G02X1219405Y1140848I134J149D01*
G01X1219385Y1140883D01*
X1219381Y1140913D01*
G03X1218208Y1141851I-1173J-264D01*
G03X1217007Y1140688I0J-1202D01*
G01X1217006Y1140659D01*
X1216988Y1140604D01*
X1216894Y1140469D01*
X1216849Y1140433D01*
X1216821Y1140422D01*
G03X1216335Y1140188I1391J-3511D01*
G03X1216291Y1140163I1844J-3296D01*
G01X1216290Y1140162D01*
X1216267Y1140149D01*
X1216212Y1140133D01*
G02X1216143Y1140126I-54J193D01*
G02X1216050Y1140157I15J200D01*
G01X1215708Y1140374D01*
X1215659Y1140476D01*
X1215664Y1140532D01*
G03X1215670Y1140649I-1196J120D01*
G03X1213266I-1202J0D01*
G03X1213536Y1139890I1202J0D01*
G01X1213573Y1139845D01*
X1213587Y1139730D01*
X1213407Y1139351D01*
G02X1213226Y1139237I-181J86D01*
G01X1208230D01*
G02X1208049Y1139351I0J200D01*
G01X1207869Y1139730D01*
X1207883Y1139845D01*
X1207920Y1139890D01*
G03X1208190Y1140649I-932J759D01*
G03X1205786I-1202J0D01*
G03X1206056Y1139890I1202J0D01*
G01X1206093Y1139845D01*
X1206107Y1139730D01*
X1205927Y1139351D01*
G02X1205746Y1139237I-181J86D01*
G01X1204489D01*
G02X1204308Y1139351I0J200D01*
G01X1204128Y1139730D01*
X1204142Y1139845D01*
X1204179Y1139890D01*
G03X1204449Y1140649I-932J759D01*
G03X1202045I-1202J0D01*
G03X1202062Y1140449I1202J1D01*
G01X1202061D01*
G03X1203076Y1139459I1186J200D01*
G01X1203126Y1139452D01*
G03X1203245Y1139446I120J1197D01*
G01X1203247D01*
G03X1203640Y1139512I0J1203D01*
G01X1203671Y1139523D01*
X1203705D01*
G02X1203905Y1139323I0J-200D01*
G01Y1139287D01*
X1203960Y1139171D01*
G02X1203979Y1139086I-181J-85D01*
G01Y1138476D01*
G02X1203978Y1138455I-200J-1D01*
G02X1203946Y1138367I-199J22D01*
G02X1203904Y1138320I-168J108D01*
G01X1203836Y1138266D01*
X1203833Y1138263D01*
X1203667Y1138128D01*
G02X1203541Y1138083I-126J155D01*
G01X1203509D01*
X1203489Y1138087D01*
G03X1203251Y1138111I-239J-1178D01*
G01X1203162D01*
G03X1203129Y1138108I2J-200D01*
G01X1203045Y1138094D01*
G03X1203022Y1138089I244J-1177D01*
G01X1203018D01*
G03X1202045Y1136909I229J-1180D01*
G03X1203247Y1135707I1202J0D01*
G03X1203605Y1135761I2J1202D01*
G01X1203617Y1135765D01*
X1203627Y1135767D01*
G03X1203647Y1135773I-47J194D01*
G01X1203660Y1135778D01*
X1203743Y1135796D01*
X1203779D01*
G02X1203979Y1135596I0J-200D01*
G01Y1135522D01*
X1203959Y1135458D01*
X1203939Y1135431D01*
G03X1203795Y1135223I3048J-2264D01*
G03X1203546Y1134772I3192J-2056D01*
G01X1203521Y1134717D01*
G03X1203456Y1134561I3471J-1538D01*
G01X1203455Y1134558D01*
X1203452Y1134551D01*
G02X1203385Y1134464I-186J74D01*
G01X1203357Y1134444D01*
X1203313Y1134416D01*
G02X1203267Y1134394I-109J168D01*
G01X1203193Y1134370D01*
X1203168Y1134369D01*
G03X1202045Y1133169I80J-1200D01*
G03X1203167Y1131969I1203J0D01*
G01X1203193Y1131968D01*
X1203263Y1131945D01*
X1203296Y1131933D01*
X1203383Y1131874D01*
X1203403Y1131846D01*
X1203445Y1131796D01*
X1203463Y1131759D01*
X1203466Y1131752D01*
X1203467Y1131750D01*
G03X1203606Y1131444I3522J1415D01*
G03X1203625Y1131407I3387J1716D01*
G03X1203921Y1130934I3357J1772D01*
G01X1203939Y1130909D01*
X1203979Y1130789D01*
Y1130727D01*
G02X1203896Y1130565I-200J0D01*
G01X1203857Y1130537D01*
X1203762Y1130522D01*
X1203703Y1130542D01*
X1203697Y1130544D01*
G03X1203253Y1130631I-449J-1115D01*
G01X1203231D01*
G03X1203117Y1130624I17J-1202D01*
G03X1202045Y1129429I130J-1195D01*
G03X1203247Y1128227I1202J0D01*
G03X1203605Y1128281I2J1202D01*
G01X1203617Y1128285D01*
X1203627Y1128287D01*
G03X1203647Y1128293I-47J194D01*
G01X1203660Y1128298D01*
X1203743Y1128316D01*
X1203779D01*
G02X1203979Y1128116I0J-200D01*
G01Y1128041D01*
X1203959Y1127977D01*
X1203939Y1127950D01*
G03X1203795Y1127742I3048J-2264D01*
G03X1203546Y1127291I3192J-2056D01*
G01X1203521Y1127236D01*
G03X1203456Y1127080I3471J-1538D01*
G01X1203455Y1127077D01*
X1203452Y1127070D01*
G02X1203385Y1126983I-186J74D01*
G01X1203357Y1126963D01*
X1203313Y1126935D01*
G02X1203267Y1126913I-109J168D01*
G01X1203193Y1126889D01*
X1203168Y1126888D01*
G03X1202045Y1125688I80J-1200D01*
G03X1203167Y1124488I1203J0D01*
G01X1203193Y1124487D01*
X1203263Y1124464D01*
X1203296Y1124452D01*
X1203383Y1124393D01*
X1203403Y1124365D01*
X1203445Y1124315D01*
X1203463Y1124278D01*
X1203466Y1124271D01*
X1203467Y1124269D01*
G03X1203606Y1123963I3522J1415D01*
G03X1203625Y1123926I3387J1716D01*
G03X1203921Y1123453I3357J1772D01*
G01X1203939Y1123428D01*
X1203979Y1123308D01*
Y1123246D01*
G02X1203896Y1123084I-200J0D01*
G01X1203857Y1123056D01*
X1203762Y1123041D01*
X1203703Y1123061D01*
X1203697Y1123063D01*
G03X1203253Y1123150I-449J-1115D01*
G01X1203231D01*
G03X1203117Y1123143I17J-1202D01*
G03X1202045Y1121948I130J-1195D01*
G37*
G36*
G01X1115344Y1639801D02*
X1211366D01*
G02X1211403Y1639797I-3J-200D01*
G01X1211405D01*
G02X1211506Y1639744I-39J-196D01*
G01X1211528Y1639722D01*
X1211564Y1639707D01*
G03X1211640Y1639692I76J185D01*
G01X1232376D01*
G02X1232574Y1639516I0J-199D01*
G01Y1552480D01*
Y1552280D01*
X1285356D01*
X1285376Y1552284D01*
G03X1285525Y1552420I-42J196D01*
G01X1285534Y1552448D01*
Y1639506D01*
G02X1285734Y1639692I200J-15D01*
G01X1543003D01*
G02X1543203Y1639492I0J-200D01*
G01Y1628290D01*
G02X1543186Y1628210I-200J1D01*
G01X1500130D01*
G03X1499208Y1627828I1J-1306D01*
G01X1495753Y1624373D01*
G02X1495614Y1624314I-142J141D01*
G01X1495613D01*
G03X1493718Y1622402I17J-1912D01*
G03X1495630Y1620490I1912J0D01*
G03X1497542Y1622385I0J1912D01*
G01Y1622386D01*
G02X1497601Y1622525I200J-3D01*
G01X1500632Y1625556D01*
G02X1500660Y1625558I28J-198D01*
G01X1531157D01*
G02X1531242Y1625539I0J-200D01*
G01X1531285Y1625435D01*
G02X1531242Y1625216I-184J-78D01*
G01X1530398Y1624373D01*
G02X1530259Y1624314I-142J141D01*
G01X1530258D01*
G03X1528363Y1622402I17J-1912D01*
G03X1530275Y1620490I1912J0D01*
G03X1532187Y1622385I0J1912D01*
G01Y1622386D01*
G02X1532246Y1622525I200J-3D01*
G01X1533849Y1624129D01*
G02X1533991Y1624188I142J-141D01*
G01X1543123D01*
G02X1543203Y1624028I-120J-160D01*
G01Y1612337D01*
G02X1543145Y1612195I-200J-1D01*
G01X1542415Y1611465D01*
G03X1541974Y1610400I1065J-1065D01*
G01Y1554821D01*
G03X1542045Y1554364I1506J0D01*
G01X1542054Y1554334D01*
Y1551919D01*
G03X1542113Y1551777I200J0D01*
G01X1547259Y1546631D01*
G03X1547401Y1546572I142J141D01*
G01X1552245D01*
G02X1552282Y1546568I-3J-200D01*
G01X1552284D01*
G02X1552385Y1546515I-39J-196D01*
G01X1586111Y1512789D01*
G02X1586164Y1512688I-143J-140D01*
G01Y1512686D01*
G02X1586168Y1512649I-196J-40D01*
G01Y1478925D01*
G02X1586109Y1478783I-200J0D01*
G01X1557867Y1450541D01*
G02X1557650Y1450498I-141J142D01*
G01X1557593Y1450521D01*
X1557526Y1450622D01*
Y1451156D01*
G02X1557542Y1451234I200J0D01*
G01X1557586Y1451339D01*
X1557614Y1451367D01*
G03X1558172Y1452717I-1354J1350D01*
G03X1556260Y1454629I-1912J0D01*
G03X1554362Y1452953I0J-1913D01*
G01X1554358Y1452920D01*
X1554329Y1452860D01*
X1543882Y1442412D01*
G02X1543740Y1442353I-142J141D01*
G01X1541404D01*
G02X1541204Y1442553I0J200D01*
G01Y1452292D01*
X1541207Y1452309D01*
G03X1541244Y1452717I-2270J412D01*
G03X1538937Y1455024I-2307J0D01*
G03X1537306Y1454348I1J-2307D01*
G01X1530096Y1447138D01*
G02X1530068Y1447136I-28J198D01*
G01X1524080D01*
G02X1523880Y1447336I0J200D01*
G01Y1452286D01*
X1523883Y1452304D01*
G03X1523920Y1452714I-2269J411D01*
G01Y1452717D01*
G03X1521614Y1455024I-2307J0D01*
G03X1519983Y1454348I1J-2307D01*
G01X1516249Y1450614D01*
G02X1516220Y1450612I-28J198D01*
G01X1505758D01*
G02X1505558Y1450812I0J200D01*
G01Y1451158D01*
G02X1505574Y1451235I200J-1D01*
G01X1505619Y1451340D01*
X1505646Y1451367D01*
G03X1506203Y1452716I-1356J1349D01*
G01Y1452717D01*
G03X1504291Y1454629I-1912J0D01*
G03X1504039Y1454613I-5J-1912D01*
G03X1503621Y1454508I254J-1895D01*
G03X1502940Y1454072I667J-1792D01*
G01X1502878Y1454030D01*
X1502809Y1454000D01*
G02X1502731Y1453984I-78J184D01*
G01X1499751D01*
G03X1498855Y1453613I0J-1267D01*
G01X1492391Y1447148D01*
G02X1492293Y1447095I-140J142D01*
G02X1492250Y1447090I-44J195D01*
G01X1490229D01*
G02X1490138Y1447112I0J200D01*
G02X1490088Y1447148I90J178D01*
G01X1488292Y1448944D01*
G02X1488256Y1448994I142J140D01*
G02X1488234Y1449085I178J91D01*
G01Y1451156D01*
G02X1488250Y1451234I200J0D01*
G01X1488294Y1451339D01*
X1488322Y1451367D01*
G03X1488880Y1452717I-1354J1350D01*
G03X1485056I-1912J0D01*
G01Y1452683D01*
X1485057Y1452642D01*
X1485042Y1452605D01*
G02X1484998Y1452538I-186J74D01*
G01X1463508Y1431048D01*
G02X1463458Y1431012I-140J142D01*
G02X1463367Y1430990I-91J178D01*
G01X1441621D01*
G03X1440728Y1430620I2J-1267D01*
G01X1431362Y1421254D01*
G03X1430992Y1420361I897J-895D01*
G01Y1415489D01*
G02X1430985Y1415437I-200J0D01*
G01X1430964Y1415363D01*
X1430952Y1415342D01*
G03X1430804Y1414976I1306J-741D01*
G01X1430802Y1414967D01*
G02X1430755Y1414888I-191J60D01*
G01X1430292Y1414426D01*
G03X1429922Y1413533I897J-895D01*
G01Y1364017D01*
G03Y1364014I1266J-1D01*
G01Y1347101D01*
G02X1429900Y1347010I-200J0D01*
G02X1429864Y1346960I-178J90D01*
G01X1424546Y1341642D01*
X1424545D01*
G02X1424404Y1341584I-141J142D01*
G01X1409542D01*
G03X1409057Y1341487I1J-1267D01*
G01X1407781Y1340958D01*
G02X1407719Y1340948I-62J190D01*
G01X1407716D01*
X1378507Y1340901D01*
G02X1378382Y1340959I17J199D01*
G01X1378373Y1340969D01*
G02X1378329Y1341047I148J135D01*
G01X1378319Y1341082D01*
X1378433Y1342014D01*
X1378568Y1343102D01*
G02X1378581Y1343153I199J-23D01*
G01X1378692Y1343423D01*
X1378993Y1344158D01*
X1379570Y1345568D01*
G03X1379824Y1346511I-3601J1476D01*
G01X1379829Y1346547D01*
X1379863Y1346612D01*
X1379891Y1346635D01*
G02X1380022Y1346684I131J-151D01*
G01X1381759D01*
G03Y1349690I0J1503D01*
G01X1380060D01*
G02X1379860Y1349890I0J200D01*
G01Y1353576D01*
G02X1379861Y1353594I200J-2D01*
G01X1379862Y1353598D01*
Y1353600D01*
X1379885Y1353782D01*
G02X1379896Y1353828I199J-23D01*
G01X1381660Y1358469D01*
G02X1381836Y1358598I187J-71D01*
G01X1381837D01*
G03X1383262Y1360099I-78J1501D01*
G03X1382796Y1361186I-1502J-1D01*
G02X1382792Y1361190I139J143D01*
G01X1382770Y1361212D01*
X1382746Y1361326D01*
X1386329Y1370753D01*
G02X1386516Y1370882I187J-71D01*
G01X1387059D01*
G03X1388562Y1372385I0J1503D01*
G03X1387672Y1373757I-1503J0D01*
G01X1387533Y1373819D01*
X1387504Y1373846D01*
X1400207Y1407268D01*
Y1407270D01*
X1404687Y1418754D01*
X1407274Y1425386D01*
G02X1407367Y1425490I186J-73D01*
G01X1407397Y1425506D01*
X1407468Y1425516D01*
X1407503Y1425508D01*
G03X1407825Y1425473I322J1467D01*
G03X1409327Y1426975I0J1502D01*
G03X1408569Y1428280I-1502J0D01*
G01X1408568D01*
G02X1408497Y1428350I101J173D01*
G01X1408418Y1428481D01*
G02X1408426Y1428536I200J-1D01*
G01X1409781Y1432460D01*
G02X1409783Y1432466I191J-60D01*
G01X1416460Y1450035D01*
G03X1416680Y1450893I-3669J1398D01*
G01X1416858Y1452183D01*
G02X1416868Y1452222I198J-30D01*
G01X1417279Y1453392D01*
G03X1417500Y1454668I-3671J1293D01*
G01Y1454685D01*
G03X1417499Y1454765I-3892J-9D01*
G01X1417462Y1456567D01*
X1417464Y1456579D01*
G03X1417488Y1457011I-3903J433D01*
G03X1417487Y1457091I-3927J-9D01*
G01X1416174Y1521298D01*
G03X1415930Y1522581I-3926J-82D01*
G01X1412432Y1532031D01*
G03X1411776Y1533171I-3683J-1361D01*
G01X1409780Y1535583D01*
X1409772Y1535712D01*
X1409807Y1535767D01*
G03X1410039Y1536569I-1272J802D01*
G01Y1536570D01*
G03X1408536Y1538073I-1503J0D01*
G01X1408535D01*
G03X1407986Y1537969I0J-1503D01*
G01X1407913Y1537955D01*
G02X1407759Y1538028I0J200D01*
G01X1404878Y1541511D01*
G03X1404139Y1542200I-3025J-2504D01*
G01X1402910Y1543081D01*
G02X1402872Y1543116I115J163D01*
G01X1400157Y1546399D01*
G03X1400081Y1546489I-3011J-2466D01*
G03X1400074Y1546497I-2932J-2559D01*
G03X1400058Y1546515I-2917J-2577D01*
G03X1398575Y1547544I-2900J-2596D01*
G01X1394421Y1549170D01*
G02X1394378Y1549194I75J185D01*
G01X1394027Y1549445D01*
G03X1393173Y1549909I-2287J-3192D01*
G01X1376640Y1556390D01*
X1376579Y1556458D01*
X1376573Y1556478D01*
G03X1374370Y1558153I-2203J-611D01*
G01X1374360D01*
X1374340Y1558154D01*
G02X1374158Y1558353I18J199D01*
G01Y1558801D01*
G02X1374179Y1558881I200J-10D01*
G02X1374208Y1558923I178J-92D01*
G01X1374236Y1558951D01*
X1374307Y1559020D01*
G02X1374431Y1559074I137J-145D01*
G01X1374436D01*
G03Y1562896I-66J1911D01*
G01X1374431D01*
G02X1374307Y1562950I13J199D01*
G01X1374236Y1563019D01*
X1374208Y1563047D01*
G02X1374179Y1563089I149J134D01*
G02X1374158Y1563169I179J90D01*
G01Y1563919D01*
G02X1374179Y1563999I200J-10D01*
G02X1374208Y1564041I178J-92D01*
G02X1374217Y1564050I146J-137D01*
G01X1374330Y1564162D01*
X1374358Y1564189D01*
X1374436Y1564192D01*
G03X1376282Y1566103I-66J1911D01*
G03X1374370Y1568015I-1912J0D01*
G01X1374368D01*
G03X1374365I-1J-1913D01*
G03X1374362I-1J-1913D01*
G03X1373897Y1567958I-1J-1913D01*
G01X1373852Y1567952D01*
X1373847D01*
G03X1373669Y1568377I-3705J-1302D01*
G01X1373650Y1568443D01*
G03X1372673Y1569685I-1492J-169D01*
G01X1372652Y1569694D01*
X1371139Y1571206D01*
G03X1369265Y1572252I-2778J-2775D01*
G01X1369137Y1572349D01*
G03X1365709Y1574360I-3428J-1916D01*
G01X1365708D01*
G03X1364065Y1573999I1J-3926D01*
G02X1364044Y1574004I36J197D01*
G03X1363496Y1574108I-549J-1397D01*
G03X1361994Y1572606I0J-1502D01*
G01Y1572604D01*
G03X1362102Y1572042I1503J-3D01*
G01X1362109Y1572007D01*
X1362110Y1572004D01*
G03X1361782Y1570434I3597J-1571D01*
G01Y1568930D01*
G03X1361913Y1567926I3927J2D01*
G01X1361920Y1567875D01*
X1361913Y1567824D01*
G03X1361834Y1567451I3797J-999D01*
G01X1361825Y1567401D01*
X1361771Y1567331D01*
G02X1361739Y1567303I-147J136D01*
G03X1361737Y1567301I139J-141D01*
G02X1361704Y1567282I-116J163D01*
G02X1361695Y1567278I-86J181D01*
G01X1361417Y1567167D01*
G02X1361352Y1567156I-65J189D01*
G01X1361344Y1567159D01*
X1361272Y1567213D01*
X1361270Y1567215D01*
G03X1360744Y1567555I-2388J-3117D01*
G02X1360655Y1567652I95J176D01*
G03X1357047Y1570030I-3608J-1548D01*
G03X1355403Y1569669I1J-3927D01*
G01X1355379Y1569675D01*
G03X1354834Y1569777I-544J-1400D01*
G01X1354832D01*
G03X1354548Y1569751I-6J-1503D01*
G01X1354523Y1569746D01*
X1354498Y1569744D01*
X1354492Y1569743D01*
G02X1354444Y1569749I1J200D01*
G01X1352986Y1571206D01*
G03X1352084Y1571880I-2777J-2776D01*
G02X1351996Y1571977I96J176D01*
G03X1348386Y1574360I-3610J-1543D01*
G01X1348383D01*
G03X1346802Y1574027I1J-3926D01*
G01X1346764Y1574010D01*
X1346707D01*
X1346703Y1574012D01*
X1346702D01*
G03X1346200Y1574108I-529J-1406D01*
G01X1346165D01*
G03X1344671Y1572606I8J-1502D01*
G01Y1572599D01*
G03X1344773Y1572060I1501J5D01*
G01X1344775Y1572055D01*
G02X1344783Y1572027I-188J-69D01*
G01X1344785Y1572013D01*
X1344787Y1572002D01*
G03X1344460Y1570434I3599J-1569D01*
G01Y1568927D01*
G03X1344590Y1567926I3926J1D01*
G01X1344597Y1567875D01*
X1344590Y1567824D01*
G03X1344508Y1567438I3795J-1008D01*
G01X1344494Y1567349D01*
X1344486Y1567339D01*
X1344467Y1567324D01*
G02X1344422Y1567299I-119J161D01*
G01X1344182Y1567201D01*
X1344180D01*
X1344098Y1567168D01*
G02X1344010Y1567156I-70J187D01*
G01X1343941Y1567207D01*
G03X1343436Y1567524I-2334J-3157D01*
G01X1343345Y1567624D01*
G03X1339725Y1570030I-3620J-1520D01*
G03X1338171Y1569708I3J-3926D01*
G01X1338169D01*
X1338078Y1569669D01*
G02X1338061Y1569673I37J197D01*
G03X1338046Y1569679I-565J-1391D01*
G01X1337976Y1569724D01*
X1336493Y1571206D01*
G03X1334619Y1572252I-2778J-2775D01*
G01X1334491Y1572349D01*
G03X1331063Y1574360I-3428J-1916D01*
G01X1331062D01*
G03X1329419Y1573999I1J-3926D01*
G02X1329398Y1574004I36J197D01*
G03X1328850Y1574108I-549J-1397D01*
G03X1327348Y1572606I0J-1502D01*
G01Y1572604D01*
G03X1327456Y1572042I1503J-3D01*
G01X1327463Y1572007D01*
X1327464Y1572004D01*
G03X1327136Y1570434I3597J-1571D01*
G01Y1568930D01*
G03X1327267Y1567926I3927J2D01*
G01X1327274Y1567875D01*
X1327267Y1567824D01*
G03X1327253Y1567769I3798J-996D01*
G02X1327142Y1567635I-194J48D01*
G01X1327030Y1567585D01*
G02X1326947Y1567567I-83J182D01*
G01X1326855Y1567589D01*
G03X1325958Y1567921I-1801J-3489D01*
G01X1325830Y1568018D01*
G03X1322402Y1570030I-3428J-1914D01*
G03X1320848Y1569708I3J-3926D01*
G01X1320846D01*
X1320755Y1569669D01*
G02X1320738Y1569673I37J197D01*
G03X1320723Y1569679I-565J-1391D01*
G01X1320653Y1569724D01*
X1319170Y1571206D01*
G03X1317296Y1572252I-2778J-2775D01*
G01X1317168Y1572349D01*
G03X1313740Y1574360I-3428J-1916D01*
G01X1313737D01*
G03X1312156Y1574027I1J-3926D01*
G01X1312118Y1574010D01*
X1312061D01*
X1312057Y1574012D01*
X1312056D01*
G03X1311554Y1574108I-529J-1406D01*
G01X1311519D01*
G03X1310025Y1572606I8J-1502D01*
G01Y1572599D01*
G03X1310127Y1572060I1501J5D01*
G01X1310129Y1572055D01*
G02X1310137Y1572027I-188J-69D01*
G01X1310139Y1572013D01*
X1310141Y1572002D01*
G03X1309814Y1570434I3599J-1569D01*
G01Y1568927D01*
G03X1309944Y1567926I3926J1D01*
G01X1309951Y1567875D01*
X1309944Y1567824D01*
G03X1309862Y1567438I3795J-1008D01*
G01X1309848Y1567349D01*
X1309840Y1567339D01*
X1309821Y1567324D01*
G02X1309776Y1567299I-119J161D01*
G01X1309536Y1567201D01*
X1309534D01*
X1309447Y1567166D01*
G02X1309380Y1567155I-65J189D01*
G01X1309303Y1567214D01*
G03X1308776Y1567555I-2390J-3115D01*
G02X1308687Y1567652I95J176D01*
G03X1305079Y1570030I-3608J-1548D01*
G03X1303435Y1569669I1J-3927D01*
G01X1303411Y1569675D01*
G03X1302868Y1569777I-544J-1400D01*
G01X1302866D01*
G03X1301364Y1568285I0J-1502D01*
G01Y1568274D01*
G03X1301467Y1567728I1502J1D01*
G03X1301473Y1567713I1398J550D01*
G02X1301475Y1567705I-194J-53D01*
G01X1301480Y1567674D01*
G03X1301152Y1566103I3599J-1571D01*
G01Y1564599D01*
G03X1301283Y1563595I3927J2D01*
G01X1301290Y1563544D01*
X1301283Y1563493D01*
G03X1301152Y1562489I3796J-1006D01*
G01Y1560985D01*
G03X1301481Y1559413I3927J1D01*
G02X1301480Y1559408I-197J37D01*
G01X1301473Y1559376D01*
X1301467Y1559360D01*
X1301466Y1559358D01*
G03X1301364Y1558818I1400J-544D01*
G01Y1558803D01*
G03X1302859Y1557311I1502J10D01*
G01X1302871D01*
G03X1302920Y1557312I-6J1502D01*
G01X1302927D01*
G02X1302953Y1557310I-2J-200D01*
G01X1303005Y1557296D01*
G02X1303127Y1557112I-78J-184D01*
G01X1303107Y1557037D01*
G02X1303091Y1556997I-193J54D01*
G01X1303087Y1556990D01*
G03X1303076Y1556970I1997J-1112D01*
G01X1303074Y1556966D01*
X1303070Y1556959D01*
G03X1303058Y1556936I2020J-1069D01*
G02X1303056Y1556932I-180J87D01*
G03X1303050Y1556921I2004J-1100D01*
G01X1303049Y1556919D01*
G03X1302809Y1556136I2030J-1051D01*
G03X1302793Y1555882I2270J-270D01*
G01Y1555852D01*
G03X1305079Y1553581I2286J15D01*
G01X1305141D01*
G03X1305856Y1553716I-61J2286D01*
G01X1305861Y1553718D01*
X1305873Y1553722D01*
X1305929Y1553733D01*
X1305937Y1553734D01*
X1305939D01*
G02X1306079Y1553677I0J-200D01*
G01X1311696Y1548059D01*
X1311854Y1547901D01*
X1311864Y1547887D01*
X1311867Y1547883D01*
G03X1312071Y1547611I3212J2197D01*
G01X1313151Y1546296D01*
G03X1314488Y1545250I3009J2468D01*
G01X1314519Y1545236D01*
X1314749Y1545006D01*
X1314757Y1544996D01*
G03X1315093Y1544614I3110J2397D01*
G01X1319366Y1540341D01*
G03X1320450Y1539574I2777J2775D01*
G01X1320822Y1539396D01*
X1320859Y1539367D01*
X1320873Y1539348D01*
G03X1321589Y1538640I3072J2390D01*
G03X1321610Y1538624I2369J3088D01*
G01X1321636Y1538604D01*
G03X1321652Y1538592I128J154D01*
G01X1321689Y1538567D01*
X1321691Y1538565D01*
G03X1322292Y1538214I2255J3171D01*
G01X1323868Y1537474D01*
G03X1325199Y1537119I1653J3523D01*
G01X1325200D01*
X1325246Y1537099D01*
X1325317Y1537068D01*
G03X1325322Y1537063I2750J2745D01*
G01X1325336Y1537051D01*
X1325347Y1537040D01*
G03X1325350Y1537037I2750J2747D01*
G01X1325356Y1537032D01*
G03X1325358Y1537030I142J140D01*
G03X1326268Y1536435I2564J2928D01*
G01X1327843Y1535693D01*
G03X1329309Y1535327I1657J3520D01*
G01X1329386Y1535307D01*
X1363378Y1519078D01*
X1363437Y1518997D01*
X1363442Y1518960D01*
G03X1365709Y1516966I2267J292D01*
G01X1365744D01*
G03X1366136Y1517006I-35J2286D01*
G01X1366138Y1517000D01*
X1366268Y1517035D01*
X1366272Y1517036D01*
G03X1366917Y1517310I-561J2217D01*
G01X1366919Y1517312D01*
X1366940Y1517324D01*
X1367040Y1517329D01*
X1372023Y1514951D01*
X1372084Y1514859D01*
X1372085Y1514841D01*
G03X1372896Y1513173I2285J80D01*
G03X1373708Y1512733I1473J1749D01*
G01X1373768Y1512715D01*
G02X1373848Y1512650I-82J-183D01*
G01X1373865Y1511695D01*
G02X1373861Y1511689I-169J108D01*
G01X1373843Y1511664D01*
X1373821Y1511648D01*
G02X1373771Y1511621I-119J161D01*
G01X1373731Y1511607D01*
G03X1372458Y1509804I640J-1803D01*
G03X1373625Y1508043I1912J0D01*
G03X1373798Y1507979I749J1759D01*
G01X1373851Y1507962D01*
G02X1373933Y1507899I-77J-185D01*
G01X1373935Y1507897D01*
X1373959Y1506605D01*
G02X1373953Y1506596I-170J107D01*
G01X1373933Y1506570D01*
X1373906Y1506552D01*
G02X1373853Y1506526I-114J165D01*
G01X1373816Y1506515D01*
G03X1372458Y1504685I554J-1830D01*
G03X1373897Y1502832I1913J0D01*
G01X1373933Y1502823D01*
G02X1374024Y1502759I-65J-189D01*
G01X1374030Y1502752D01*
X1374046Y1501894D01*
G02X1373934Y1501812I-167J110D01*
G01X1373910Y1501807D01*
G03X1373969Y1497316I459J-2240D01*
G01X1374026Y1497306D01*
G02X1374131Y1497230I-59J-191D01*
G01X1374147Y1496415D01*
G02X1374134Y1496397I-169J108D01*
G01X1374112Y1496371D01*
X1374056Y1496337D01*
X1374009Y1496327D01*
G03X1372464Y1494606I361J-1878D01*
G01X1372462Y1494583D01*
G03X1372457Y1494449I1908J-138D01*
G03X1373622Y1492689I1912J0D01*
G03X1374084Y1492558I749J1760D01*
G01X1374101Y1492555D01*
G02X1374206Y1492492I-45J-195D01*
G01X1374219Y1492478D01*
X1374241Y1491313D01*
G02X1374117Y1491227I-168J109D01*
G01X1374091Y1491223D01*
G03X1372464Y1489481I279J-1892D01*
G01X1372463Y1489472D01*
X1372462Y1489466D01*
G03X1372458Y1489332I1908J-124D01*
G01Y1489330D01*
G03X1374140Y1487432I1913J1D01*
G01X1374183Y1487427D01*
X1374189Y1487426D01*
G02X1374298Y1487365I-38J-196D01*
G01X1374313Y1487349D01*
X1374411Y1482027D01*
G02X1374354Y1481883I-200J-4D01*
G01X1374306Y1481834D01*
G02X1374247Y1481825I-59J191D01*
G01X1373681D01*
G02X1373576Y1481855I0J200D01*
G01X1373552Y1481870D01*
X1373515Y1481910D01*
X1373502Y1481936D01*
G03X1372691Y1482672I-1345J-668D01*
G01X1372651Y1482687D01*
X1371139Y1484198D01*
G03X1369265Y1485244I-2778J-2775D01*
G01X1369137Y1485341D01*
G03X1365709Y1487352I-3428J-1916D01*
G01X1365708D01*
G03X1364065Y1486991I1J-3926D01*
G02X1364044Y1486996I36J197D01*
G03X1363496Y1487100I-549J-1397D01*
G03X1362469Y1486694I0J-1502D01*
G02X1362390Y1486648I-137J145D01*
G01X1362369Y1486642D01*
X1362278Y1486617D01*
G02X1362224Y1486612I-45J195D01*
G01X1362214Y1486613D01*
G03X1361994Y1486414I-20J-199D01*
G01Y1485597D01*
G03X1362093Y1485061I1502J0D01*
G01X1362095Y1485056D01*
G03X1362097Y1485051I1396J555D01*
G01X1362100Y1485042D01*
X1362106Y1485010D01*
G02X1362109Y1484993I-195J-43D01*
G03X1361783Y1483444I3600J-1567D01*
G01X1361782Y1483331D01*
G02X1361618Y1483245I-164J114D01*
G01X1354853D01*
G02X1354711Y1483304I0J200D01*
G01X1353816Y1484198D01*
G03X1351942Y1485244I-2778J-2775D01*
G01X1351814Y1485341D01*
G03X1348386Y1487352I-3428J-1916D01*
G01X1348383D01*
G03X1346802Y1487019I1J-3926D01*
G01X1346764Y1487002D01*
X1346707D01*
X1346703Y1487004D01*
X1346702D01*
G03X1346571Y1487047I-534J-1404D01*
G01X1346570D01*
G03X1346200Y1487100I-396J-1449D01*
G01X1346165D01*
G03X1344671Y1485610I8J-1502D01*
G01Y1485566D01*
G03X1344773Y1485053I1502J32D01*
G01Y1485051D01*
G02X1344762Y1484936I-196J-39D01*
G03X1344460Y1483489I3624J-1511D01*
G01X1344458Y1483378D01*
G02X1344303Y1483292I-164J114D01*
G01X1337483D01*
G02X1337341Y1483351I0J200D01*
G01X1336493Y1484198D01*
G03X1334619Y1485244I-2778J-2775D01*
G01X1334491Y1485341D01*
G03X1331063Y1487352I-3428J-1916D01*
G01X1331062D01*
G03X1329419Y1486991I1J-3926D01*
G02X1329398Y1486996I36J197D01*
G03X1328850Y1487100I-549J-1397D01*
G03X1327823Y1486694I0J-1502D01*
G02X1327744Y1486648I-137J145D01*
G01X1327723Y1486642D01*
X1327632Y1486617D01*
G02X1327578Y1486612I-45J195D01*
G01X1327568Y1486613D01*
G03X1327348Y1486414I-20J-199D01*
G01Y1485597D01*
G03X1327447Y1485061I1502J0D01*
G01X1327449Y1485056D01*
G03X1327451Y1485051I1396J555D01*
G01X1327454Y1485042D01*
X1327460Y1485010D01*
G02X1327463Y1484993I-195J-43D01*
G03X1327136Y1483426I3600J-1569D01*
G01Y1483299D01*
G02X1326972Y1483213I-164J113D01*
G01X1320239D01*
G02X1320097Y1483272I0J200D01*
G01X1319170Y1484198D01*
G03X1317296Y1485244I-2778J-2775D01*
G01X1317168Y1485341D01*
G03X1313740Y1487352I-3428J-1916D01*
G01X1313737D01*
G03X1312156Y1487019I1J-3926D01*
G01X1312118Y1487002D01*
X1312061D01*
X1312057Y1487004D01*
X1312056D01*
G03X1311925Y1487047I-534J-1404D01*
G01X1311924D01*
G03X1311554Y1487100I-396J-1449D01*
G01X1311519D01*
G03X1310025Y1485610I8J-1502D01*
G01Y1485566D01*
G03X1310127Y1485053I1502J32D01*
G01Y1485051D01*
G02X1310131Y1485013I-196J-40D01*
G01X1310115Y1484936D01*
G03X1309828Y1483768I3625J-1510D01*
G01X1309818Y1483655D01*
X1309799Y1483638D01*
G02X1309664Y1483585I-136J147D01*
G01X1301844D01*
G03X1301702Y1483526I0J-200D01*
G01X1300666Y1482490D01*
G03X1300607Y1482348I141J-142D01*
G01Y1453585D01*
G02X1300585Y1453494I-200J0D01*
G02X1300549Y1453444I-178J90D01*
G01X1298029Y1450924D01*
G02X1297959Y1450879I-141J142D01*
G01X1292904Y1448944D01*
X1292862Y1448946D01*
G03X1292668Y1448950I-178J-3922D01*
G03X1291264Y1448691I-2J-3926D01*
G01X1289441Y1447993D01*
G03X1288339Y1447349I1404J-3667D01*
G01X1288219Y1447303D01*
G03X1286966Y1447046I152J-3924D01*
G01X1285144Y1446348D01*
G03X1284043Y1445704I1406J-3666D01*
G01X1283923Y1445658D01*
G03X1282669Y1445401I151J-3924D01*
G01X1280847Y1444703D01*
G03X1279746Y1444059I1406J-3666D01*
G01X1279626Y1444013D01*
G03X1278372Y1443756I151J-3924D01*
G01X1276550Y1443058D01*
G03X1275449Y1442414I1406J-3666D01*
G01X1275329Y1442368D01*
G03X1274075Y1442111I151J-3924D01*
G01X1272253Y1441413D01*
G03X1270898Y1440539I1406J-3667D01*
G01X1270883Y1440524D01*
X1270848Y1440501D01*
X1238427Y1428091D01*
G03X1237030Y1427175I1405J-3666D01*
G01X1233770Y1423856D01*
G02X1233751Y1423839I-143J140D01*
G01X1233206Y1423407D01*
G03X1232700Y1422926I2417J-3050D01*
G01X1231383Y1421426D01*
G02X1231375Y1421418I-145J137D01*
G01X1230648Y1420677D01*
G03X1230217Y1420156I2799J-2754D01*
G01X1230042Y1419902D01*
G02X1230027Y1419883I-164J114D01*
G01X1228037Y1417617D01*
G03X1227626Y1417055I2923J-2569D01*
G01X1224549Y1411939D01*
G02X1224542Y1411929I-167J109D01*
G01X1181446Y1349459D01*
X1181432Y1349449D01*
G03X1181367Y1349431I315J-1264D01*
G01X1181251Y1349496D01*
G03X1180513Y1349690I-739J-1309D01*
G01X1176112D01*
G03X1175336Y1349474I0J-1503D01*
G01X1175232Y1349445D01*
X1175184Y1349451D01*
G03X1174873Y1349489I-312J-1264D01*
G03Y1346885I0J-1302D01*
G03X1175184Y1346923I-1J1302D01*
G01X1175232Y1346929D01*
X1175336Y1346900D01*
G03X1176112Y1346684I776J1287D01*
G01X1178386D01*
G02X1178561Y1346579I-1J-200D01*
G01X1178569Y1346559D01*
G02X1178581Y1346443I-184J-78D01*
G01X1178576Y1346417D01*
X1178548Y1346365D01*
X1177996Y1345813D01*
G02X1177979Y1345798I-141J142D01*
G01X1124294Y1303374D01*
G03X1123965Y1303083I2433J-3082D01*
G01X1115626Y1294823D01*
G03X1115125Y1294216I2763J-2790D01*
G01X1112412Y1290159D01*
G03X1112048Y1289479I3263J-2184D01*
G01X1109301Y1282847D01*
G03X1109002Y1281344I3628J-1503D01*
G01Y1259509D01*
G03X1109268Y1258090I3926J1D01*
G01X1109282Y1258018D01*
Y1248595D01*
G02X1109172Y1248417I-200J1D01*
G01X1108852Y1248256D01*
G02X1108643Y1248275I-89J179D01*
G03X1107875Y1248530I-769J-1032D01*
G01X1107873D01*
G03Y1245956I0J-1287D01*
G01X1107875D01*
G03X1108643Y1246211I-1J1287D01*
G02X1108852Y1246230I120J-160D01*
G01X1109172Y1246069D01*
G02X1109282Y1245891I-90J-179D01*
G01Y1245886D01*
G03X1110299Y1243288I3827J0D01*
G01X1110347Y1243199D01*
G03X1110789Y1242495I1266J304D01*
G01X1110863Y1242340D01*
Y1240926D01*
X1110789Y1240771D01*
G03X1110311Y1239763I824J-1008D01*
G03X1110491Y1239104I1302J1D01*
G01X1110390Y1239003D01*
G03X1110018Y1238102I909J-902D01*
G01Y1237620D01*
G03X1110087Y1237207I1281J2D01*
G01X1110098Y1237142D01*
Y1234904D01*
X1110087Y1234839D01*
G03X1110018Y1234426I1212J-415D01*
G01Y1233880D01*
G03X1110087Y1233467I1281J2D01*
G01X1110098Y1233402D01*
Y1231798D01*
X1110094Y1231794D01*
Y1231152D01*
G02X1110084Y1231088I-200J-2D01*
G03X1110018Y1230686I1214J-406D01*
G01Y1230140D01*
G03X1110084Y1229738I1280J4D01*
G02X1110094Y1229674I-190J-62D01*
G01Y1227412D01*
G02X1110084Y1227348I-200J-2D01*
G03X1110018Y1226946I1214J-406D01*
G01Y1226400D01*
G03X1110084Y1225998I1280J4D01*
G02X1110094Y1225934I-190J-62D01*
G01Y1223672D01*
G02X1110084Y1223608I-200J-2D01*
G03X1110018Y1223206I1214J-406D01*
G01Y1222659D01*
G03X1110084Y1222257I1280J4D01*
G02X1110094Y1222193I-190J-62D01*
G01Y1220754D01*
G02X1110041Y1220654I-196J40D01*
G01X1109846Y1220454D01*
G02X1109783Y1220410I-144J139D01*
G01X1109748Y1220395D01*
X1109709Y1220394D01*
G03Y1217990I34J-1202D01*
G01X1109748Y1217989D01*
X1109783Y1217974D01*
G02X1109846Y1217930I-81J-183D01*
G01X1110041Y1217730D01*
G02X1110094Y1217630I-143J-140D01*
G01Y1217014D01*
G02X1110041Y1216914I-196J40D01*
G01X1109846Y1216714D01*
G02X1109783Y1216670I-144J139D01*
G01X1109748Y1216655D01*
X1109709Y1216654D01*
G03Y1214250I34J-1202D01*
G01X1109748Y1214249D01*
X1109783Y1214234D01*
G02X1109842Y1214194I-81J-183D01*
G02X1109846Y1214190I-139J-143D01*
G01X1109901Y1214133D01*
X1109961Y1214071D01*
G02X1110018Y1213932I-143J-140D01*
G01Y1200723D01*
G03X1110033Y1200648I200J1D01*
G01X1110198Y1200242D01*
G03X1110244Y1200174I185J76D01*
G01X1110400Y1200023D01*
G02X1110402Y1200021I-140J-142D01*
G01X1110804Y1199619D01*
G02X1110863Y1199477I-141J-142D01*
G01Y1199337D01*
G03X1110922Y1199195I200J0D01*
G01X1112392Y1197725D01*
G03X1112534Y1197666I142J141D01*
G01X1112674D01*
G02X1112816Y1197607I0J-200D01*
G01X1112920Y1197503D01*
G03X1113826Y1197126I907J904D01*
G01X1144991D01*
G02X1145133Y1197067I0J-200D01*
G01X1145341Y1196859D01*
G02X1145400Y1196717I-141J-142D01*
G01Y1194712D01*
G02X1145200Y1194512I-200J0D01*
G01X1143405D01*
G03Y1191510I0J-1501D01*
G01X1144528D01*
G02X1144670Y1191451I0J-200D01*
G01X1144945Y1191176D01*
G02X1145004Y1191034I-141J-142D01*
G01Y1186594D01*
G02X1144875Y1186407I-200J0D01*
G01X1144525Y1186274D01*
G02X1144304Y1186329I-71J187D01*
G03X1143405Y1186733I-899J-798D01*
G03Y1184329I0J-1202D01*
G03X1144304Y1184733I0J1202D01*
G02X1144525Y1184788I150J-132D01*
G01X1144875Y1184655D01*
G02X1145004Y1184468I-71J-187D01*
G01Y1179114D01*
G02X1144875Y1178927I-200J0D01*
G01X1144525Y1178794D01*
G02X1144304Y1178849I-71J187D01*
G03X1143405Y1179253I-899J-798D01*
G03Y1176849I0J-1202D01*
G03X1144304Y1177253I0J1202D01*
G02X1144525Y1177308I150J-132D01*
G01X1144875Y1177175D01*
G02X1145004Y1176988I-71J-187D01*
G01Y1171633D01*
G02X1144875Y1171446I-200J0D01*
G01X1144525Y1171313D01*
G02X1144304Y1171368I-71J187D01*
G03X1143405Y1171772I-899J-798D01*
G03Y1169368I0J-1202D01*
G03X1144304Y1169772I0J1202D01*
G02X1144525Y1169827I150J-132D01*
G01X1144875Y1169694D01*
G02X1145004Y1169507I-71J-187D01*
G01Y1168027D01*
G02X1144945Y1167885I-200J0D01*
G01X1143345Y1166285D01*
G02X1143203Y1166226I-142J141D01*
G01X1141255D01*
G02X1141104Y1166294I-1J200D01*
G01X1140876Y1166553D01*
X1140852Y1166634D01*
X1140857Y1166677D01*
G03X1140867Y1166830I-1192J155D01*
G03X1138463I-1202J0D01*
G03X1138473Y1166678I1202J3D01*
G01Y1166676D01*
X1138478Y1166634D01*
X1138454Y1166553D01*
X1138226Y1166294D01*
G02X1138075Y1166226I-150J132D01*
G01X1133774D01*
G02X1133623Y1166294I-1J200D01*
G01X1133395Y1166553D01*
X1133371Y1166634D01*
X1133376Y1166677D01*
G03X1133386Y1166830I-1192J155D01*
G03X1130982I-1202J0D01*
G03X1130992Y1166678I1202J3D01*
G01Y1166676D01*
X1130997Y1166634D01*
X1130973Y1166553D01*
X1130745Y1166294D01*
G02X1130594Y1166226I-150J132D01*
G01X1126294D01*
G02X1126143Y1166294I-1J200D01*
G01X1125915Y1166553D01*
X1125891Y1166634D01*
X1125896Y1166677D01*
G03X1125906Y1166830I-1192J155D01*
G03X1123502I-1202J0D01*
G03X1123512Y1166678I1202J3D01*
G01Y1166676D01*
X1123517Y1166634D01*
X1123493Y1166553D01*
X1123265Y1166294D01*
G02X1123114Y1166226I-150J132D01*
G01X1118814D01*
G02X1118663Y1166294I-1J200D01*
G01X1118435Y1166553D01*
X1118411Y1166634D01*
X1118416Y1166677D01*
G03X1118426Y1166830I-1192J155D01*
G03X1116022I-1202J0D01*
G03X1116032Y1166678I1202J3D01*
G01Y1166676D01*
X1116037Y1166634D01*
X1116013Y1166553D01*
X1115785Y1166294D01*
G02X1115634Y1166226I-150J132D01*
G01X1111333D01*
G02X1111182Y1166294I-1J200D01*
G01X1110954Y1166553D01*
X1110930Y1166634D01*
X1110935Y1166677D01*
G03X1110945Y1166830I-1192J155D01*
G03X1108541I-1202J0D01*
G03X1108551Y1166678I1202J3D01*
G01Y1166676D01*
X1108556Y1166634D01*
X1108532Y1166553D01*
X1108304Y1166294D01*
G02X1108153Y1166226I-150J132D01*
G01X1103853D01*
G02X1103702Y1166294I-1J200D01*
G01X1103474Y1166553D01*
X1103450Y1166634D01*
X1103455Y1166677D01*
G03X1103465Y1166830I-1192J155D01*
G03X1101061I-1202J0D01*
G03X1101071Y1166678I1202J3D01*
G01Y1166676D01*
X1101076Y1166634D01*
X1101052Y1166553D01*
X1100824Y1166294D01*
G02X1100673Y1166226I-150J132D01*
G01X1092633D01*
G02X1092482Y1166294I-1J200D01*
G01X1092254Y1166553D01*
X1092230Y1166634D01*
X1092235Y1166677D01*
G03X1092245Y1166830I-1192J155D01*
G03X1089841I-1202J0D01*
G03X1089851Y1166678I1202J3D01*
G01Y1166676D01*
X1089856Y1166634D01*
X1089832Y1166553D01*
X1089604Y1166294D01*
G02X1089453Y1166226I-150J132D01*
G01X1053472D01*
G03X1052412Y1165787I1J-1501D01*
G01X1050701Y1164075D01*
G02X1050559Y1164016I-142J141D01*
G01X1040876D01*
G02X1040711Y1164103I0J200D01*
G01X1040524Y1164374D01*
G02X1040502Y1164558I165J113D01*
G03X1040600Y1165091I-1404J534D01*
G03X1040003Y1166289I-1502J-1D01*
G01X1039966Y1166317D01*
X1039924Y1166399D01*
X1039919Y1166808D01*
X1039958Y1166891D01*
X1039994Y1166920D01*
G03X1040555Y1168091I-942J1171D01*
G03X1037551I-1502J0D01*
G03X1038148Y1166893I1502J1D01*
G01X1038185Y1166865D01*
X1038227Y1166783D01*
X1038232Y1166374D01*
X1038193Y1166291D01*
X1038157Y1166262D01*
G03X1037596Y1165091I942J-1171D01*
G03X1037694Y1164558I1502J1D01*
G01X1037712Y1164511D01*
X1037700Y1164415D01*
X1037485Y1164103D01*
G02X1037320Y1164016I-165J113D01*
G01X1037088D01*
G02X1036946Y1164075I0J200D01*
G01X1035553Y1165468D01*
G02X1035494Y1165610I141J142D01*
G01Y1182432D01*
G03X1035055Y1183492I-1501J-1D01*
G01X1003836Y1214711D01*
G03X1002776Y1215150I-1061J-1062D01*
G01X980508D01*
G02X980366Y1215209I0J200D01*
G01X979716Y1215859D01*
G02X979712Y1215863I139J143D01*
G03X978614Y1216340I-1098J-1025D01*
G03X977112Y1214838I0J-1502D01*
G03X977589Y1213740I1502J0D01*
G01X977591Y1213737D01*
X978484Y1212844D01*
G02Y1212562I-142J-141D01*
G01X977582Y1211659D01*
G02X977578Y1211655I-143J139D01*
G03X977112Y1210568I1035J-1087D01*
G03X978614Y1209066I1502J0D01*
G03X978704Y1209069I-5J1502D01*
G01X979193D01*
G03X979335Y1209128I0J200D01*
G01X980459Y1210251D01*
G02X980601Y1210310I142J-141D01*
G01X1001304D01*
G02X1001446Y1210251I0J-200D01*
G01X1024904Y1186793D01*
Y1186789D01*
X1030572Y1181121D01*
G02X1030631Y1180979I-141J-142D01*
G01Y1180884D01*
G03X1030690Y1180742I200J0D01*
G01X1030692Y1180740D01*
Y1163900D01*
G02X1030633Y1163758I-200J0D01*
G01X1030035Y1163160D01*
G02X1029893Y1163101I-142J141D01*
G01X978756D01*
G03X978556Y1162901I0J-200D01*
G01Y1109639D01*
G02X978534Y1109548I-200J0D01*
G02X978498Y1109498I-178J90D01*
G01X977558Y1108558D01*
G02X977508Y1108522I-140J142D01*
G02X977417Y1108500I-91J178D01*
G01X924083D01*
G02X923941Y1108559I0J200D01*
G01X921665Y1110835D01*
G02X921606Y1110977I141J142D01*
G01Y1265968D01*
G02X921665Y1266110I200J0D01*
G01X922832Y1267277D01*
G02X922974Y1267336I142J-141D01*
G01X942024D01*
G03X943654Y1268011I0J2306D01*
G01X949890Y1274247D01*
G03X950566Y1275878I-1631J1632D01*
G01Y1293857D01*
G02X950689Y1294041I200J-1D01*
G01X950745Y1294064D01*
X950863Y1294041D01*
X990387Y1254517D01*
G02X990446Y1254375I-141J-142D01*
G01Y1242015D01*
G03X991113Y1240405I2277J0D01*
G01X1024438Y1207081D01*
X1024469Y1207009D01*
Y1206970D01*
G03X1025135Y1205393I2276J32D01*
G01X1026197Y1204331D01*
G03X1027615Y1203673I1609J1610D01*
G02X1027797Y1203491I-17J-199D01*
G03X1028455Y1202073I2268J191D01*
G01X1029517Y1201011D01*
G03X1031094Y1200345I1609J1610D01*
G01X1031133D01*
X1031205Y1200314D01*
X1032124Y1199395D01*
X1032155Y1199323D01*
Y1199284D01*
G03X1032821Y1197707I2276J32D01*
G01X1033883Y1196645D01*
G03X1035460Y1195979I1609J1610D01*
G01X1035499D01*
X1035571Y1195948D01*
X1050906Y1180612D01*
G03X1051998Y1180005I1610J1610D01*
G02X1052094Y1179952I-45J-195D01*
G01X1053551Y1178495D01*
G02X1053606Y1178313I-141J-142D01*
G03X1053579Y1178051I1275J-264D01*
G01Y1178050D01*
G03X1054881Y1176748I1302J0D01*
G03X1055948Y1177304I0J1302D01*
G01X1056112Y1177390D01*
X1056150D01*
G02X1056313Y1177305I-1J-200D01*
G03X1057380Y1176748I1068J745D01*
G01X1061120D01*
G03X1062149Y1177252I0J1302D01*
G01X1062163Y1177270D01*
X1062196Y1177297D01*
X1062294Y1177348D01*
G02X1062386Y1177370I91J-178D01*
G01X1063596D01*
G02X1063687Y1177348I0J-200D01*
G01X1063722Y1177330D01*
X1063768Y1177306D01*
G02X1063831Y1177253I-95J-176D01*
G01X1063832Y1177252D01*
Y1177251D01*
G03X1065890I1029J801D01*
G01Y1177252D01*
X1065891Y1177253D01*
G02X1065954Y1177306I158J-123D01*
G01X1065999Y1177329D01*
G02X1066001Y1177331I136J-134D01*
G01X1066035Y1177348D01*
G02X1066126Y1177370I91J-178D01*
G01X1066396D01*
G02X1066581Y1177245I0J-200D01*
G01Y1177244D01*
G03X1066817Y1176806I2021J807D01*
G03X1066901Y1176693I1788J1241D01*
G01X1066927Y1176660D01*
X1066958Y1176624D01*
G03X1068602Y1175874I1644J1427D01*
G01X1069751D01*
G03X1070441Y1175987I-2J2177D01*
G01X1070518Y1176013D01*
X1070663Y1175944D01*
X1070665Y1175940D01*
G03X1071193Y1175874I532J2111D01*
G01X1072342D01*
G03X1074227Y1176963I0J2176D01*
G03X1074518Y1178049I-1885J1087D01*
G01Y1178051D01*
G03X1072896Y1180156I-2177J0D01*
G01X1072837Y1180171D01*
X1072770Y1180225D01*
X1072751Y1180262D01*
G03X1072425Y1180706I-1903J-1056D01*
G03X1072386Y1180746I-1578J-1499D01*
G01X1071277Y1181855D01*
G03X1069738Y1182492I-1538J-1539D01*
G01X1069699D01*
G03X1067573Y1182591I-1098J-701D01*
G01Y1182590D01*
X1067572Y1182589D01*
G02X1067509Y1182536I-158J123D01*
G01X1067470Y1182516D01*
G02X1067376Y1182492I-95J176D01*
G01X1066087D01*
G02X1065993Y1182516I1J200D01*
G01X1065954Y1182536D01*
G02X1065891Y1182589I95J176D01*
G01X1065890Y1182590D01*
Y1182591D01*
G03X1063832I-1029J-801D01*
G01Y1182590D01*
X1063831Y1182589D01*
G02X1063768Y1182536I-158J123D01*
G01X1063729Y1182516D01*
G02X1063635Y1182492I-95J176D01*
G01X1062346D01*
G02X1062252Y1182516I1J200D01*
G01X1062213Y1182536D01*
G02X1062150Y1182589I95J176D01*
G01X1062149Y1182590D01*
Y1182591D01*
G03X1061227Y1183089I-1028J-801D01*
G03X1061120Y1183093I-102J-1298D01*
G03X1060078Y1182572I0J-1302D01*
G01X1059918Y1182492D01*
X1056854D01*
G02X1056712Y1182551I0J200D01*
G01X1056228Y1183035D01*
G02X1056224Y1183039I139J143D01*
G03X1056172Y1183093I-1594J-1482D01*
G01X1055707Y1183558D01*
G02X1055654Y1183654I142J141D01*
G03X1055046Y1184751I-2218J-512D01*
G01X1033667Y1206129D01*
G02X1033609Y1206286I141J141D01*
G01X1033636Y1206633D01*
X1033679Y1206709D01*
X1033715Y1206735D01*
G03X1034333Y1207950I-885J1215D01*
G03X1032831Y1209452I-1502J0D01*
G03X1031616Y1208834I0J-1503D01*
G01X1031590Y1208798D01*
X1031514Y1208755D01*
X1031167Y1208728D01*
G02X1031010Y1208786I-16J199D01*
G01X1027162Y1212634D01*
G02X1027104Y1212784I142J141D01*
G01X1027117Y1213079D01*
G02X1027187Y1213222I200J-9D01*
G01X1027188Y1213223D01*
G03X1027723Y1214372I-966J1149D01*
G03X1026221Y1215874I-1502J0D01*
G03X1025072Y1215339I0J-1501D01*
G01X1025071Y1215338D01*
G02X1024928Y1215268I-152J130D01*
G01X1024633Y1215255D01*
G02X1024483Y1215313I-9J200D01*
G01X1023142Y1216654D01*
G02X1023084Y1216787I142J141D01*
G01X1023072Y1217097D01*
X1023096Y1217168D01*
X1023120Y1217196D01*
G03X1023478Y1218169I-1143J973D01*
G03X1021976Y1219671I-1502J0D01*
G03X1021003Y1219313I0J-1501D01*
G01X1020975Y1219289D01*
X1020904Y1219265D01*
X1020594Y1219277D01*
G02X1020461Y1219335I8J200D01*
G01X996359Y1243438D01*
G02X996300Y1243580I141J142D01*
G01Y1255940D01*
G03X995633Y1257550I-2277J0D01*
G01X956153Y1297030D01*
G02X956094Y1297172I141J142D01*
G01Y1305456D01*
G03X955427Y1307066I-2277J0D01*
G01X944645Y1317848D01*
G02X944593Y1318040I142J141D01*
G01X944681Y1318374D01*
X944821Y1318516D01*
G03X946514Y1320739I-613J2223D01*
G01Y1322357D01*
G02X946583Y1322509I200J1D01*
G01X946812Y1322706D01*
G02X946971Y1322753I131J-151D01*
G01X946972D01*
G03X947308Y1322728I339J2282D01*
G03X949614Y1325033I0J2306D01*
G01Y1326344D01*
G03X948939Y1327974I-2306J0D01*
G01X937482Y1339431D01*
G03X935852Y1340106I-1630J-1631D01*
G01X921695D01*
G02X921510Y1340230I0J200D01*
G01X921486Y1340286D01*
X921510Y1340404D01*
X930828Y1349723D01*
G02X930970Y1349782I142J-141D01*
G01X1039690D01*
G03X1040612Y1350164I-1J1306D01*
G01X1050525Y1360077D01*
G03X1050908Y1361001I-923J924D01*
G01Y1376933D01*
G02X1051108Y1377133I200J0D01*
G01X1051802D01*
G03X1052002Y1377333I0J200D01*
G01Y1398401D01*
G02X1052061Y1398543I200J0D01*
G01X1057337Y1403818D01*
Y1403819D01*
X1078535Y1425017D01*
G02X1078677Y1425076I142J-141D01*
G01X1098962D01*
G03X1099104Y1425135I0J200D01*
G01X1113229Y1439260D01*
G03X1113288Y1439402I-141J142D01*
G01Y1637745D01*
G02X1113292Y1637782I200J-3D01*
G01Y1637784D01*
G02X1113345Y1637885I196J-39D01*
G01X1115204Y1639744D01*
G02X1115305Y1639797I140J-143D01*
G01X1115307D01*
G02X1115344Y1639801I40J-196D01*
G37*
G36*
G01X1048635Y1436271D02*
Y1425672D01*
Y1421061D01*
X1032671Y1405097D01*
X1028494D01*
X997127D01*
G02X996985Y1405156I0J200D01*
G01X995905Y1406236D01*
G02X995846Y1406378I141J142D01*
G01Y1411565D01*
G03X995787Y1411707I-200J0D01*
G01X991112Y1416382D01*
G03X990970Y1416441I-142J-141D01*
G01X971645D01*
G02X971503Y1416500I0J200D01*
G01X967547Y1420456D01*
G03X967405Y1420515I-142J-141D01*
G01X935211D01*
X934331Y1421395D01*
X932266Y1423460D01*
Y1440609D01*
X933596Y1441939D01*
X1046516D01*
X1048635Y1439820D01*
Y1436271D01*
G37*
G36*
G01X953099Y1477459D02*
X953979Y1476579D01*
G02X954038Y1476437I-141J-142D01*
G01Y1451122D01*
G02X953979Y1450980I-200J0D01*
G01X953597Y1450598D01*
G02X953455Y1450539I-142J141D01*
G01X933021D01*
G02X932879Y1450598I0J200D01*
G01X932875Y1450602D01*
X932802Y1450632D01*
X930506D01*
G02X930364Y1450691I0J200D01*
G01X929199Y1451856D01*
G02X929140Y1451998I141J142D01*
G01Y1467455D01*
G02X929199Y1467597I200J0D01*
G01X931879Y1470277D01*
G03X931938Y1470419I-141J142D01*
G01Y1475174D01*
G02X931997Y1475316I200J0D01*
G01X934140Y1477459D01*
G02X934282Y1477518I142J-141D01*
G01X952957D01*
G02X953099Y1477459I0J-200D01*
G37*
G36*
G01X1106884Y1640102D02*
X1108278D01*
G02X1108420Y1640043I0J-200D01*
G01X1110751Y1637712D01*
G02X1110810Y1637570I-141J-142D01*
G01Y1597717D01*
G02X1110751Y1597575I-200J0D01*
G01X1108372Y1595196D01*
G02X1108230Y1595137I-142J141D01*
G01X1083511D01*
G03X1083369Y1595078I0J-200D01*
G01X1081529Y1593238D01*
G03X1081470Y1593096I141J-142D01*
G01Y1587776D01*
G03X1081529Y1587634I200J0D01*
G01X1082391Y1586772D01*
G03X1082533Y1586713I142J141D01*
G01X1094319D01*
G02X1094461Y1586654I0J-200D01*
G01X1099846Y1581269D01*
G02X1099902Y1581099I-142J-141D01*
G01X1099850Y1580735D01*
X1099797Y1580659D01*
X1099755Y1580636D01*
G03X1098974Y1579318I722J-1318D01*
G03X1100476Y1577816I1502J0D01*
G03X1101794Y1578597I0J1503D01*
G01X1101817Y1578639D01*
X1101893Y1578692D01*
X1102257Y1578744D01*
G02X1102427Y1578688I29J-198D01*
G01X1108535Y1572580D01*
G02X1108594Y1572439I-141J-142D01*
G01Y1546961D01*
G02X1108535Y1546820I-200J1D01*
G01X1107440Y1545725D01*
G02X1107298Y1545666I-142J141D01*
G01X1102479D01*
G02X1102337Y1545725I0J200D01*
G01X1100248Y1547814D01*
G03X1098617Y1548490I-1632J-1631D01*
G03X1096310Y1546183I0J-2307D01*
G03X1096329Y1545891I2307J3D01*
G01X1096331Y1545879D01*
Y1545866D01*
G02X1096131Y1545666I-200J0D01*
G01X1096079D01*
G02X1095937Y1545725I0J200D01*
G01X1093731Y1547931D01*
G03X1092100Y1548606I-1630J-1631D01*
G01X1091525D01*
G03X1089218Y1546300I0J-2307D01*
G03X1089227Y1546101I2307J5D01*
G01X1089231Y1546058D01*
X1089204Y1545980D01*
X1088976Y1545731D01*
G02X1088829Y1545666I-148J135D01*
G01X1079938D01*
G02X1079796Y1545725I0J200D01*
G01X1077362Y1548159D01*
G02X1077303Y1548301I141J142D01*
G01Y1557636D01*
G03X1077244Y1557778I-200J0D01*
G01X1065514Y1569508D01*
G03X1065372Y1569567I-142J-141D01*
G01X1049101D01*
G03X1048959Y1569508I0J-200D01*
G01X1044083Y1564632D01*
X1044069Y1564622D01*
G03X1038920Y1559473I11836J-16985D01*
G01X1038910Y1559459D01*
X1024230Y1544779D01*
G02X1024088Y1544720I-142J141D01*
G01X1003880D01*
G02X1003738Y1544779I0J200D01*
G01X1002426Y1546091D01*
G02X1002367Y1546233I141J142D01*
G01Y1568512D01*
G03X1002308Y1568654I-200J0D01*
G01X999129Y1571833D01*
G03X998987Y1571892I-142J-141D01*
G01X967749D01*
G02X967607Y1571951I0J200D01*
G01X965422Y1574136D01*
G02X965363Y1574278I141J142D01*
G01Y1578250D01*
G03X965304Y1578392I-200J0D01*
G01X960265Y1583431D01*
G03X960123Y1583490I-142J-141D01*
G01X942870D01*
G02X942728Y1583549I0J200D01*
G01X938157Y1588120D01*
G02X938098Y1588262I141J142D01*
G01Y1628572D01*
G02X938157Y1628714I200J0D01*
G01X941866Y1632423D01*
G02X942008Y1632482I142J-141D01*
G01X1037599D01*
G02X1037741Y1632423I0J-200D01*
G01X1074051D01*
G03X1074193Y1632482I0J200D01*
G01X1081754Y1640043D01*
G02X1081896Y1640102I142J-141D01*
G01X1088291D01*
G02X1088479Y1639968I-1J-200D01*
G01X1088625Y1639551D01*
X1088590Y1639429D01*
X1088540Y1639389D01*
G03X1087972Y1638213I933J-1176D01*
G03X1090976I1502J0D01*
G03X1090408Y1639389I-1501J0D01*
G01X1090358Y1639429D01*
X1090323Y1639551D01*
X1090469Y1639968D01*
G02X1090657Y1640102I189J-66D01*
G01X1092291D01*
G02X1092479Y1639968I-1J-200D01*
G01X1092625Y1639551D01*
X1092590Y1639429D01*
X1092540Y1639389D01*
G03X1091972Y1638213I933J-1176D01*
G03X1094976I1502J0D01*
G03X1094408Y1639389I-1501J0D01*
G01X1094358Y1639429D01*
X1094323Y1639551D01*
X1094469Y1639968D01*
G02X1094657Y1640102I189J-66D01*
G01X1104064D01*
G02X1104246Y1639983I-1J-200D01*
G01X1104419Y1639594D01*
X1104400Y1639478D01*
X1104360Y1639434D01*
G03X1103972Y1638426I1115J-1008D01*
G03X1106976I1502J0D01*
G03X1106588Y1639434I-1503J0D01*
G01X1106548Y1639478D01*
X1106529Y1639594D01*
X1106702Y1639983D01*
G02X1106884Y1640102I183J-81D01*
G37*
G36*
G01X1014686Y202336D02*
X1018198D01*
G02X1018339Y202278I0J-200D01*
G01X1020379Y200238D01*
X1020394Y200207D01*
G03X1020433Y200132I1352J655D01*
G01X1020434Y200131D01*
G03X1020449Y200105I1308J738D01*
G01X1020462Y200083D01*
X1020478Y200027D01*
X1020491Y199981D01*
Y197600D01*
G02X1020458Y197490I-200J0D01*
G03Y195840I1254J-825D01*
G02X1020491Y195730I-167J-110D01*
G01Y193600D01*
G02X1020458Y193490I-200J0D01*
G03Y191840I1254J-825D01*
G02X1020491Y191730I-167J-110D01*
G01Y187518D01*
X1020481Y187475D01*
X1020470Y187453D01*
G03Y186103I1355J-675D01*
G01X1020481Y186081D01*
X1020491Y186038D01*
Y181600D01*
G02X1020458Y181490I-200J0D01*
G03Y179840I1254J-825D01*
G02X1020491Y179730I-167J-110D01*
G01Y177600D01*
G02X1020458Y177490I-200J0D01*
G03Y175840I1254J-825D01*
G02X1020491Y175730I-167J-110D01*
G01Y173600D01*
G02X1020458Y173490I-200J0D01*
G03Y171840I1254J-825D01*
G02X1020491Y171730I-167J-110D01*
G01Y169600D01*
G02X1020458Y169490I-200J0D01*
G03Y167840I1254J-825D01*
G02X1020491Y167730I-167J-110D01*
G01Y163086D01*
G02X1020435Y162946I-200J-1D01*
G01X1020375Y162885D01*
G02X1020320Y162845I-143J139D01*
G01X1020231Y162802D01*
X1020198Y162798D01*
G03Y159814I180J-1492D01*
G01X1020231Y159810D01*
X1020320Y159767D01*
G02X1020375Y159727I-88J-179D01*
G01X1020435Y159666D01*
G02X1020491Y159526I-144J-139D01*
G01Y151308D01*
G02X1020291Y151108I-200J0D01*
G01X1013717D01*
G02X1013541Y151213I0J200D01*
G01X1013375Y151523D01*
G02X1013351Y151625I176J95D01*
G01X1013353Y151682D01*
X1013384Y151729D01*
G03X1013636Y152562I-1251J833D01*
G03X1012134Y154064I-1502J0D01*
G03X1010840Y153325I0J-1502D01*
G01X1010814Y153281D01*
X1010729Y153229D01*
X1010551Y153219D01*
X1010298Y153204D01*
X1010208Y153245D01*
X1010178Y153285D01*
G03X1008984Y153875I-1194J-913D01*
G03X1007482Y152373I0J-1502D01*
G03X1007647Y151689I1502J0D01*
G01X1007671Y151642D01*
X1007667Y151539D01*
X1007461Y151203D01*
G02X1007291Y151108I-170J105D01*
G01X997973D01*
G02X997845Y151155I1J200D01*
G01X997012Y151988D01*
X996707Y152292D01*
G03X995292Y152878I-1415J-1415D01*
G01X988932D01*
G03X987517Y152292I0J-2001D01*
G01X984180Y148955D01*
G03X983594Y147540I1415J-1415D01*
G03X983602Y147354I2001J-7D01*
G01X983603Y147345D01*
Y147340D01*
G03X985590Y145538I1992J200D01*
G01X985595D01*
G03X986097Y145602I0J2002D01*
G03X987010Y146125I-503J1937D01*
G01X989702Y148817D01*
G02X989844Y148876I142J-141D01*
G01X992322D01*
G02X992471Y148809I0J-200D01*
G01X992670Y148588D01*
G02X992720Y148437I-149J-133D01*
G01Y148434D01*
G03X992712Y148277I1494J-155D01*
G03X994214Y146775I1502J0D01*
G03X995403Y147359I0J1502D01*
G01X995427Y147390D01*
X995460Y147410D01*
G02X995530Y147435I101J-173D01*
G01X995799Y147479D01*
G02X995943Y147447I32J-198D01*
G01X995944Y147446D01*
G03X996408Y147214I1120J1659D01*
G03X997063Y147104I654J1892D01*
G01X1020291D01*
G02X1020491Y146904I0J-200D01*
G01Y124540D01*
X1020488Y124524D01*
G03X1020469Y124283I1483J-238D01*
G03X1020488Y124042I1502J-3D01*
G01X1020491Y124026D01*
Y120792D01*
G02X1020477Y120718I-200J0D01*
G01X1020439Y120621D01*
X1020415Y120594D01*
G03Y118594I1122J-1000D01*
G01X1020439Y118567D01*
X1020477Y118470D01*
G02X1020491Y118396I-186J-74D01*
G01Y117752D01*
X1020437Y117618D01*
X1020414Y117592D01*
G03X1020035Y116594I1124J-998D01*
G01Y116592D01*
G03X1020339Y115687I1503J1D01*
G02X1020379Y115567I-160J-120D01*
G01Y114421D01*
G02X1020339Y114301I-200J0D01*
G03Y112487I1199J-907D01*
G02X1020379Y112367I-160J-120D01*
G01Y111688D01*
G03X1020409Y111583I200J0D01*
G01X1020460Y111504D01*
G02X1020491Y111396I-169J-107D01*
G01Y109734D01*
G02X1020432Y109592I-200J0D01*
G01X1019489Y108649D01*
G02X1019347Y108590I-142J141D01*
G01X982675D01*
G02X982511Y108676I0J200D01*
G03X979547I-1482J-1027D01*
G02X979383Y108590I-164J114D01*
G01X963102D01*
G02X962960Y108649I0J200D01*
G01X961901Y109708D01*
X961876Y109753D01*
X961869Y109780D01*
G03X960783Y110866I-1456J-370D01*
G01X960756Y110873D01*
X960711Y110898D01*
X960649Y110960D01*
G02X960590Y111102I141J142D01*
G01Y114907D01*
X960677Y115016D01*
X960746Y115031D01*
G03Y117961I-333J1465D01*
G01X960677Y117976D01*
X960590Y118085D01*
Y159263D01*
G02X960649Y159405I200J0D01*
G01X961512Y160268D01*
G02X961654Y160327I142J-141D01*
G01X997171D01*
G03X997313Y160386I0J200D01*
G01X1001018Y164091D01*
G03X1001077Y164233I-141J142D01*
G01Y165148D01*
G03X1001078Y165174I-1200J59D01*
G01Y190158D01*
G03X1001077Y190185I-1201J-31D01*
G01Y193697D01*
G03X1001078Y193724I-1200J58D01*
G01Y201568D01*
G02X1001137Y201710I200J0D01*
G01X1001704Y202277D01*
G02X1001846Y202336I142J-141D01*
G01X1011546D01*
G02X1011723Y202229I0J-200D01*
G01X1011913Y201867D01*
X1011907Y201757D01*
X1011875Y201711D01*
G03X1011722Y201423I1242J-845D01*
G01X1011714Y201402D01*
G03X1011641Y201150I1401J-542D01*
G01Y201147D01*
G02X1011528Y201006I-196J41D01*
G01X1011231Y200871D01*
G02X1011047Y200880I-83J182D01*
G03X1010291Y201084I-756J-1299D01*
G03Y198080I0J-1502D01*
G03X1011766Y199296I0J1503D01*
G01Y199298D01*
G02X1011879Y199440I196J-40D01*
G01X1012176Y199575D01*
G02X1012360Y199566I83J-182D01*
G03X1013116Y199362I756J1299D01*
G03X1014618Y200845I0J1502D01*
G01Y200865D01*
G03X1014357Y201711I-1502J0D01*
G01X1014325Y201757D01*
X1014319Y201867D01*
X1014509Y202229D01*
G02X1014686Y202336I177J-93D01*
G37*
G36*
G01X958794Y1450939D02*
X955821D01*
G02X955679Y1450998I0J200D01*
G01X955197Y1451480D01*
G02X955138Y1451622I141J142D01*
G01Y1479563D01*
G02X955197Y1479705I200J0D01*
G01X956745Y1481253D01*
G02X956887Y1481312I142J-141D01*
G01X1040339D01*
G02X1040529Y1481174I0J-200D01*
G03X1049670Y1467295I29942J9771D01*
G02X1049738Y1467144I-132J-150D01*
G01Y1452449D01*
G02X1049679Y1452307I-200J0D01*
G01X1048392Y1451020D01*
G02X1048250Y1450961I-142J141D01*
G01X958816D01*
X958794Y1450939D01*
G37*
G36*
G01X1007026Y905290D02*
X1017952D01*
G02X1018092Y905233I0J-200D01*
G01X1018093Y905232D01*
X1022139Y901186D01*
G02X1022198Y901044I-141J-142D01*
G01Y896870D01*
G02X1022124Y896715I-200J0D01*
G01X1021847Y896490D01*
X1021760Y896469D01*
X1021715Y896478D01*
G03X1021408Y896510I-308J-1470D01*
G03Y893506I0J-1502D01*
G03X1021716Y893538I0J1502D01*
G01X1021761Y893547D01*
X1021848Y893526D01*
X1022124Y893301D01*
G02X1022198Y893146I-126J-155D01*
G01Y885410D01*
G03Y885344I1201J-33D01*
G01Y850524D01*
G02X1022116Y850363I-200J0D01*
G01X1021857Y850174D01*
G02X1021680Y850144I-118J161D01*
G01X1021679D01*
X1021652Y850152D01*
G03X1021614Y850162I-401J-1447D01*
G01X1021610Y850163D01*
X1021608D01*
G03X1021507Y850187I-398J-1449D01*
G03X1021217Y850214I-284J-1475D01*
G03X1019719Y848712I4J-1502D01*
G03X1021221Y847210I1502J0D01*
G01X1021224D01*
G03X1021507Y847237I-1J1502D01*
G03X1021608Y847261I-297J1473D01*
G01X1021610D01*
X1021614Y847262D01*
G03X1021652Y847272I-363J1457D01*
G01X1021679Y847280D01*
X1021752D01*
G02X1021870Y847241I-1J-200D01*
G01X1022116Y847061D01*
G02X1022122Y847056I-125J-156D01*
G02X1022198Y846900I-124J-157D01*
G01Y839158D01*
X1022140Y839063D01*
X1022090Y839037D01*
X1021725Y838847D01*
X1021614Y838854D01*
X1021568Y838887D01*
G03X1020703Y839161I-865J-1228D01*
G03Y836157I0J-1502D01*
G03X1021568Y836431I0J1502D01*
G02X1021776Y836444I115J-164D01*
G01X1021805Y836429D01*
X1021815Y836424D01*
X1021818Y836422D01*
X1021967Y836345D01*
X1021983Y836337D01*
X1022090Y836282D01*
G02X1022178Y836190I-93J-177D01*
G01X1022198Y836149D01*
Y835237D01*
G02X1022193Y835193I-200J0D01*
G01X1022183Y835150D01*
G02X1022169Y835108I-195J42D01*
G01X1022150Y835067D01*
X1021983Y834981D01*
X1021967Y834973D01*
X1021828Y834901D01*
G03X1021822Y834897I107J-168D01*
G02X1021693Y834870I-103J171D01*
G01X1021620Y834879D01*
G02X1021536Y834909I24J199D01*
G01X1021534Y834911D01*
X1021533D01*
G03X1020709Y835162I-831J-1252D01*
G01X1020667Y835161D01*
G03X1019201Y833659I36J-1502D01*
G03X1020703Y832157I1502J0D01*
G03X1021568Y832431I0J1502D01*
G02X1021776Y832444I115J-164D01*
G01X1021805Y832429D01*
X1021815Y832424D01*
X1021818Y832422D01*
X1021967Y832345D01*
X1021983Y832337D01*
X1022090Y832282D01*
G02X1022178Y832190I-93J-177D01*
G01X1022198Y832149D01*
Y820875D01*
G02X1022168Y820769I-200J-1D01*
G01X1022156Y820750D01*
X1022071Y820660D01*
X1021926Y820508D01*
X1021857Y820476D01*
X1021818Y820474D01*
G03Y817474I77J-1500D01*
G02X1021891Y817456I-11J-200D01*
G01X1021926Y817440D01*
X1022003Y817359D01*
X1022004Y817358D01*
X1022143Y817211D01*
G02X1022198Y817073I-145J-138D01*
G01Y773873D01*
G02X1022142Y773734I-200J0D01*
G01X1021977Y773563D01*
X1021951Y773536D01*
X1021820Y773475D01*
X1021783Y773472D01*
G03X1021817Y770474I112J-1498D01*
G02X1021948Y770416I-10J-200D01*
G01X1021963Y770401D01*
X1021980Y770383D01*
X1022052Y770307D01*
X1022142Y770213D01*
G02X1022198Y770074I-144J-139D01*
G01Y722646D01*
X1022168Y722572D01*
X1022139Y722544D01*
X1016264Y716669D01*
X1016236Y716640D01*
X1016162Y716610D01*
X1002090D01*
X1002016Y716640D01*
X1001988Y716669D01*
X995779Y722878D01*
X995750Y722906D01*
X995720Y722980D01*
Y776865D01*
G02X995777Y777005I200J0D01*
G01X995778Y777006D01*
X996100Y777328D01*
G02X996102Y777330I142J-140D01*
G02X996242Y777387I140J-143D01*
G01X996638D01*
X996663Y777380D01*
G03X997048Y777330I384J1453D01*
G01X997051D01*
G03Y780336I0J1503D01*
G03X996280Y780123I0J-1503D01*
G02X996229Y780101I-104J171D01*
G01X996203Y780094D01*
X995985D01*
G02X995843Y780153I0J200D01*
G01X995779Y780217D01*
X995750Y780245D01*
X995720Y780319D01*
Y806893D01*
X995719Y806895D01*
Y814257D01*
G02X995778Y814399I200J0D01*
G01X995788Y814409D01*
X996014Y814605D01*
G02X996145Y814654I131J-151D01*
G01X996173D01*
X996186Y814652D01*
G03X996385Y814639I197J1489D01*
G03Y817643I0J1502D01*
G03X996175Y817628I2J-1502D01*
G01X996132Y817622D01*
X996050Y817646D01*
X995789Y817871D01*
X995783Y817878D01*
X995778Y817883D01*
X995749Y817911D01*
X995719Y817985D01*
Y859578D01*
G03X995660Y859720I-200J0D01*
G01X986417Y868963D01*
G02X986379Y869016I141J141D01*
G01X986353Y869069D01*
X986348Y869089D01*
G03X985241Y870181I-1456J-369D01*
G01X985213Y870188D01*
X985166Y870214D01*
X980659Y874721D01*
G02X980701Y875323I283J283D01*
G02X980712Y875331I123J-157D01*
G03X981393Y876589I-821J1258D01*
G03X981199Y877326I-1502J-1D01*
G02X981188Y877350I176J95D01*
G02X981315Y877816I371J149D01*
G02X981330Y877827I126J-156D01*
G03X982031Y879097I-800J1270D01*
G03X980529Y880599I-1502J0D01*
G01X980527D01*
G03X979025Y879097I0J-1502D01*
G03X979208Y878379I1502J0D01*
G02X979073Y877852I-352J-191D01*
G03X978636Y877421I815J-1263D01*
G02X978020Y877360I-333J222D01*
G01X975461Y879919D01*
X975432Y879947D01*
X975402Y880021D01*
Y902044D01*
G02X975461Y902186I200J0D01*
G01X978506Y905231D01*
G02X978648Y905290I142J-141D01*
G01X1002785D01*
X1002794Y905289D01*
G03X1002930Y905283I134J1496D01*
G03X1003066Y905289I2J1502D01*
G01X1003075Y905290D01*
X1003800D01*
X1003913Y905190D01*
X1003922Y905114D01*
G03X1006904I1491J181D01*
G01X1006913Y905190D01*
X1007026Y905290D01*
G37*
G36*
G01X964962Y1566784D02*
X993823D01*
G02X993965Y1566725I0J-200D01*
G01X995797Y1564893D01*
G02X995856Y1564751I-141J-142D01*
G01Y1547091D01*
G02X995797Y1546949I-200J0D01*
G01X993903Y1545055D01*
G02X993761Y1544996I-142J141D01*
G01X965293D01*
G02X965151Y1545055I0J200D01*
G01X963569Y1546637D01*
G02X963510Y1546779I141J142D01*
G01Y1565332D01*
G02X963569Y1565474I200J0D01*
G01X964820Y1566725D01*
G02X964962Y1566784I142J-141D01*
G37*
G36*
G01X1051831Y54588D02*
X1080886D01*
X1081101Y54373D01*
Y52806D01*
X1080886Y52591D01*
X1051831D01*
G03X1045894Y46654I0J-5937D01*
G01Y7874D01*
G02X1040020Y2000I-5874J0D01*
G01X992776D01*
G02X986902Y7874I0J5874D01*
G01Y46654D01*
G03Y46659I-5936J2D01*
G01X988900D01*
G02Y46654I-7934J-2D01*
G01Y7874D01*
G03X992776Y3998I3876J0D01*
G01X1040020D01*
G03X1043896Y7874I0J3876D01*
G01Y46654D01*
G02X1051831Y54588I7935J-1D01*
G37*
G36*
G01X997483Y275932D02*
X1019418D01*
X1019492Y275902D01*
X1019520Y275873D01*
X1020131Y275262D01*
G02X1020190Y275120I-141J-142D01*
G01Y205020D01*
X1020160Y204946D01*
X1020131Y204918D01*
X1018610Y203397D01*
G02X1018468Y203338I-142J141D01*
G01X997601D01*
X997527Y203368D01*
X997499Y203397D01*
X997341Y203555D01*
G02X997283Y203696I142J141D01*
G01Y204858D01*
G02X997343Y205001I200J0D01*
G01X997577Y205230D01*
X997651Y205259D01*
X997691Y205258D01*
X997725D01*
G03Y208262I0J1502D01*
G01X997691D01*
X997651Y208261D01*
X997577Y208290D01*
X997343Y208519D01*
G02X997283Y208661I140J143D01*
G01Y255107D01*
G02X997401Y255289I200J0D01*
G01X997725Y255436D01*
G02X997896Y255432I81J-183D01*
G01X997946Y255407D01*
X997965Y255392D01*
G03X998939Y255033I975J1143D01*
G03Y258037I0J1502D01*
G03X997965Y257678I1J-1502D01*
G01X997946Y257663D01*
X997896Y257638D01*
G02X997725Y257634I-90J179D01*
G01X997401Y257781D01*
G02X997283Y257963I82J182D01*
G01Y275732D01*
G02X997483Y275932I200J0D01*
G37*
G36*
G01X1314416Y374507D02*
X1325527D01*
G02X1325669Y374448I0J-200D01*
G01X1326525Y373592D01*
G02X1326584Y373450I-141J-142D01*
G01Y364660D01*
X1315474Y353550D01*
Y351396D01*
X1315444Y351322D01*
X1315415Y351294D01*
X1315362Y351241D01*
X1315334Y351226D01*
G03Y348551I683J-1337D01*
G01X1315362Y348536D01*
X1315415Y348483D01*
G02X1315417Y348481I-140J-142D01*
G02X1315474Y348341I-143J-140D01*
G01Y338295D01*
G02X1315415Y338153I-200J0D01*
G01X1315304Y338042D01*
X1315267Y338027D01*
X1315234Y338013D01*
X1315197Y338011D01*
G03X1313754Y336510I59J-1501D01*
G03X1314290Y335360I1502J0D01*
G01X1314297Y335354D01*
X1314312Y335339D01*
G02X1314370Y335208I-142J-141D01*
G01X1314376Y335084D01*
Y335082D01*
X1314385Y334915D01*
G02X1314327Y334763I-200J-11D01*
G01X1314326Y334762D01*
G03X1314137Y334526I1072J-1052D01*
G01X1314124Y334506D01*
X1314106Y334489D01*
X1314087Y334471D01*
X1314040Y334445D01*
G02X1313769Y334519I-98J174D01*
G01X1313739Y334571D01*
X1313741Y334629D01*
G03X1313742Y334681I-1501J55D01*
G03X1312240Y333179I-1502J0D01*
G03X1313267Y333585I0J1502D01*
G01X1313306Y333622D01*
X1313411Y333646D01*
X1313794Y333528D01*
G02X1313913Y333430I-58J-192D01*
G01X1313925Y333406D01*
X1313931Y333380D01*
Y333379D01*
G03X1315397Y332207I1466J331D01*
G03X1316814Y333211I0J1502D01*
G02X1316861Y333286I189J-66D01*
G01X1317236Y333661D01*
G02X1317378Y333720I142J-141D01*
G01X1317393D01*
G02X1317593Y333520I0J-200D01*
G01Y328431D01*
X1316161Y326999D01*
X1306593D01*
X1289903Y310309D01*
X1264071D01*
G03X1263330Y310505I-742J-1307D01*
G01X1263328D01*
G03Y307501I0J-1502D01*
G01X1263330D01*
G03X1264071Y307697I-1J1503D01*
G01X1290985D01*
X1307675Y324387D01*
X1312730D01*
X1313401Y323716D01*
X1316720D01*
X1317593Y322843D01*
Y314916D01*
G02X1317432Y314719I-200J-1D01*
G01X1317395Y314712D01*
X1317289Y314559D01*
X1317232Y314519D01*
X1317197Y314510D01*
G03X1316082Y313058I388J-1452D01*
G03X1316685Y311855I1502J0D01*
G01X1316713Y311834D01*
X1316791Y311717D01*
X1316799Y311680D01*
X1316825Y311568D01*
X1316819Y311504D01*
X1316805Y311473D01*
X1316801Y311463D01*
X1316794Y311450D01*
X1316789Y311440D01*
G03X1316660Y311153I1573J-880D01*
G03X1316585Y310862I1702J-594D01*
G03X1316560Y310564I1778J-299D01*
G01Y310562D01*
G03X1317316Y309094I1803J0D01*
G01X1317318D01*
G03X1317429Y309019I1064J1455D01*
G01X1317449Y309007D01*
X1317501Y308955D01*
G02X1317532Y308915I-141J-142D01*
G01X1317553Y308879D01*
X1317554Y308878D01*
G03X1317559Y308869I177J93D01*
G01X1317576Y308845D01*
X1317593Y308788D01*
Y292176D01*
X1317563Y292102D01*
X1317534Y292074D01*
X1317322Y291862D01*
G02X1317277Y291828I-142J141D01*
G01X1317276D01*
G02X1317177Y291803I-97J175D01*
G01X1316890Y291807D01*
X1316815Y291841D01*
X1316787Y291872D01*
G03X1316676Y291982I-1133J-1032D01*
G01X1316675Y291983D01*
X1316654Y292003D01*
X1316627Y292039D01*
X1316615Y292069D01*
X1316601Y292106D01*
Y292352D01*
G02X1316619Y292434I200J-1D01*
G01X1316665Y292537D01*
X1316693Y292564D01*
G03X1317151Y293644I-1044J1080D01*
G01Y293683D01*
G03X1315649Y295147I-1502J-38D01*
G03X1314662Y294777I0J-1501D01*
G01X1314634Y294753D01*
X1314568Y294728D01*
X1314282D01*
G02X1314192Y294750I1J200D01*
G01X1314136Y294778D01*
X1314117Y294793D01*
X1314115Y294795D01*
G03X1313149Y295147I-966J-1150D01*
G03X1311647Y293683I0J-1502D01*
G01Y293644D01*
G03X1312105Y292564I1502J0D01*
G01X1312133Y292537D01*
X1312179Y292434D01*
G02X1312197Y292352I-182J-83D01*
G01Y292138D01*
G02X1312179Y292056I-200J1D01*
G01X1312133Y291953D01*
X1312105Y291926D01*
G03X1311647Y290846I1044J-1080D01*
G01Y290807D01*
G03X1312017Y289858I1502J39D01*
G01X1312041Y289830D01*
X1312066Y289764D01*
Y289478D01*
G02X1312044Y289388I-200J1D01*
G01X1312016Y289332D01*
X1312001Y289313D01*
X1311999Y289311D01*
G03X1311647Y288345I1150J-966D01*
G01Y288344D01*
G03X1312122Y287249I1502J1D01*
G01X1312138Y287234D01*
X1312162Y287200D01*
X1312171Y287177D01*
G02X1312187Y287102I-184J-78D01*
G01X1312191Y286818D01*
G02X1312167Y286719I-200J-4D01*
G01X1312152Y286692D01*
X1308119Y282659D01*
X1308091Y282630D01*
X1308017Y282600D01*
X1305819D01*
G02X1305721Y282626I1J200D01*
G01X1305642Y282671D01*
G02X1305600Y282703I99J174D01*
G01X1305582Y282721D01*
X1305568Y282743D01*
X1305566Y282746D01*
X1305562Y282751D01*
X1305557Y282760D01*
G03X1302990Y282761I-1284J-778D01*
G01X1302978Y282743D01*
X1302964Y282721D01*
X1302946Y282703D01*
G02X1302904Y282671I-141J142D01*
G01X1302825Y282626D01*
G02X1302727Y282600I-99J174D01*
G01X1299715D01*
G02X1299676Y282604I1J200D01*
G01X1299629Y282613D01*
G02X1299583Y282628I39J196D01*
G01X1299533Y282652D01*
G02X1299468Y282701I85J181D01*
G01X1299467Y282702D01*
Y282703D01*
G03X1297199I-1134J-986D01*
G01X1297172Y282672D01*
X1297022Y282600D01*
X1272123D01*
G02X1272091Y282603I3J200D01*
G01X1272052Y282609D01*
X1272050D01*
X1272048Y282610D01*
X1272033Y282615D01*
G03X1271573Y282687I-459J-1430D01*
G01X1271571D01*
G03X1271097Y282610I1J-1502D01*
G01X1271066Y282600D01*
X1209642D01*
G02X1209592Y282606I-1J200D01*
G01X1209519Y282625D01*
X1209498Y282636D01*
G03X1208598Y282796I-700J-1329D01*
G03X1208096Y282636I198J-1489D01*
G01X1208076Y282626D01*
X1208005Y282607D01*
G02X1207954Y282600I-52J193D01*
G01X1203457D01*
G02X1203359Y282626I1J200D01*
G01X1203280Y282671D01*
G02X1203238Y282703I99J174D01*
G01X1203220Y282721D01*
X1203206Y282743D01*
X1203204Y282746D01*
X1203200Y282751D01*
X1203195Y282760D01*
G03X1200628Y282761I-1284J-778D01*
G01X1200616Y282743D01*
X1200602Y282721D01*
X1200584Y282703D01*
G02X1200542Y282671I-141J142D01*
G01X1200463Y282626D01*
G02X1200365Y282600I-99J174D01*
G01X1197353D01*
G02X1197314Y282604I1J200D01*
G01X1197267Y282613D01*
G02X1197221Y282628I39J196D01*
G01X1197171Y282652D01*
G02X1197106Y282701I85J181D01*
G01X1197105Y282702D01*
Y282703D01*
G03X1194837I-1134J-986D01*
G01X1194810Y282672D01*
X1194660Y282600D01*
X1107280D01*
G02X1107230Y282606I-1J200D01*
G01X1107157Y282625D01*
X1107136Y282636D01*
G03X1106236Y282796I-700J-1329D01*
G03X1105734Y282636I198J-1489D01*
G01X1105714Y282626D01*
X1105643Y282607D01*
G02X1105592Y282600I-52J193D01*
G01X1101095D01*
G02X1100997Y282626I1J200D01*
G01X1100918Y282671D01*
G02X1100876Y282703I99J174D01*
G01X1100858Y282721D01*
X1100844Y282743D01*
X1100842Y282746D01*
X1100838Y282751D01*
X1100833Y282760D01*
G03X1098266Y282761I-1284J-778D01*
G01X1098254Y282743D01*
X1098240Y282721D01*
X1098222Y282703D01*
G02X1098180Y282671I-141J142D01*
G01X1098101Y282626D01*
G02X1098003Y282600I-99J174D01*
G01X1094991D01*
G02X1094952Y282604I1J200D01*
G01X1094905Y282613D01*
G02X1094859Y282628I39J196D01*
G01X1094809Y282652D01*
G02X1094744Y282701I85J181D01*
G01X1094743Y282702D01*
Y282703D01*
G03X1092475I-1134J-986D01*
G01X1092448Y282672D01*
X1092298Y282600D01*
X998706D01*
X998656Y282614D01*
X998632Y282628D01*
X998527Y282690D01*
X998492Y282726D01*
X998481Y282745D01*
X998478Y282749D01*
X998473Y282757D01*
G03X997497Y283452I-1287J-774D01*
G01X997468Y283458D01*
X997417Y283486D01*
X996561Y284342D01*
X996532Y284370D01*
X996502Y284444D01*
Y289197D01*
G02X996610Y289374I200J-1D01*
G01X996970Y289563D01*
X997026Y289560D01*
X997083Y289558D01*
X997132Y289524D01*
G03X997992Y289253I861J1231D01*
G03Y292257I0J1502D01*
G03X997131Y291985I1J-1502D01*
G01X997085Y291953D01*
X996974Y291946D01*
X996610Y292136D01*
G02X996502Y292313I92J178D01*
G01Y299572D01*
G02X996559Y299712I200J0D01*
G01X998548Y301701D01*
G02X998550Y301703I142J-140D01*
G02X998690Y301760I140J-143D01*
G01X1003071D01*
G02X1003243Y301662I0J-200D01*
G01X1003246Y301658D01*
X1003412Y301341D01*
G02X1003435Y301233I-176J-94D01*
G01X1003433Y301204D01*
X1003415Y301153D01*
X1003393Y301119D01*
X1003392Y301117D01*
G03X1003133Y300277I1243J-843D01*
G01Y300276D01*
G03X1006137I1502J0D01*
G01Y300277D01*
G03X1005878Y301117I-1502J-3D01*
G01X1005877Y301119D01*
X1005855Y301153D01*
X1005848Y301174D01*
X1005835Y301244D01*
Y301298D01*
X1006021Y301653D01*
G02X1006198Y301760I177J-93D01*
G01X1007071D01*
G02X1007243Y301662I0J-200D01*
G01X1007246Y301658D01*
X1007412Y301341D01*
G02X1007435Y301233I-176J-94D01*
G01X1007433Y301204D01*
X1007415Y301153D01*
X1007393Y301119D01*
X1007392Y301117D01*
G03X1007133Y300277I1243J-843D01*
G01Y300276D01*
G03X1010137I1502J0D01*
G01Y300277D01*
G03X1009878Y301117I-1502J-3D01*
G01X1009877Y301119D01*
X1009855Y301153D01*
X1009848Y301174D01*
X1009835Y301244D01*
Y301298D01*
X1010021Y301653D01*
G02X1010198Y301760I177J-93D01*
G01X1026656D01*
G03X1028059Y302240I0J2292D01*
G01X1028085Y302260D01*
X1028173Y302291D01*
G02X1028240Y302303I68J-188D01*
G01X1030212D01*
G03X1030354Y302362I0J200D01*
G01X1034474Y306482D01*
G02X1034476Y306484I142J-140D01*
G02X1034616Y306541I140J-143D01*
G01X1172077D01*
G02X1172257Y306428I0J-200D01*
G01X1172413Y306105D01*
Y306103D01*
X1172438Y306054D01*
X1172426Y305937D01*
X1172389Y305890D01*
G03X1172057Y304948I1170J-942D01*
G03X1175061I1502J0D01*
G01Y304949D01*
G03X1174729Y305891I-1503J0D01*
G01X1174711Y305913D01*
X1174690Y305962D01*
X1174686Y305990D01*
G02X1174692Y306071I198J26D01*
G01X1174697Y306090D01*
X1174861Y306428D01*
G02X1174865Y306436I181J-85D01*
G01Y306437D01*
G02X1175040Y306541I176J-96D01*
G01X1175171D01*
G02X1175360Y306406I0J-200D01*
G03X1176858Y305031I1498J129D01*
G03X1177814Y305374I0J1504D01*
G01X1177818Y305375D01*
X1178130Y305318D01*
G02X1178235Y305263I-36J-197D01*
G01X1178253Y305245D01*
G02X1178275Y305219I-141J-142D01*
G03X1179901Y304376I1626J1147D01*
G03X1181887Y306233I0J1990D01*
G01X1181889Y306270D01*
X1181940Y306380D01*
X1181960Y306410D01*
X1182032Y306482D01*
G02X1182034Y306484I142J-140D01*
G02X1182174Y306541I140J-143D01*
G01X1231596D01*
G03X1231738Y306600I0J200D01*
G01X1236291Y311153D01*
G03X1236350Y311295I-141J142D01*
G01Y316508D01*
X1236356Y316553D01*
X1236359Y316564D01*
G03X1236406Y316913I-1455J374D01*
G01X1236407Y316952D01*
X1236436Y317022D01*
X1236465Y317051D01*
G02X1236635Y317107I141J-142D01*
G01X1236844Y316898D01*
G03X1238293Y315794I1449J399D01*
G03X1239795Y317296I0J1502D01*
G03X1238691Y318745I-1503J0D01*
G01X1237130Y320306D01*
X1236350D01*
Y332633D01*
G02X1236407Y332773I200J0D01*
G01X1256631Y352997D01*
G02X1256633Y352999I142J-140D01*
G02X1256773Y353056I140J-143D01*
G01X1285845D01*
G03X1285987Y353115I0J200D01*
G01X1296192Y363320D01*
G03X1296251Y363462I-141J142D01*
G01Y368696D01*
G02X1296310Y368838I200J0D01*
G01X1297599Y370127D01*
G02X1297755Y370185I141J-141D01*
G01X1298100Y370160D01*
X1298176Y370118D01*
X1298202Y370083D01*
G03X1299410Y369474I1208J894D01*
G03X1300912Y370976I0J1502D01*
G01Y370977D01*
G03X1300304Y372183I-1501J0D01*
G01X1300268Y372209D01*
X1300226Y372286D01*
X1300201Y372631D01*
G02X1300259Y372787I199J15D01*
G01X1300528Y373056D01*
G02X1300670Y373115I142J-141D01*
G01X1306639D01*
G03X1306693Y373123I-2J200D01*
G01X1306706Y373127D01*
X1306787Y373160D01*
G02X1306862Y373174I74J-186D01*
G01X1311823D01*
G03X1311965Y373233I0J200D01*
G01X1312035Y373303D01*
G02X1312057Y373322I141J-141D01*
G01X1312768D01*
X1312817Y373371D01*
G03X1313559Y373732I-153J1257D01*
G01X1314274Y374448D01*
G02X1314416Y374507I142J-141D01*
G37*
G36*
G01X1036315Y242428D02*
X1036328Y242427D01*
G03X1036472Y242418I147J1201D01*
G01X1040937D01*
G02X1040976Y242414I-1J-200D01*
G01X1040989Y242412D01*
G02X1041089Y242360I-39J-196D01*
G01X1041306Y242152D01*
X1041337Y242081D01*
X1041339Y242042D01*
G03X1041389Y241710I1501J56D01*
G03X1041812Y241002I1451J387D01*
G01X1041814Y241000D01*
X1041817Y240997D01*
G03X1042860Y240576I1043J1081D01*
G03X1044362Y242057I0J1502D01*
G01X1044363Y242098D01*
X1044394Y242170D01*
X1044591Y242359D01*
G02X1044691Y242412I140J-143D01*
G01X1044723Y242418D01*
X1048595D01*
G03X1048731Y242426I-3J1210D01*
G01X1048743Y242427D01*
X1052131D01*
X1052143Y242426D01*
G03X1052279Y242418I139J1202D01*
G01X1058872D01*
G02X1059014Y242359I0J-200D01*
G01X1061516Y239857D01*
G02X1061541Y239761I-175J-97D01*
G01Y153174D01*
G02X1061538Y153138I-200J-1D01*
G01X1061533Y153113D01*
G02X1061478Y153008I-197J36D01*
G01X1061472Y153002D01*
X1061467Y152998D01*
G03X1061311Y147579I2441J-2782D01*
G01X1061312Y147578D01*
G03X1061430Y147465I2619J2616D01*
G03X1061447Y147450I2458J2768D01*
G01X1061464Y147435D01*
X1061489Y147400D01*
X1061525Y147315D01*
G02X1061541Y147237I-184J-78D01*
G01Y125105D01*
X1061530Y125073D01*
G03X1061445Y124576I1417J-498D01*
G03X1061530Y124079I1502J1D01*
G01X1061541Y124047D01*
Y122985D01*
G03X1061556Y122909I200J0D01*
G01X1061576Y122862D01*
G02X1061591Y122785I-185J-76D01*
G01Y117487D01*
G02X1061554Y117370I-200J-1D01*
G03X1061273Y116496I1221J-875D01*
G03X1061554Y115622I1502J1D01*
G02X1061591Y115505I-163J-116D01*
G01Y110680D01*
G03X1061603Y110609I200J-3D01*
G01X1061618Y110569D01*
X1061609Y110439D01*
G02X1061597Y110383I-200J13D01*
G01X1061568Y110305D01*
X1061552Y110283D01*
G03X1061273Y109410I1223J-872D01*
G03X1061278Y109288I1502J0D01*
G01X1061281Y109259D01*
G03X1062775Y107908I1494J151D01*
G03X1063706Y108232I-1J1502D01*
G01X1063767Y108279D01*
X1063917Y108271D01*
X1064521Y107667D01*
G03X1064663Y107608I142J141D01*
G01X1065246D01*
X1065263Y107605D01*
G03X1065462Y107588I201J1185D01*
G01X1081389D01*
G02X1081588Y107389I0J-200D01*
G01Y104249D01*
G03X1081611Y103967I1803J5D01*
G03X1081620Y103915I1780J281D01*
G01X1081625Y103886D01*
X1081619Y103829D01*
X1081607Y103801D01*
G02X1081536Y103712I-185J75D01*
G01X1081460Y103659D01*
X1081350Y103652D01*
X1081301Y103678D01*
G03X1080615Y103844I-686J-1335D01*
G01X1080613D01*
G03X1079111Y102342I0J-1502D01*
G03X1079585Y101247I1502J0D01*
G01X1079587Y101245D01*
X1079590Y101242D01*
G03X1080633Y100821I1043J1081D01*
G03X1082133Y102242I0J1502D01*
G01Y102244D01*
G02X1082227Y102402I200J-12D01*
G01X1082366Y102488D01*
X1082546Y102600D01*
X1082643Y102608D01*
X1082688Y102589D01*
G03X1083380Y102446I704J1660D01*
G01X1083391D01*
G03X1085194Y104249I0J1803D01*
G01Y107389D01*
G02X1085393Y107588I199J-1D01*
G01X1121635D01*
G02X1121777Y107529I0J-200D01*
G01X1123191Y106115D01*
G02X1123249Y105995I-141J-142D01*
G01X1123250Y105984D01*
Y98929D01*
G02X1123182Y98779I-200J0D01*
G01X1122924Y98552D01*
X1122842Y98527D01*
X1122800Y98532D01*
G03X1122613Y98544I-189J-1490D01*
G03X1121111Y97064I0J-1502D01*
G01Y97041D01*
G03X1121249Y96413I1502J1D01*
G01Y96412D01*
G02X1121231Y96212I-181J-84D01*
G01X1121000Y95886D01*
X1120902Y95841D01*
X1120849Y95846D01*
G03X1120706Y95853I-145J-1495D01*
G03Y92849I0J-1502D01*
G03X1122208Y94329I0J1502D01*
G01Y94352D01*
G03X1122070Y94980I-1502J-1D01*
G01Y94981D01*
G02X1122088Y95181I181J84D01*
G01X1122319Y95507D01*
X1122417Y95552D01*
X1122470Y95547D01*
G03X1122613Y95540I145J1495D01*
G03X1122800Y95552I-2J1502D01*
G01X1122842Y95557D01*
X1122924Y95532D01*
X1123182Y95305D01*
G02X1123250Y95155I-132J-150D01*
G01Y94811D01*
X1123239Y94779D01*
G03X1123153Y94279I1416J-501D01*
G03X1123239Y93779I1502J1D01*
G01X1123250Y93747D01*
Y87618D01*
G02X1123127Y87433I-200J0D01*
G03Y84659I576J-1387D01*
G01X1123184Y84635D01*
X1123250Y84536D01*
Y62332D01*
X1123249Y62321D01*
X1123246Y62286D01*
X1123217Y62223D01*
X1123143Y62148D01*
X1122997Y62000D01*
G02X1122859Y61940I-143J140D01*
G01X1122854D01*
G03X1121778Y61457I28J-1502D01*
G01X1121748Y61425D01*
X1121669Y61392D01*
X1121526Y61396D01*
X1121281Y61402D01*
X1121204Y61439D01*
X1121176Y61473D01*
G03X1120021Y62015I-1155J-960D01*
G03Y59011I0J-1502D01*
G03X1121124Y59494I0J1501D01*
G01X1121154Y59526D01*
X1121233Y59559D01*
X1121376Y59555D01*
X1121621Y59549D01*
X1121698Y59512D01*
X1121726Y59478D01*
G03X1121993Y59226I1157J958D01*
G01X1122030Y59200D01*
X1122072Y59122D01*
X1122095Y58724D01*
X1122062Y58642D01*
X1122029Y58611D01*
G03X1121550Y57511I1024J-1100D01*
G03X1122975Y56011I1502J0D01*
G02X1123107Y55953I-9J-200D01*
G01X1123192Y55868D01*
G02X1123250Y55726I-142J-141D01*
G01Y54059D01*
G02X1123191Y53917I-200J0D01*
G01X1121989Y52715D01*
G02X1121847Y52656I-142J141D01*
G01X1103317D01*
G02X1103175Y52715I0J200D01*
G01X1098034Y57856D01*
G03X1097937Y57910I-142J-141D01*
G01X1097899Y57919D01*
X1097838Y57961D01*
X1097647Y58244D01*
X1097614Y58293D01*
X1097604Y58391D01*
X1097623Y58438D01*
G03X1098245Y61612I-7780J3173D01*
G01Y61733D01*
G03X1095602Y67733I-8402J-119D01*
G01X1095544Y67786D01*
X1095543Y67787D01*
G03X1089822Y70035I-5721J-6156D01*
G03X1081420Y61633I0J-8402D01*
G03X1082033Y58484I8402J1D01*
G02X1082044Y58447I-185J-75D01*
G01X1082048Y58424D01*
G02X1082018Y58275I-196J-38D01*
G01X1081978Y58215D01*
X1081835Y58003D01*
G02X1081669Y57915I-166J112D01*
G01X1074524D01*
G02X1074345Y58026I0J200D01*
G01X1074334Y58048D01*
X1074174Y58365D01*
X1074183Y58477D01*
X1074217Y58522D01*
G03X1074930Y60707I-2989J2184D01*
G01Y60731D01*
G03X1074486Y62466I-3702J-23D01*
G01X1074462Y62511D01*
Y62611D01*
X1074652Y62963D01*
X1074736Y63018D01*
X1074787Y63022D01*
G03X1077069Y69585I-319J3789D01*
G01X1077067Y69587D01*
X1077065Y69589D01*
G03X1071099Y65031I-2616J-2759D01*
G01X1071100Y65028D01*
X1071106Y65016D01*
X1071112Y65001D01*
G02X1071097Y64816I-184J-78D01*
G01X1071094Y64812D01*
X1070924Y64527D01*
G02X1070752Y64429I-172J102D01*
G01X1063908D01*
G03X1060207Y60728I0J-3701D01*
G01Y60726D01*
G03X1060915Y58551I3701J2D01*
G01X1060948Y58505D01*
X1060957Y58392D01*
X1060909Y58299D01*
X1060771Y58027D01*
G02X1060691Y57943I-179J90D01*
G01X1060687Y57941D01*
G02X1060588Y57915I-99J174D01*
G01X1023895D01*
G02X1023753Y57974I0J200D01*
G01X1022988Y58739D01*
G02X1022946Y58962I141J142D01*
G01X1023012Y59110D01*
X1023099Y59304D01*
G02X1023178Y59393I182J-82D01*
G01X1023205Y59409D01*
X1023262Y59423D01*
X1023292Y59422D01*
G03X1023373Y59420I78J1500D01*
G03Y62424I0J1502D01*
G03X1022691Y62260I0J-1502D01*
G01X1022644Y62236D01*
X1022541Y62240D01*
X1022362Y62349D01*
X1022302Y62386D01*
X1022249Y62419D01*
X1022203Y62448D01*
G02X1022109Y62617I106J170D01*
G01Y84646D01*
G02X1022195Y84810I200J0D01*
G03Y87282I-854J1236D01*
G02X1022109Y87446I114J164D01*
G01Y92579D01*
X1022226Y92696D01*
X1022277Y92747D01*
X1022343Y92777D01*
X1022381Y92780D01*
G03X1023795Y94279I-88J1499D01*
G03X1022417Y95776I-1502J0D01*
G01X1022379Y95779D01*
X1022312Y95812D01*
X1022163Y95973D01*
X1022103Y96039D01*
G02X1022050Y96174I147J136D01*
G01Y108876D01*
G02X1022163Y109057I200J1D01*
G01X1022164D01*
G03X1022709Y109498I-646J1356D01*
G01Y109499D01*
X1022719Y109512D01*
X1022740Y109533D01*
G02X1022852Y109589I141J-142D01*
G01X1023123Y109629D01*
G02X1023273Y109590I29J-198D01*
G01X1023275Y109589D01*
G03X1024186Y109281I912J1195D01*
G01X1024204D01*
G03X1025480Y110021I-19J1503D01*
G01X1025493Y110042D01*
X1025529Y110078D01*
X1025607Y110124D01*
G02X1025708Y110152I102J-172D01*
G01X1025986D01*
G02X1026159Y110052I0J-200D01*
G03X1026295Y109855I1300J752D01*
G03X1026436Y109704I1166J947D01*
G01X1026438Y109702D01*
X1026441Y109699D01*
G03X1027480Y109282I1039J1086D01*
G03X1028982Y110784I0J1502D01*
G03X1028508Y111879I-1502J0D01*
G01X1028506Y111881D01*
X1028503Y111884D01*
G03X1027460Y112305I-1043J-1081D01*
G03X1026159Y111554I0J-1502D01*
G02X1025986Y111454I-173J100D01*
G01X1025702D01*
G02X1025602Y111480I-1J200D01*
G01X1025500Y111539D01*
X1025466Y111571D01*
X1025452Y111593D01*
G03X1025333Y111754I-1265J-810D01*
G03X1025272Y111822I-1148J-969D01*
G01X1025270Y111824D01*
X1025268Y111827D01*
G03X1025255Y111840I-1068J-1055D01*
G03X1025251Y111844I-143J-139D01*
G03X1025221Y111872I-1040J-1084D01*
G02X1025220Y111874I167J85D01*
G03X1025213Y111880I-980J-1136D01*
G02X1025210Y111883I140J143D01*
G03X1024166Y112305I-1044J-1080D01*
G03X1022974Y111717I0J-1502D01*
G01X1022963Y111703D01*
X1022943Y111683D01*
G02X1022831Y111627I-141J142D01*
G01X1022555Y111586D01*
G02X1022407Y111623I-29J198D01*
G03X1022386Y111638I-883J-1215D01*
G01X1022382Y111640D01*
X1022369Y111650D01*
G03X1022359Y111657I-866J-1226D01*
G01X1022340Y111670D01*
X1022308Y111705D01*
X1022252Y111807D01*
G02X1022227Y111904I175J97D01*
G01Y111923D01*
G02X1022255Y112024I200J-1D01*
G01X1022286Y112077D01*
X1022318Y112110D01*
X1022339Y112123D01*
G03X1022580Y114475I-803J1271D01*
G02X1022578Y114477I140J142D01*
G03X1022164Y114769I-1061J-1065D01*
G01X1022111Y114794D01*
X1022050Y114891D01*
Y115107D01*
X1022113Y115205D01*
X1022166Y115230D01*
G03X1023039Y116594I-629J1364D01*
G03X1022564Y117690I-1502J0D01*
G01X1022562Y117692D01*
G03X1022440Y117798I-1045J-1079D01*
G02X1022363Y117956I123J158D01*
G01Y118236D01*
G02X1022442Y118396I200J1D01*
G03X1023029Y119418I-904J1199D01*
G01X1023036Y119478D01*
G03X1023040Y119594I-1499J110D01*
G03X1022573Y120683I-1503J0D01*
G01X1022571Y120685D01*
X1022556Y120699D01*
G03X1022164Y120969I-1038J-1087D01*
G01X1022111Y120994D01*
X1022050Y121091D01*
Y122677D01*
X1022145Y122789D01*
X1022217Y122801D01*
G03X1023473Y124283I-246J1482D01*
G03X1022999Y125378I-1502J0D01*
G01X1022997Y125380D01*
X1022995Y125382D01*
G03X1022223Y125780I-1045J-1080D01*
G01X1022215Y125781D01*
X1022197Y125786D01*
G02X1022050Y125979I53J193D01*
G01Y131938D01*
G02X1022171Y132122I200J0D01*
G01X1022564Y132291D01*
X1022681Y132270D01*
X1022725Y132228D01*
G03X1022855Y132118I1035J1091D01*
G01X1022883Y132096D01*
X1022903Y132065D01*
G02X1022930Y131999I-169J-107D01*
G01X1022993Y131711D01*
X1022983Y131641D01*
X1022966Y131609D01*
G03X1022787Y130898I1323J-711D01*
G03X1024289Y129396I1502J0D01*
G03X1025781Y130722I0J1502D01*
G01X1025787Y130776D01*
G03X1025194Y132098I-1498J122D01*
G01X1025165Y132120D01*
X1025126Y132180D01*
X1025056Y132503D01*
X1025066Y132574D01*
X1025083Y132605D01*
G03X1025188Y132850I-1323J712D01*
G01Y132851D01*
G02X1025275Y132960I190J-63D01*
G01X1025533Y133114D01*
X1025567Y133121D01*
G03X1025927Y133077I361J1458D01*
G03X1027429Y134579I0J1502D01*
G03X1026955Y135674I-1502J0D01*
G01X1026953Y135676D01*
X1026950Y135679D01*
G03X1025907Y136100I-1043J-1081D01*
G03X1024479Y135065I0J-1503D01*
G01X1024478Y135063D01*
G02X1024391Y134954I-190J62D01*
G01X1024278Y134887D01*
X1024133Y134801D01*
X1024063Y134789D01*
X1024027Y134795D01*
G03X1023761Y134819I-267J-1478D01*
G01X1023760D01*
G03X1022724Y134405I0J-1503D01*
G01X1022680Y134363D01*
X1022563Y134342D01*
X1022323Y134445D01*
X1022324Y134446D01*
X1022171Y134512D01*
G02X1022050Y134696I79J184D01*
G01Y167115D01*
X1022125Y167219D01*
X1022187Y167240D01*
G03X1023215Y168665I-474J1425D01*
G03X1022742Y169759I-1502J0D01*
G02X1022737Y169764I139J144D01*
G03X1022735Y169766I-1063J-1061D01*
G01X1022734Y169767D01*
G03X1022196Y170099I-1040J-1083D01*
G01X1022185Y170103D01*
X1022162Y170114D01*
G02X1022050Y170294I88J180D01*
G01Y171115D01*
X1022125Y171219D01*
X1022187Y171240D01*
G03X1023215Y172665I-474J1425D01*
G03X1022742Y173759I-1502J0D01*
G02X1022737Y173764I139J144D01*
G03X1022735Y173766I-1063J-1061D01*
G01X1022734Y173767D01*
G03X1022196Y174099I-1040J-1083D01*
G01X1022185Y174103D01*
X1022162Y174114D01*
G02X1022050Y174294I88J180D01*
G01Y175115D01*
X1022125Y175219D01*
X1022187Y175240D01*
G03X1023215Y176665I-474J1425D01*
G03X1022742Y177759I-1502J0D01*
G02X1022737Y177764I139J144D01*
G03X1022735Y177766I-1063J-1061D01*
G01X1022734Y177767D01*
G03X1022196Y178099I-1040J-1083D01*
G01X1022185Y178103D01*
X1022162Y178114D01*
G02X1022050Y178294I88J180D01*
G01Y179115D01*
X1022125Y179219D01*
X1022187Y179240D01*
G03X1023215Y180665I-474J1425D01*
G03X1022742Y181759I-1502J0D01*
G02X1022737Y181764I139J144D01*
G03X1022735Y181766I-1063J-1061D01*
G01X1022734Y181767D01*
G03X1022196Y182099I-1040J-1083D01*
G01X1022185Y182103D01*
X1022162Y182114D01*
G02X1022050Y182294I88J180D01*
G01Y185129D01*
G02X1022088Y185247I200J1D01*
G02X1022199Y185323I162J-118D01*
G01X1022200D01*
G03X1023328Y186778I-374J1455D01*
G03X1022855Y187872I-1502J0D01*
G01X1022853Y187874D01*
X1022850Y187877D01*
G03X1022200Y188246I-1043J-1081D01*
G01X1022198Y188247D01*
X1022193Y188249D01*
G02X1022050Y188440I57J192D01*
G01Y191115D01*
X1022125Y191219D01*
X1022187Y191240D01*
G03X1023215Y192665I-474J1425D01*
G03X1022742Y193759I-1502J0D01*
G02X1022737Y193764I139J144D01*
G03X1022735Y193766I-1063J-1061D01*
G01X1022734Y193767D01*
G03X1022196Y194099I-1040J-1083D01*
G01X1022185Y194103D01*
X1022162Y194114D01*
G02X1022050Y194294I88J180D01*
G01Y195115D01*
X1022125Y195219D01*
X1022187Y195240D01*
G03X1023215Y196665I-474J1425D01*
G03X1022742Y197759I-1502J0D01*
G02X1022737Y197764I139J144D01*
G03X1022735Y197766I-1063J-1061D01*
G01X1022734Y197767D01*
G03X1022196Y198099I-1040J-1083D01*
G01X1022185Y198103D01*
X1022162Y198114D01*
G02X1022050Y198294I88J180D01*
G01Y199305D01*
X1022127Y199410D01*
X1022191Y199430D01*
G03X1023247Y200864I-446J1434D01*
G03X1022773Y201959I-1502J0D01*
G02X1022771Y201961I140J142D01*
G03X1022188Y202312I-1046J-1078D01*
G01X1022158Y202322D01*
X1022107Y202358D01*
X1022089Y202384D01*
G02X1022050Y202502I161J119D01*
G01Y203209D01*
G02X1022111Y203353I200J0D01*
G01X1022190Y203429D01*
X1022232Y203443D01*
G03X1023247Y204864I-487J1421D01*
G03X1022773Y205959I-1502J0D01*
G02X1022771Y205961I140J142D01*
G03X1022754Y205977I-1038J-1086D01*
G02X1022692Y206122I138J145D01*
G01Y207606D01*
G02X1022757Y207754I200J1D01*
G03X1023247Y208864I-1012J1110D01*
G03X1022773Y209959I-1502J0D01*
G02X1022771Y209961I140J142D01*
G03X1022754Y209977I-1038J-1086D01*
G02X1022692Y210122I138J145D01*
G01Y211606D01*
G02X1022757Y211754I200J1D01*
G03X1023247Y212864I-1012J1110D01*
G03X1022773Y213959I-1502J0D01*
G02X1022771Y213961I140J142D01*
G03X1022754Y213977I-1038J-1086D01*
G02X1022692Y214122I138J145D01*
G01Y215606D01*
G02X1022757Y215754I200J1D01*
G03X1023247Y216864I-1012J1110D01*
G03X1022773Y217959I-1502J0D01*
G02X1022771Y217961I140J142D01*
G03X1022754Y217977I-1038J-1086D01*
G02X1022692Y218122I138J145D01*
G01Y220606D01*
G02X1022757Y220754I200J1D01*
G03X1023247Y221864I-1012J1110D01*
G03X1022773Y222959I-1502J0D01*
G02X1022771Y222961I140J142D01*
G03X1022754Y222977I-1038J-1086D01*
G02X1022692Y223122I138J145D01*
G01Y242110D01*
G02X1022750Y242251I200J0D01*
G01X1022892Y242393D01*
X1022970Y242423D01*
X1023013Y242421D01*
G03X1023077Y242420I51J1209D01*
G01X1033010D01*
G03X1033152Y242428I3J1210D01*
G01X1036315D01*
G37*
G36*
G01X1022184Y276294D02*
X1097158D01*
G02X1097300Y276235I0J-200D01*
G01X1098584Y274951D01*
G02X1098586Y274949I-140J-142D01*
G02X1098643Y274809I-143J-140D01*
G01Y267385D01*
G02X1098530Y267205I-200J0D01*
G01X1098153Y267023D01*
X1098040Y267036D01*
X1097994Y267072D01*
G03X1097060Y267398I-934J-1175D01*
G03Y264394I0J-1502D01*
G03X1097994Y264720I0J1501D01*
G01X1098040Y264756D01*
X1098153Y264769D01*
X1098530Y264587D01*
G02X1098643Y264407I-87J-180D01*
G01Y257901D01*
X1098589Y257809D01*
X1098544Y257782D01*
X1098542D01*
X1098254Y257613D01*
G02X1098180Y257588I-100J174D01*
G01X1098139Y257583D01*
X1098046Y257608D01*
X1098024Y257620D01*
G03X1097302Y257805I-723J-1319D01*
G01X1097301D01*
G03Y254801I0J-1502D01*
G01X1097302D01*
G03X1098024Y254986I-1J1504D01*
G01X1098046Y254998D01*
X1098100Y255013D01*
G02X1098180Y255018I52J-193D01*
G01X1098219Y255013D01*
X1098543Y254824D01*
G02X1098546Y254822I-109J-167D01*
G02X1098643Y254651I-103J-171D01*
G01Y207177D01*
X1098636Y207152D01*
G03X1098585Y206763I1451J-388D01*
G01Y206755D01*
G03X1098636Y206372I1502J5D01*
G01X1098643Y206346D01*
Y202582D01*
G03X1098702Y202440I200J0D01*
G01X1099123Y202019D01*
G03X1099265Y201960I142J141D01*
G01X1101983D01*
G02X1102016Y201957I-2J-200D01*
G02X1102123Y201903I-32J-197D01*
G01X1102438Y201588D01*
Y193725D01*
G02X1102352Y193561I-200J0D01*
G01X1102101Y193386D01*
G02X1101987Y193350I-114J164D01*
G01X1101900D01*
X1101869Y193361D01*
G03X1101379Y193443I-490J-1420D01*
G01X1101363D01*
G03X1099877Y191941I16J-1502D01*
G03X1101379Y190439I1502J0D01*
G01X1101382D01*
G03X1101900Y190532I-2J1502D01*
G01X1101946Y190549D01*
X1102043Y190537D01*
X1102352Y190321D01*
G02X1102438Y190157I-114J-164D01*
G01Y165175D01*
G02X1102379Y165034I-200J1D01*
G01X1098912Y161567D01*
X1098884Y161538D01*
X1098810Y161508D01*
X1091796D01*
G02X1091625Y161604I0J200D01*
G01X1091448Y161896D01*
G02X1091432Y161930I172J102D01*
G02X1091443Y162094I188J70D01*
G01X1091446Y162100D01*
X1091463Y162135D01*
G03X1091615Y162788I-1350J658D01*
G01Y162790D01*
Y162815D01*
G03X1091212Y163817I-1502J-22D01*
G01X1091211Y163818D01*
G02X1091155Y163957I144J139D01*
G01Y164268D01*
X1091182Y164338D01*
X1091209Y164366D01*
G03Y166420I-1096J1027D01*
G01X1091182Y166448D01*
X1091155Y166518D01*
Y166868D01*
X1091182Y166938D01*
X1091209Y166966D01*
G03X1091615Y167993I-1096J1027D01*
G03X1091245Y168980I-1501J0D01*
G01X1091221Y169008D01*
X1091196Y169074D01*
Y169412D01*
X1091221Y169478D01*
X1091245Y169506D01*
G03X1091615Y170493I-1131J987D01*
G03X1088611I-1502J0D01*
G03X1088981Y169506I1501J0D01*
G01X1089005Y169478D01*
X1089030Y169412D01*
Y169074D01*
X1089005Y169008D01*
X1088981Y168980D01*
G03X1088611Y167993I1131J-987D01*
G03X1089017Y166966I1502J0D01*
G01X1089044Y166938D01*
X1089071Y166868D01*
Y166518D01*
X1089044Y166448D01*
X1089017Y166420D01*
G03Y164366I1096J-1027D01*
G01X1089044Y164338D01*
X1089071Y164268D01*
Y163918D01*
X1089044Y163849D01*
X1089017Y163820D01*
G03X1088611Y162821I1096J-1027D01*
G01Y162793D01*
G03X1088763Y162134I1502J-1D01*
G01X1088792Y162073D01*
G02X1088794Y161930I-186J-74D01*
G02X1088778Y161896I-188J68D01*
G01X1088601Y161605D01*
X1088574Y161559D01*
X1088483Y161508D01*
X1084859D01*
G02X1084701Y161585I0J200D01*
G01X1084478Y161870D01*
X1084459Y161959D01*
X1084470Y162005D01*
G03X1084515Y162368I-1457J365D01*
G03X1083013Y163870I-1502J0D01*
G03X1081986Y163464I0J-1502D01*
G01X1081958Y163437D01*
X1081888Y163410D01*
X1081538D01*
X1081468Y163437D01*
X1081440Y163464D01*
G03X1080413Y163870I-1027J-1096D01*
G03X1078911Y162368I0J-1502D01*
G03X1078956Y162005I1502J2D01*
G01X1078967Y161959D01*
X1078948Y161870D01*
X1078725Y161585D01*
G02X1078567Y161508I-158J123D01*
G01X1063419D01*
G02X1063277Y161567I0J200D01*
G01X1062621Y162223D01*
G02X1062563Y162364I142J141D01*
G01Y240157D01*
G03X1062504Y240298I-200J-1D01*
G01X1059450Y243352D01*
G03X1059310Y243410I-141J-142D01*
G01X1059090D01*
X1059074Y243413D01*
G03X1058833Y243428I-195J-1186D01*
G01X1052281D01*
G02X1052210Y243441I0J200D01*
G01X1052173Y243455D01*
X1052145Y243481D01*
G02X1052122Y243506I135J147D01*
G01X1051900Y243792D01*
X1051881Y243882D01*
X1051893Y243927D01*
G03X1051939Y244288I-1456J369D01*
G01Y244308D01*
G03X1050437Y245799I-1502J-11D01*
G03X1050070Y245753I2J-1502D01*
G01X1050014Y245739D01*
X1049907Y245773D01*
X1049599Y246131D01*
X1049581Y246242D01*
X1049603Y246295D01*
G03X1049719Y246874I-1387J579D01*
G03X1048217Y248376I-1502J0D01*
G03X1047188Y247968I0J-1502D01*
G01X1047154Y247936D01*
X1047068Y247909D01*
X1046714Y247958D01*
G02X1046706Y247959I21J199D01*
G02X1046569Y248055I36J197D01*
G03X1045275Y248794I-1294J-763D01*
G03Y245790I0J-1502D01*
G03X1046304Y246198I0J1502D01*
G01X1046338Y246230D01*
X1046424Y246257D01*
X1046824Y246201D01*
X1046899Y246151D01*
X1046923Y246111D01*
G03X1048217Y245372I1294J763D01*
G03X1048296Y245374I1J1502D01*
G01X1048297D01*
G03X1048359Y245378I-66J1501D01*
G01X1048393Y245382D01*
G03X1048475Y245394I-176J1492D01*
G01X1048476D01*
G03X1048584Y245418I-272J1477D01*
G01X1048640Y245432D01*
X1048747Y245398D01*
X1049055Y245040D01*
X1049073Y244929D01*
X1049051Y244876D01*
G03X1048935Y244308I1387J-579D01*
G01Y244296D01*
G03X1048980Y243930I1502J-1D01*
G01X1048981Y243929D01*
G02X1048945Y243755I-193J-51D01*
G01X1048752Y243506D01*
G02X1048729Y243481I-158J122D01*
G01X1048701Y243455D01*
X1048664Y243441D01*
G02X1048593Y243428I-71J187D01*
G01X1044740D01*
G03X1044546Y243413I-5J-1201D01*
G01X1044530Y243410D01*
X1043578D01*
X1043532Y243422D01*
X1043513Y243431D01*
X1043511Y243432D01*
G03X1043269Y243523I-648J-1355D01*
G03X1042609Y243559I-410J-1445D01*
G03X1042205Y243430I250J-1481D01*
G01X1042185Y243420D01*
X1042141Y243410D01*
X1041150D01*
X1041134Y243413D01*
G03X1040940Y243428I-189J-1186D01*
G01X1036473D01*
G02X1036350Y243470I0J200D01*
G01X1036323Y243491D01*
X1036134Y243781D01*
X1036106Y243824D01*
X1036102Y243875D01*
X1036098Y243924D01*
X1036121Y243977D01*
G03X1036243Y244571I-1380J593D01*
G01Y244590D01*
G03X1033239I-1502J-19D01*
G01Y244570D01*
G03X1033364Y243971I1502J1D01*
G01X1033380Y243934D01*
X1033382Y243855D01*
X1033367Y243818D01*
G02X1033348Y243781I-186J72D01*
G01X1033177Y243520D01*
G02X1033010Y243430I-167J110D01*
G01X1023080D01*
G02X1022939Y243488I0J200D01*
G01X1021349Y245078D01*
X1021320Y245106D01*
X1021290Y245180D01*
Y275400D01*
G02X1021347Y275540I200J0D01*
G01X1021348Y275541D01*
X1022042Y276235D01*
G02X1022044Y276237I142J-140D01*
G02X1022184Y276294I140J-143D01*
G37*
G36*
G01X1117048Y202336D02*
X1120560D01*
G02X1120701Y202278I0J-200D01*
G01X1122741Y200238D01*
X1122756Y200207D01*
G03X1122795Y200132I1352J655D01*
G01X1122796Y200131D01*
G03X1122811Y200105I1308J738D01*
G01X1122824Y200083D01*
X1122840Y200027D01*
X1122853Y199981D01*
Y197600D01*
G02X1122820Y197490I-200J0D01*
G03Y195840I1254J-825D01*
G02X1122853Y195730I-167J-110D01*
G01Y193600D01*
G02X1122820Y193490I-200J0D01*
G03Y191840I1254J-825D01*
G02X1122853Y191730I-167J-110D01*
G01Y187518D01*
X1122843Y187475D01*
X1122832Y187453D01*
G03Y186103I1355J-675D01*
G01X1122843Y186081D01*
X1122853Y186038D01*
Y181600D01*
G02X1122820Y181490I-200J0D01*
G03Y179840I1254J-825D01*
G02X1122853Y179730I-167J-110D01*
G01Y177600D01*
G02X1122820Y177490I-200J0D01*
G03Y175840I1254J-825D01*
G02X1122853Y175730I-167J-110D01*
G01Y173600D01*
G02X1122820Y173490I-200J0D01*
G03Y171840I1254J-825D01*
G02X1122853Y171730I-167J-110D01*
G01Y169600D01*
G02X1122820Y169490I-200J0D01*
G03Y167840I1254J-825D01*
G02X1122853Y167730I-167J-110D01*
G01Y163086D01*
G02X1122798Y162947I-200J-1D01*
G01X1122716Y162862D01*
X1122683Y162846D01*
X1122591Y162801D01*
X1122558Y162797D01*
G03Y159815I182J-1491D01*
G01X1122591Y159811D01*
X1122684Y159766D01*
G02X1122741Y159724I-88J-180D01*
G01X1122798Y159665D01*
G02X1122853Y159526I-145J-138D01*
G01Y151308D01*
G02X1122653Y151108I-200J0D01*
G01X1116079D01*
G02X1115903Y151213I0J200D01*
G01X1115737Y151523D01*
G02X1115713Y151625I176J95D01*
G01X1115715Y151682D01*
X1115746Y151729D01*
G03X1115998Y152562I-1251J833D01*
G03X1114496Y154064I-1502J0D01*
G03X1113202Y153325I0J-1502D01*
G01X1113176Y153281D01*
X1113091Y153229D01*
X1112913Y153219D01*
X1112660Y153204D01*
X1112570Y153245D01*
X1112540Y153285D01*
G03X1111346Y153875I-1194J-913D01*
G03X1109844Y152373I0J-1502D01*
G03X1110009Y151689I1502J0D01*
G01X1110033Y151642D01*
X1110029Y151539D01*
X1109823Y151203D01*
G02X1109653Y151108I-170J105D01*
G01X1100335D01*
G02X1100207Y151155I1J200D01*
G01X1099374Y151988D01*
X1099069Y152292D01*
G03X1097654Y152878I-1415J-1415D01*
G01X1091294D01*
G03X1089879Y152292I0J-2001D01*
G01X1086542Y148955D01*
G03X1085956Y147540I1415J-1415D01*
G03X1085964Y147354I2001J-7D01*
G01X1085965Y147345D01*
Y147340D01*
G03X1087952Y145538I1992J200D01*
G01X1087957D01*
G03X1088459Y145602I0J2002D01*
G03X1089372Y146125I-503J1937D01*
G01X1092064Y148817D01*
G02X1092206Y148876I142J-141D01*
G01X1094684D01*
G02X1094833Y148809I0J-200D01*
G01X1095032Y148588D01*
G02X1095082Y148437I-149J-133D01*
G01Y148434D01*
G03X1095074Y148277I1494J-155D01*
G03X1096576Y146775I1502J0D01*
G03X1097765Y147359I0J1502D01*
G01X1097789Y147390D01*
X1097822Y147410D01*
G02X1097892Y147435I101J-173D01*
G01X1098161Y147479D01*
G02X1098305Y147447I32J-198D01*
G01X1098306Y147446D01*
G03X1098770Y147214I1120J1659D01*
G03X1099425Y147104I654J1892D01*
G01X1122653D01*
G02X1122853Y146904I0J-200D01*
G01Y124540D01*
X1122850Y124524D01*
G03X1122831Y124283I1483J-238D01*
G03X1122850Y124042I1502J-3D01*
G01X1122853Y124026D01*
Y120792D01*
G02X1122839Y120718I-200J0D01*
G01X1122801Y120621D01*
X1122777Y120594D01*
G03Y118594I1122J-1000D01*
G01X1122801Y118567D01*
X1122839Y118470D01*
G02X1122853Y118396I-186J-74D01*
G01Y117752D01*
X1122799Y117618D01*
X1122776Y117592D01*
G03X1122397Y116594I1124J-998D01*
G01Y116592D01*
G03X1122701Y115687I1503J1D01*
G02X1122741Y115567I-160J-120D01*
G01Y114421D01*
G02X1122701Y114301I-200J0D01*
G03Y112487I1199J-907D01*
G02X1122741Y112367I-160J-120D01*
G01Y111688D01*
G03X1122771Y111583I200J0D01*
G01X1122822Y111504D01*
G02X1122853Y111396I-169J-107D01*
G01Y109734D01*
G02X1122794Y109592I-200J0D01*
G01X1121851Y108649D01*
G02X1121709Y108590I-142J141D01*
G01X1085037D01*
G02X1084873Y108676I0J200D01*
G03X1081909I-1482J-1027D01*
G02X1081745Y108590I-164J114D01*
G01X1065464D01*
G02X1065322Y108649I0J200D01*
G01X1064263Y109708D01*
X1064238Y109753D01*
X1064231Y109780D01*
G03X1063145Y110866I-1456J-370D01*
G01X1063118Y110873D01*
X1063073Y110898D01*
X1063011Y110960D01*
G02X1062952Y111102I141J142D01*
G01Y114907D01*
X1063039Y115016D01*
X1063108Y115031D01*
G03Y117961I-333J1465D01*
G01X1063039Y117976D01*
X1062952Y118085D01*
Y122963D01*
X1063052Y123076D01*
X1063128Y123085D01*
G03Y126067I-181J1491D01*
G01X1063052Y126076D01*
X1062952Y126189D01*
Y159263D01*
G02X1063011Y159405I200J0D01*
G01X1063874Y160268D01*
G02X1064016Y160327I142J-141D01*
G01X1099533D01*
G03X1099675Y160386I0J200D01*
G01X1103380Y164091D01*
G03X1103439Y164233I-141J142D01*
G01Y201567D01*
G02X1103498Y201709I200J0D01*
G01X1104066Y202277D01*
G02X1104208Y202336I142J-141D01*
G01X1113908D01*
G02X1114085Y202229I0J-200D01*
G01X1114249Y201916D01*
G02X1114238Y201711I-177J-93D01*
G01X1114237Y201710D01*
G03X1113976Y200873I1241J-846D01*
G01Y200845D01*
G03X1116980I1502J19D01*
G01Y200865D01*
G03X1116719Y201711I-1502J0D01*
G01X1116687Y201757D01*
X1116681Y201867D01*
X1116871Y202229D01*
G02X1117048Y202336I177J-93D01*
G37*
G36*
G01X1154193Y54588D02*
X1182695D01*
X1183133Y54150D01*
Y53029D01*
X1182695Y52591D01*
X1154193D01*
G03X1148256Y46654I0J-5937D01*
G01Y7874D01*
G02X1142382Y2000I-5874J0D01*
G01X1095138D01*
G02X1089264Y7874I0J5874D01*
G01Y46558D01*
X1091262D01*
Y7874D01*
G03X1095138Y3998I3876J0D01*
G01X1142382D01*
G03X1146258Y7874I0J3876D01*
G01Y46654D01*
G02X1154193Y54588I7935J-1D01*
G37*
G36*
G01X1099845Y275932D02*
X1121780D01*
X1121854Y275902D01*
X1121882Y275873D01*
X1122493Y275262D01*
G02X1122552Y275120I-141J-142D01*
G01Y205020D01*
X1122522Y204946D01*
X1122493Y204918D01*
X1120972Y203397D01*
G02X1120830Y203338I-142J141D01*
G01X1099963D01*
X1099889Y203368D01*
X1099861Y203397D01*
X1099703Y203555D01*
G02X1099645Y203696I142J141D01*
G01Y204858D01*
G02X1099705Y205001I200J0D01*
G01X1099939Y205230D01*
X1100013Y205259D01*
X1100053Y205258D01*
X1100087D01*
G03Y208262I0J1502D01*
G01X1100053D01*
X1100013Y208261D01*
X1099939Y208290D01*
X1099705Y208519D01*
G02X1099645Y208661I140J143D01*
G01Y255107D01*
G02X1099763Y255289I200J0D01*
G01X1100087Y255436D01*
G02X1100258Y255432I81J-183D01*
G01X1100308Y255407D01*
X1100327Y255392D01*
G03X1101301Y255033I975J1143D01*
G03Y258037I0J1502D01*
G03X1100327Y257678I1J-1502D01*
G01X1100308Y257663D01*
X1100258Y257638D01*
G02X1100087Y257634I-90J179D01*
G01X1099763Y257781D01*
G02X1099645Y257963I82J182D01*
G01Y275732D01*
G02X1099845Y275932I200J0D01*
G37*
G36*
G01X1135374Y242420D02*
G03X1135511Y242428I-2J1210D01*
G01X1135523Y242429D01*
X1138684D01*
X1138696Y242428D01*
G03X1138832Y242420I139J1202D01*
G01X1143296D01*
G02X1143332Y242417I1J-200D01*
G01X1143349Y242414D01*
G02X1143452Y242361I-36J-197D01*
G01X1143641Y242180D01*
G02X1143702Y242046I-139J-144D01*
G01Y242042D01*
G03X1144102Y241077I1501J57D01*
G01X1144104Y241075D01*
X1144107Y241072D01*
G03X1144113Y241065I1143J974D01*
G01X1144115Y241063D01*
X1144120Y241057D01*
G03X1145222Y240576I1102J1022D01*
G03X1146724Y242057I0J1502D01*
G01X1146725Y242098D01*
X1146756Y242170D01*
X1146930Y242338D01*
X1146953Y242360D01*
G02X1147057Y242414I140J-143D01*
G01X1147092Y242420D01*
X1150957D01*
G03X1151098Y242428I2J1210D01*
G01X1154500D01*
G03X1154641Y242420I139J1202D01*
G01X1161233D01*
G02X1161328Y242396I0J-200D01*
G01X1161354Y242382D01*
X1163828Y239908D01*
X1163840Y239895D01*
X1163881Y239854D01*
G02X1163904Y239762I-177J-93D01*
G01Y153175D01*
G02X1163901Y153139I-200J-1D01*
G01X1163890Y153081D01*
X1163857Y153023D01*
X1163831Y153000D01*
G03X1163527Y147733I2440J-2783D01*
G01X1163545Y147713D01*
X1163546Y147711D01*
G03X1163736Y147517I2738J2492D01*
G03X1163789Y147469I2511J2719D01*
G01X1163790Y147468D01*
G03X1163807Y147452I2545J2687D01*
G01X1163823Y147437D01*
X1163847Y147404D01*
X1163887Y147312D01*
G02X1163904Y147232I-183J-81D01*
G01Y125108D01*
X1163893Y125076D01*
G03X1163807Y124576I1416J-501D01*
G03X1163893Y124076I1502J1D01*
G01X1163904Y124044D01*
Y122986D01*
G03X1163919Y122910I200J0D01*
G01X1163939Y122863D01*
G02X1163954Y122786I-185J-76D01*
G01Y117488D01*
G02X1163917Y117371I-200J-1D01*
G03X1163635Y116496I1220J-876D01*
G03X1163917Y115621I1502J1D01*
G02X1163954Y115504I-163J-116D01*
G01Y110681D01*
G03X1163967Y110611I200J1D01*
G02X1163979Y110527I-188J-70D01*
G01X1163970Y110411D01*
G02X1163931Y110306I-199J14D01*
G03X1163635Y109410I1206J-895D01*
G03X1165137Y107908I1502J0D01*
G03X1166069Y108232I0J1502D01*
G01X1166130Y108280D01*
X1166280Y108272D01*
X1166884Y107668D01*
G03X1167026Y107609I142J141D01*
G01X1167602D01*
X1167619Y107606D01*
G03X1167699Y107595I204J1184D01*
G01X1167700D01*
G03X1167824Y107588I130J1195D01*
G01X1183751D01*
G02X1183950Y107389I0J-200D01*
G01Y104249D01*
G03X1183968Y103999I1803J4D01*
G01Y103997D01*
G03X1183972Y103974I1777J297D01*
G01Y103972D01*
G03X1183982Y103915I1780J283D01*
G01X1183987Y103886D01*
X1183981Y103829D01*
X1183970Y103802D01*
G02X1183899Y103713I-185J75D01*
G01X1183869Y103692D01*
X1183766Y103620D01*
G03X1182976Y103845I-790J-1274D01*
G03X1181474Y102343I0J-1502D01*
G03X1181895Y101300I1502J0D01*
G01X1181898Y101297D01*
X1181900Y101295D01*
G03X1182995Y100821I1095J1028D01*
G03X1184495Y102242I0J1502D01*
G01Y102244D01*
G02X1184589Y102402I200J-12D01*
G01X1184728Y102488D01*
X1184908Y102600D01*
X1185005Y102608D01*
X1185050Y102589D01*
G03X1185744Y102446I704J1660D01*
G01X1185753D01*
G03X1187556Y104249I0J1803D01*
G01Y107389D01*
G02X1187755Y107588I200J-1D01*
G01X1223999D01*
G02X1224139Y107531I0J-200D01*
G01X1224140Y107530D01*
X1225554Y106116D01*
G02X1225613Y105974I-141J-142D01*
G01Y98974D01*
G02X1225548Y98827I-200J1D01*
G01X1225299Y98599D01*
X1225219Y98572D01*
X1225177Y98576D01*
G03X1225041Y98582I-134J-1496D01*
G03X1223539Y97080I0J-1502D01*
G03X1223696Y96412I1502J1D01*
G01X1223721Y96362D01*
X1223712Y96251D01*
X1223439Y95873D01*
X1223336Y95830D01*
X1223281Y95838D01*
G03X1223068Y95853I-212J-1487D01*
G03X1224570Y94351I0J-1502D01*
G03X1224413Y95019I-1502J-1D01*
G01X1224388Y95069D01*
X1224397Y95180D01*
X1224670Y95558D01*
X1224773Y95601D01*
X1224828Y95593D01*
G03X1225041Y95578I212J1487D01*
G03X1225177Y95584I2J1502D01*
G01X1225219Y95588D01*
X1225299Y95561D01*
X1225548Y95333D01*
G02X1225613Y95186I-135J-148D01*
G01Y94814D01*
X1225601Y94781D01*
G03X1225528Y94080I1416J-502D01*
G03X1225553Y93938I1490J189D01*
G01X1225554Y93937D01*
G03X1225601Y93777I1463J343D01*
G01X1225613Y93744D01*
Y87557D01*
X1225546Y87457D01*
X1225490Y87433D01*
G03Y84659I574J-1387D01*
G01X1225546Y84635D01*
X1225613Y84535D01*
Y62345D01*
Y62331D01*
X1225606Y62237D01*
X1225497Y62139D01*
G03X1225489Y62131I137J-145D01*
G01X1225330Y61971D01*
X1225259Y61941D01*
X1225219Y61940D01*
G03X1224140Y61457I25J-1502D01*
G01X1224110Y61425D01*
X1224031Y61392D01*
X1223643Y61402D01*
X1223566Y61439D01*
X1223538Y61473D01*
G03X1222383Y62015I-1155J-960D01*
G03Y59011I0J-1502D01*
G03X1223486Y59494I0J1501D01*
G01X1223516Y59526D01*
X1223595Y59559D01*
X1223983Y59549D01*
X1224060Y59512D01*
X1224088Y59478D01*
G03X1225219Y58936I1155J960D01*
G01X1225258D01*
X1225331Y58905D01*
X1225506Y58728D01*
X1225555Y58678D01*
G02X1225612Y58552I-142J-140D01*
G01X1225613Y58538D01*
Y54060D01*
G02X1225554Y53918I-200J0D01*
G01X1224352Y52716D01*
G02X1224210Y52657I-142J141D01*
G01X1205680D01*
G02X1205538Y52716I0J200D01*
G01X1200397Y57857D01*
G03X1200300Y57911I-142J-141D01*
G01X1200262Y57920D01*
X1200201Y57962D01*
X1199976Y58296D01*
X1199966Y58394D01*
X1199985Y58441D01*
G03X1200606Y61459I-7780J3174D01*
G03X1200607Y61610I-8401J131D01*
G01Y61614D01*
G03X1198106Y67595I-8402J0D01*
G03X1192185Y70036I-5921J-5961D01*
G03X1183783Y61634I0J-8402D01*
G03X1184396Y58485I8402J1D01*
G01X1184403Y58467D01*
X1184411Y58425D01*
G02X1184381Y58275I-196J-39D01*
G01X1184198Y58004D01*
G02X1184032Y57916I-166J112D01*
G01X1176887D01*
G02X1176709Y58026I1J200D01*
G01X1176536Y58367D01*
X1176545Y58479D01*
X1176578Y58525D01*
G03X1177287Y60519I-2988J2185D01*
G01X1177290Y60588D01*
G03X1177268Y61129I-3700J121D01*
G03X1177189Y61575I-3678J-421D01*
G03X1177155Y61706I-3599J-864D01*
G01Y61707D01*
X1177150Y61723D01*
G03X1176848Y62466I-3560J-1014D01*
G01X1176824Y62511D01*
Y62611D01*
X1177014Y62963D01*
X1177098Y63018D01*
X1177149Y63022D01*
G03X1179562Y69456I-319J3789D01*
G01X1179561Y69457D01*
G03X1175342Y70338I-2750J-2626D01*
G03X1173462Y65032I1469J-3507D01*
G01X1173463Y65029D01*
X1173469Y65017D01*
X1173475Y65003D01*
G02X1173460Y64817I-184J-79D01*
G01X1173457Y64813D01*
X1173287Y64528D01*
G02X1173115Y64430I-172J102D01*
G01X1166271D01*
G03X1162570Y60729I0J-3701D01*
G01Y60727D01*
G03X1163278Y58552I3701J2D01*
G01X1163311Y58506D01*
X1163320Y58393D01*
X1163272Y58300D01*
X1163134Y58027D01*
G02X1163052Y57943I-178J92D01*
G01X1163050Y57941D01*
G02X1162952Y57916I-97J175D01*
G01X1126258D01*
G02X1126116Y57975I0J200D01*
G01X1125351Y58740D01*
G02X1125310Y58962I142J141D01*
G01Y58963D01*
X1125460Y59302D01*
G02X1125541Y59393I183J-81D01*
G01X1125569Y59410D01*
X1125625Y59424D01*
X1125654Y59422D01*
X1125660D01*
G03X1125735Y59420I78J1500D01*
G03Y62424I0J1502D01*
G03X1125053Y62260I0J-1502D01*
G01X1125006Y62236D01*
X1124903Y62240D01*
X1124567Y62446D01*
G02X1124472Y62616I105J170D01*
G01Y84598D01*
G02X1124495Y84691I200J0D01*
G01X1124547Y84790D01*
X1124576Y84824D01*
X1124594Y84837D01*
G03Y87255I-891J1209D01*
G01X1124576Y87268D01*
X1124547Y87302D01*
X1124495Y87401D01*
G02X1124472Y87494I177J93D01*
G01Y92536D01*
X1124502Y92607D01*
X1124530Y92636D01*
X1124640Y92747D01*
X1124706Y92777D01*
X1124744Y92780D01*
G03X1126157Y94279I-89J1499D01*
G01X1126158D01*
G03X1124786Y95776I-1503J0D01*
G01X1124742Y95779D01*
X1124705Y95798D01*
G02X1124650Y95840I92J178D01*
G01X1124466Y96039D01*
G02X1124413Y96175I147J136D01*
G01Y108877D01*
G02X1124526Y109058I200J1D01*
G01X1124527D01*
G03X1125072Y109500I-648J1355D01*
G01X1125081Y109512D01*
X1125091Y109522D01*
X1125103Y109534D01*
G02X1125215Y109590I141J-142D01*
G01X1125259Y109597D01*
X1125526Y109636D01*
X1125603Y109616D01*
X1125635Y109591D01*
G03X1126548Y109282I913J1194D01*
G03X1127835Y110009I0J1503D01*
G01X1127849Y110031D01*
X1127883Y110066D01*
X1127985Y110125D01*
G02X1128025Y110143I101J-172D01*
G02X1128062Y110152I66J-189D01*
G02X1128086Y110153I20J-199D01*
G01X1128297D01*
G02X1128394Y110128I0J-200D01*
G01X1128495Y110072D01*
X1128531Y110037D01*
X1128545Y110015D01*
G03X1128744Y109759I1279J789D01*
G01X1128746Y109757D01*
X1128748Y109755D01*
G03X1129842Y109282I1094J1029D01*
G03X1131344Y110784I0J1502D01*
G03X1130923Y111827I-1502J0D01*
G01X1130920Y111830D01*
X1130913Y111837D01*
G03X1129823Y112306I-1090J-1032D01*
G03X1128522Y111555I0J-1502D01*
G02X1128349Y111455I-173J100D01*
G01X1128010D01*
G02X1127838Y111553I0J200D01*
G03X1127642Y111813I-1290J-769D01*
G01X1127639Y111816D01*
X1127635Y111821D01*
G03X1127632Y111824I-1064J-1061D01*
G01X1127631Y111825D01*
G03X1126529Y112306I-1102J-1022D01*
G03X1125337Y111718I0J-1502D01*
G01X1125328Y111706D01*
X1125318Y111696D01*
X1125306Y111684D01*
G02X1125194Y111628I-141J142D01*
G01X1124918Y111587D01*
G02X1124769Y111624I-30J198D01*
G03X1124722Y111658I-904J-1200D01*
G01X1124703Y111671D01*
X1124671Y111706D01*
X1124615Y111807D01*
G02X1124590Y111904I175J97D01*
G01Y111924D01*
G02X1124615Y112021I200J0D01*
G01X1124632Y112051D01*
G02X1124698Y112122I175J-97D01*
G01X1124700Y112123D01*
X1124701D01*
G03X1125401Y113394I-804J1271D01*
G03X1124996Y114420I-1502J0D01*
G01X1124994Y114422D01*
X1124991Y114426D01*
G03X1124986Y114431I-1065J-1060D01*
G03X1124984Y114433I-142J-140D01*
G03X1124527Y114770I-1104J-1019D01*
G01X1124474Y114795D01*
X1124413Y114892D01*
Y115049D01*
G02X1124529Y115231I200J0D01*
G03X1125401Y116594I-629J1363D01*
G03X1124981Y117636I-1503J0D01*
G01X1124979Y117638D01*
X1124977Y117640D01*
G03X1124803Y117799I-1097J-1026D01*
G02X1124726Y117957I123J158D01*
G01Y118190D01*
G02X1124747Y118278I200J-1D01*
G01X1124794Y118374D01*
X1124821Y118408D01*
X1124838Y118421D01*
G03X1125401Y119594I-940J1173D01*
G03X1124996Y120620I-1502J0D01*
G01X1124994Y120622D01*
X1124991Y120626D01*
G03X1124986Y120631I-1065J-1060D01*
G03X1124984Y120633I-142J-140D01*
G03X1124527Y120970I-1104J-1019D01*
G01X1124474Y120995D01*
X1124413Y121092D01*
Y122677D01*
X1124508Y122789D01*
X1124580Y122801D01*
G03X1125419Y125321I-247J1482D01*
G01X1125417Y125323D01*
X1125415Y125326D01*
G03X1124578Y125782I-1100J-1023D01*
G01X1124506Y125795D01*
X1124413Y125905D01*
Y131939D01*
G02X1124524Y132118I200J0D01*
G01X1124529Y132121D01*
X1124869Y132267D01*
G02X1124987Y132280I80J-183D01*
G01X1125018Y132274D01*
X1125069Y132247D01*
X1125090Y132226D01*
G03X1126142Y131796I1052J1072D01*
G03X1127580Y132865I0J1502D01*
G01X1127591Y132901D01*
X1127636Y132959D01*
X1127896Y133115D01*
X1127928Y133121D01*
G03X1128289Y133077I361J1459D01*
G03X1129791Y134579I0J1502D01*
G03X1129370Y135622I-1502J0D01*
G01X1129367Y135625D01*
X1129360Y135632D01*
G03X1128270Y136101I-1090J-1032D01*
G03X1126842Y135066I0J-1503D01*
G01X1126841Y135064D01*
G02X1126754Y134955I-190J62D01*
G01X1126497Y134802D01*
X1126427Y134789D01*
X1126391Y134796D01*
G03X1126124Y134820I-267J-1478D01*
G01X1126123D01*
G03X1125088Y134407I0J-1503D01*
G01X1125044Y134366D01*
X1124927Y134345D01*
X1124534Y134513D01*
G02X1124413Y134697I79J184D01*
G01Y167050D01*
G02X1124449Y167163I200J-1D01*
G01Y167164D01*
G02X1124548Y167239I164J-114D01*
G01X1124550Y167240D01*
G03X1125577Y168665I-475J1425D01*
G03X1125154Y169710I-1502J0D01*
G01X1125151Y169713D01*
X1125149Y169715D01*
G03X1124559Y170100I-1093J-1030D01*
G01X1124548Y170104D01*
X1124524Y170116D01*
G02X1124413Y170295I89J179D01*
G01Y171050D01*
G02X1124449Y171163I200J-1D01*
G01Y171164D01*
G02X1124548Y171239I164J-114D01*
G01X1124550Y171240D01*
G03X1125577Y172665I-475J1425D01*
G03X1125154Y173710I-1502J0D01*
G01X1125151Y173713D01*
X1125149Y173715D01*
G03X1124559Y174100I-1093J-1030D01*
G01X1124548Y174104D01*
X1124524Y174116D01*
G02X1124413Y174295I89J179D01*
G01Y175050D01*
G02X1124449Y175163I200J-1D01*
G01Y175164D01*
G02X1124548Y175239I164J-114D01*
G01X1124550Y175240D01*
G03X1125577Y176665I-475J1425D01*
G03X1125154Y177710I-1502J0D01*
G01X1125151Y177713D01*
X1125149Y177715D01*
G03X1124559Y178100I-1093J-1030D01*
G01X1124548Y178104D01*
X1124524Y178116D01*
G02X1124413Y178295I89J179D01*
G01Y179050D01*
G02X1124449Y179163I200J-1D01*
G01Y179164D01*
G02X1124548Y179239I164J-114D01*
G01X1124550Y179240D01*
G03X1125577Y180665I-475J1425D01*
G03X1125154Y181710I-1502J0D01*
G01X1125151Y181713D01*
X1125149Y181715D01*
G03X1124559Y182100I-1093J-1030D01*
G01X1124548Y182104D01*
X1124524Y182116D01*
G02X1124413Y182295I89J179D01*
G01Y185199D01*
X1124496Y185306D01*
X1124563Y185324D01*
G03X1125690Y186778I-374J1454D01*
G03X1125677Y186978I-1502J3D01*
G01X1125676Y186988D01*
G03X1125269Y187821I-1488J-211D01*
G01X1125267Y187823D01*
X1125260Y187831D01*
G03X1124563Y188247I-1090J-1034D01*
G01X1124561Y188248D01*
X1124556Y188250D01*
G02X1124413Y188441I57J192D01*
G01Y191050D01*
G02X1124449Y191163I200J-1D01*
G01Y191164D01*
G02X1124548Y191239I164J-114D01*
G01X1124550Y191240D01*
G03X1125577Y192665I-475J1425D01*
G03X1125154Y193710I-1502J0D01*
G01X1125151Y193713D01*
X1125149Y193715D01*
G03X1124559Y194100I-1093J-1030D01*
G01X1124548Y194104D01*
X1124524Y194116D01*
G02X1124413Y194295I89J179D01*
G01Y195050D01*
G02X1124449Y195163I200J-1D01*
G01Y195164D01*
G02X1124548Y195239I164J-114D01*
G01X1124550Y195240D01*
G03X1125577Y196665I-475J1425D01*
G03X1125154Y197710I-1502J0D01*
G01X1125151Y197713D01*
X1125149Y197715D01*
G03X1124559Y198100I-1093J-1030D01*
G01X1124548Y198104D01*
X1124524Y198116D01*
G02X1124413Y198295I89J179D01*
G01Y199305D01*
X1124490Y199410D01*
X1124554Y199430D01*
G03X1125609Y200864I-447J1434D01*
G03X1125190Y201905I-1503J0D01*
G01X1125187Y201908D01*
X1125185Y201910D01*
G03X1124551Y202313I-1097J-1026D01*
G01X1124521Y202323D01*
X1124470Y202359D01*
X1124452Y202385D01*
G02X1124413Y202503I161J119D01*
G01Y203305D01*
X1124490Y203410D01*
X1124554Y203430D01*
G03X1125609Y204864I-447J1434D01*
G03X1125190Y205905I-1503J0D01*
G01X1125187Y205908D01*
X1125185Y205910D01*
G03X1124551Y206313I-1097J-1026D01*
G01X1124521Y206323D01*
X1124470Y206359D01*
X1124452Y206385D01*
G02X1124413Y206503I161J119D01*
G01Y207305D01*
X1124490Y207410D01*
X1124554Y207430D01*
G03X1125609Y208864I-447J1434D01*
G03X1125190Y209905I-1503J0D01*
G01X1125187Y209908D01*
X1125185Y209910D01*
G03X1124551Y210313I-1097J-1026D01*
G01X1124521Y210323D01*
X1124470Y210359D01*
X1124452Y210385D01*
G02X1124413Y210503I161J119D01*
G01Y211305D01*
X1124490Y211410D01*
X1124554Y211430D01*
G03X1125609Y212864I-447J1434D01*
G03X1125190Y213905I-1503J0D01*
G01X1125187Y213908D01*
X1125185Y213910D01*
G03X1124551Y214313I-1097J-1026D01*
G01X1124521Y214323D01*
X1124470Y214359D01*
X1124452Y214385D01*
G02X1124413Y214503I161J119D01*
G01Y215305D01*
X1124490Y215410D01*
X1124554Y215430D01*
G03X1125609Y216864I-447J1434D01*
G03X1125190Y217905I-1503J0D01*
G01X1125187Y217908D01*
X1125185Y217910D01*
G03X1124551Y218313I-1097J-1026D01*
G01X1124521Y218323D01*
X1124470Y218359D01*
X1124452Y218385D01*
G02X1124413Y218503I161J119D01*
G01Y220305D01*
X1124490Y220410D01*
X1124554Y220430D01*
G03X1125609Y221864I-447J1434D01*
G03X1125190Y222905I-1503J0D01*
G01X1125187Y222908D01*
X1125185Y222910D01*
G03X1124551Y223313I-1097J-1026D01*
G01X1124521Y223323D01*
X1124470Y223359D01*
X1124452Y223385D01*
G02X1124413Y223503I161J119D01*
G01Y241469D01*
G02X1124472Y241611I200J0D01*
G01X1125255Y242394D01*
X1125334Y242424D01*
X1125377Y242422D01*
G03X1125440Y242420I70J1208D01*
G01X1135374D01*
G37*
G36*
G01X1124546Y276294D02*
X1199520D01*
G02X1199662Y276235I0J-200D01*
G01X1200946Y274951D01*
G02X1200948Y274949I-140J-142D01*
G02X1201005Y274809I-143J-140D01*
G01Y267385D01*
G02X1200892Y267205I-200J0D01*
G01X1200515Y267023D01*
X1200402Y267036D01*
X1200356Y267072D01*
G03X1199422Y267398I-934J-1175D01*
G03Y264394I0J-1502D01*
G03X1200356Y264720I0J1501D01*
G01X1200402Y264756D01*
X1200515Y264769D01*
X1200892Y264587D01*
G02X1201005Y264407I-87J-180D01*
G01Y257901D01*
X1200951Y257809D01*
X1200906Y257782D01*
X1200904D01*
X1200616Y257613D01*
G02X1200542Y257588I-100J174D01*
G01X1200501Y257583D01*
X1200408Y257608D01*
X1200386Y257620D01*
G03X1199664Y257805I-723J-1319D01*
G01X1199663D01*
G03Y254801I0J-1502D01*
G01X1199664D01*
G03X1200386Y254986I-1J1504D01*
G01X1200408Y254998D01*
X1200462Y255013D01*
G02X1200542Y255018I52J-193D01*
G01X1200581Y255013D01*
X1200905Y254824D01*
G02X1200908Y254822I-109J-167D01*
G02X1201005Y254651I-103J-171D01*
G01Y207177D01*
X1200998Y207152D01*
G03X1200947Y206763I1451J-388D01*
G01Y206755D01*
G03X1200998Y206372I1502J5D01*
G01X1201005Y206346D01*
Y202582D01*
G03X1201064Y202440I200J0D01*
G01X1201485Y202019D01*
G03X1201627Y201960I142J141D01*
G01X1204345D01*
G02X1204378Y201957I-2J-200D01*
G02X1204485Y201903I-32J-197D01*
G01X1204741Y201647D01*
G02X1204800Y201505I-141J-142D01*
G01Y193725D01*
G02X1204742Y193585I-200J1D01*
G01X1204729Y193571D01*
X1204463Y193386D01*
G02X1204349Y193350I-114J164D01*
G01X1204262D01*
X1204231Y193361D01*
G03X1203741Y193443I-490J-1420D01*
G01X1203725D01*
G03X1202239Y191941I16J-1502D01*
G03X1203741Y190439I1502J0D01*
G01X1203744D01*
G03X1204262Y190532I-2J1502D01*
G01X1204308Y190549D01*
X1204405Y190537D01*
X1204714Y190321D01*
G02X1204742Y190298I-113J-166D01*
G01Y190297D01*
G02X1204800Y190157I-142J-141D01*
G01Y165176D01*
G02X1204754Y165048I-200J0D01*
G01X1204748Y165041D01*
X1201274Y161567D01*
X1201246Y161538D01*
X1201172Y161508D01*
X1194158D01*
G02X1193987Y161604I0J200D01*
G01X1193810Y161896D01*
G02X1193794Y161930I172J102D01*
G02X1193805Y162094I188J70D01*
G01X1193808Y162100D01*
X1193825Y162135D01*
G03X1193977Y162788I-1350J658D01*
G01Y162790D01*
Y162815D01*
G03X1193574Y163817I-1502J-22D01*
G01X1193573Y163818D01*
G02X1193517Y163957I144J139D01*
G01Y164268D01*
X1193544Y164338D01*
X1193571Y164366D01*
G03Y166420I-1096J1027D01*
G01X1193544Y166448D01*
X1193517Y166518D01*
Y166868D01*
X1193544Y166938D01*
X1193571Y166966D01*
G03X1193977Y167993I-1096J1027D01*
G03X1193607Y168980I-1501J0D01*
G01X1193583Y169008D01*
X1193558Y169074D01*
Y169412D01*
X1193583Y169478D01*
X1193607Y169506D01*
G03X1193977Y170493I-1131J987D01*
G03X1190973I-1502J0D01*
G03X1191343Y169506I1501J0D01*
G01X1191367Y169478D01*
X1191392Y169412D01*
Y169074D01*
X1191367Y169008D01*
X1191343Y168980D01*
G03X1190973Y167993I1131J-987D01*
G03X1191379Y166966I1502J0D01*
G01X1191406Y166938D01*
X1191433Y166868D01*
Y166518D01*
X1191406Y166448D01*
X1191379Y166420D01*
G03Y164366I1096J-1027D01*
G01X1191406Y164338D01*
X1191433Y164268D01*
Y163918D01*
X1191406Y163849D01*
X1191379Y163820D01*
G03X1190973Y162821I1096J-1027D01*
G01Y162793D01*
G03X1191125Y162134I1502J-1D01*
G01X1191154Y162073D01*
G02X1191156Y161930I-186J-74D01*
G02X1191140Y161896I-188J68D01*
G01X1190963Y161605D01*
X1190936Y161559D01*
X1190845Y161508D01*
X1187221D01*
G02X1187063Y161585I0J200D01*
G01X1186840Y161870D01*
X1186821Y161959D01*
X1186832Y162005D01*
G03X1186877Y162368I-1457J365D01*
G03X1185375Y163870I-1502J0D01*
G03X1184348Y163464I0J-1502D01*
G01X1184320Y163437D01*
X1184250Y163410D01*
X1183900D01*
X1183830Y163437D01*
X1183802Y163464D01*
G03X1182775Y163870I-1027J-1096D01*
G03X1181273Y162368I0J-1502D01*
G03X1181318Y162005I1502J2D01*
G01X1181329Y161959D01*
X1181310Y161870D01*
X1181087Y161585D01*
G02X1180929Y161508I-158J123D01*
G01X1165781D01*
G02X1165639Y161567I0J200D01*
G01X1164983Y162223D01*
G02X1164925Y162364I142J141D01*
G01Y240157D01*
G03X1164866Y240298I-200J-1D01*
G01X1164569Y240595D01*
X1164567Y240598D01*
G03X1164554Y240611I-856J-843D01*
G01X1164553Y240612D01*
X1162086Y243079D01*
G03X1162060Y243104I-845J-853D01*
G01X1162058Y243106D01*
X1161812Y243352D01*
G03X1161672Y243410I-141J-142D01*
G01X1161456D01*
X1161439Y243413D01*
G03X1161238Y243430I-201J-1185D01*
G01X1154643D01*
G02X1154485Y243507I0J200D01*
G01X1154262Y243793D01*
X1154243Y243882D01*
X1154255Y243928D01*
G03X1154301Y244297I-1457J369D01*
G03X1152799Y245799I-1502J0D01*
G03X1152432Y245753I2J-1502D01*
G01X1152376Y245739D01*
X1152269Y245773D01*
X1151961Y246131D01*
X1151943Y246242D01*
X1151965Y246295D01*
G03X1152081Y246874I-1387J579D01*
G03X1150579Y248376I-1502J0D01*
G03X1149550Y247968I0J-1502D01*
G01X1149516Y247936D01*
X1149430Y247909D01*
X1149076Y247958D01*
G02X1149068Y247959I21J199D01*
G02X1148931Y248055I36J197D01*
G03X1147637Y248794I-1294J-763D01*
G03Y245790I0J-1502D01*
G03X1148666Y246198I0J1502D01*
G01X1148700Y246230D01*
X1148786Y246257D01*
X1149186Y246201D01*
X1149261Y246151D01*
X1149285Y246111D01*
G03X1150579Y245372I1294J763D01*
G03X1150658Y245374I1J1502D01*
G01X1150659D01*
G03X1150721Y245378I-66J1501D01*
G01X1150755Y245382D01*
G03X1150837Y245394I-176J1492D01*
G01X1150838D01*
G03X1150946Y245418I-272J1477D01*
G01X1151002Y245432D01*
X1151109Y245398D01*
X1151417Y245040D01*
X1151434Y244930D01*
X1151412Y244876D01*
G03X1151306Y244474I1387J-581D01*
G01X1151301Y244419D01*
G03X1151296Y244297I1498J-122D01*
G01Y244295D01*
G03X1151342Y243927I1503J1D01*
G01X1151354Y243881D01*
X1151335Y243792D01*
X1151113Y243507D01*
G02X1150955Y243430I-158J123D01*
G01X1147103D01*
G03X1146904Y243413I2J-1201D01*
G01X1146887Y243410D01*
X1145940D01*
X1145894Y243422D01*
X1145875Y243431D01*
X1145873Y243432D01*
G03X1145631Y243523I-648J-1355D01*
G03X1144971Y243559I-410J-1445D01*
G03X1144567Y243430I250J-1481D01*
G01X1144547Y243420D01*
X1144503Y243410D01*
X1143519D01*
X1143502Y243413D01*
G03X1143303Y243430I-201J-1184D01*
G01X1138834D01*
G02X1138667Y243520I0J200D01*
G01X1138496Y243781D01*
G02X1138480Y243971I167J110D01*
G03X1138605Y244571I-1377J600D01*
G01Y244590D01*
G03X1135601I-1502J-19D01*
G01Y244570D01*
G03X1135726Y243971I1502J1D01*
G01X1135745Y243928D01*
X1135741Y243838D01*
X1135720Y243797D01*
G02X1135710Y243781I-175J98D01*
G01X1135540Y243521D01*
X1135512Y243478D01*
X1135424Y243430D01*
X1125442D01*
G02X1125300Y243489I0J200D01*
G01X1123711Y245078D01*
X1123682Y245106D01*
X1123652Y245180D01*
Y275400D01*
G02X1123709Y275540I200J0D01*
G01X1123710Y275541D01*
X1124404Y276235D01*
G02X1124406Y276237I142J-140D01*
G02X1124546Y276294I140J-143D01*
G37*
G36*
G01X1219410Y202336D02*
X1222922D01*
G02X1223063Y202278I0J-200D01*
G01X1225103Y200238D01*
X1225118Y200207D01*
G03X1225157Y200132I1352J655D01*
G01X1225158Y200131D01*
G03X1225173Y200105I1308J738D01*
G01X1225186Y200083D01*
X1225202Y200027D01*
X1225215Y199981D01*
Y197600D01*
G02X1225182Y197490I-200J0D01*
G03Y195840I1254J-825D01*
G02X1225215Y195730I-167J-110D01*
G01Y193600D01*
G02X1225182Y193490I-200J0D01*
G03Y191840I1254J-825D01*
G02X1225215Y191730I-167J-110D01*
G01Y187518D01*
X1225205Y187475D01*
X1225194Y187453D01*
G03Y186103I1355J-675D01*
G01X1225205Y186081D01*
X1225215Y186038D01*
Y181600D01*
G02X1225182Y181490I-200J0D01*
G03Y179840I1254J-825D01*
G02X1225215Y179730I-167J-110D01*
G01Y177600D01*
G02X1225182Y177490I-200J0D01*
G03Y175840I1254J-825D01*
G02X1225215Y175730I-167J-110D01*
G01Y173600D01*
G02X1225182Y173490I-200J0D01*
G03Y171840I1254J-825D01*
G02X1225215Y171730I-167J-110D01*
G01Y169600D01*
G02X1225182Y169490I-200J0D01*
G03Y167840I1254J-825D01*
G02X1225215Y167730I-167J-110D01*
G01Y163086D01*
G02X1225160Y162947I-200J-1D01*
G01X1225078Y162862D01*
X1225045Y162846D01*
X1224953Y162801D01*
X1224920Y162797D01*
G03Y159815I182J-1491D01*
G01X1224953Y159811D01*
X1225046Y159766D01*
G02X1225103Y159724I-88J-180D01*
G01X1225160Y159665D01*
G02X1225215Y159526I-145J-138D01*
G01Y151308D01*
G02X1225015Y151108I-200J0D01*
G01X1218441D01*
G02X1218265Y151213I0J200D01*
G01X1218099Y151523D01*
G02X1218075Y151625I176J95D01*
G01X1218077Y151682D01*
X1218108Y151729D01*
G03X1218360Y152562I-1251J833D01*
G03X1216858Y154064I-1502J0D01*
G03X1215564Y153325I0J-1502D01*
G01X1215538Y153281D01*
X1215453Y153229D01*
X1215275Y153219D01*
X1215022Y153204D01*
X1214932Y153245D01*
X1214902Y153285D01*
G03X1213708Y153875I-1194J-913D01*
G03X1212206Y152373I0J-1502D01*
G03X1212371Y151689I1502J0D01*
G01X1212395Y151642D01*
X1212391Y151539D01*
X1212185Y151203D01*
G02X1212015Y151108I-170J105D01*
G01X1202697D01*
G02X1202569Y151155I1J200D01*
G01X1201736Y151988D01*
X1201431Y152292D01*
G03X1200016Y152878I-1415J-1415D01*
G01X1193656D01*
G03X1192241Y152292I0J-2001D01*
G01X1188904Y148955D01*
G03X1188318Y147540I1415J-1415D01*
G03X1188326Y147354I2001J-7D01*
G01X1188327Y147345D01*
Y147340D01*
G03X1190314Y145538I1992J200D01*
G01X1190319D01*
G03X1190821Y145602I0J2002D01*
G03X1191734Y146125I-503J1937D01*
G01X1194426Y148817D01*
G02X1194568Y148876I142J-141D01*
G01X1197046D01*
G02X1197195Y148809I0J-200D01*
G01X1197394Y148588D01*
G02X1197444Y148437I-149J-133D01*
G01Y148434D01*
G03X1197436Y148277I1494J-155D01*
G03X1198938Y146775I1502J0D01*
G03X1200127Y147359I0J1502D01*
G01X1200151Y147390D01*
X1200184Y147410D01*
G02X1200254Y147435I101J-173D01*
G01X1200523Y147479D01*
G02X1200667Y147447I32J-198D01*
G01X1200668Y147446D01*
G03X1201132Y147214I1120J1659D01*
G03X1201787Y147104I654J1892D01*
G01X1225015D01*
G02X1225215Y146904I0J-200D01*
G01Y124540D01*
X1225212Y124524D01*
G03X1225193Y124283I1483J-238D01*
G03X1225212Y124042I1502J-3D01*
G01X1225215Y124026D01*
Y120792D01*
G02X1225201Y120718I-200J0D01*
G01X1225163Y120621D01*
X1225139Y120594D01*
G03Y118594I1122J-1000D01*
G01X1225163Y118567D01*
X1225201Y118470D01*
G02X1225215Y118396I-186J-74D01*
G01Y117752D01*
X1225161Y117618D01*
X1225138Y117592D01*
G03X1224759Y116594I1124J-998D01*
G01Y116592D01*
G03X1225063Y115687I1503J1D01*
G02X1225103Y115567I-160J-120D01*
G01Y114421D01*
G02X1225063Y114301I-200J0D01*
G03Y112487I1199J-907D01*
G02X1225103Y112367I-160J-120D01*
G01Y111688D01*
G03X1225133Y111583I200J0D01*
G01X1225184Y111504D01*
G02X1225215Y111396I-169J-107D01*
G01Y109734D01*
G02X1225156Y109592I-200J0D01*
G01X1224213Y108649D01*
G02X1224071Y108590I-142J141D01*
G01X1187399D01*
G02X1187235Y108676I0J200D01*
G03X1184271I-1482J-1027D01*
G02X1184107Y108590I-164J114D01*
G01X1167826D01*
G02X1167684Y108649I0J200D01*
G01X1166625Y109708D01*
X1166600Y109753D01*
X1166593Y109780D01*
G03X1165507Y110866I-1456J-370D01*
G01X1165480Y110873D01*
X1165435Y110898D01*
X1165373Y110960D01*
G02X1165314Y111102I141J142D01*
G01Y114907D01*
X1165401Y115016D01*
X1165470Y115031D01*
G03Y117961I-333J1465D01*
G01X1165401Y117976D01*
X1165314Y118085D01*
Y122963D01*
X1165414Y123076D01*
X1165490Y123085D01*
G03Y126067I-181J1491D01*
G01X1165414Y126076D01*
X1165314Y126189D01*
Y159263D01*
G02X1165373Y159405I200J0D01*
G01X1166236Y160268D01*
G02X1166378Y160327I142J-141D01*
G01X1201895D01*
G03X1202037Y160386I0J200D01*
G01X1205742Y164091D01*
G03X1205801Y164233I-141J142D01*
G01Y165144D01*
G03X1205802Y165174I-1200J55D01*
G01Y190158D01*
G03X1205801Y190189I-1201J-23D01*
G01Y193693D01*
G03X1205802Y193724I-1200J54D01*
G01Y201568D01*
G02X1205860Y201709I200J0D01*
G01X1206428Y202277D01*
G02X1206570Y202336I142J-141D01*
G01X1216270D01*
G02X1216447Y202229I0J-200D01*
G01X1216611Y201916D01*
G02X1216600Y201711I-177J-93D01*
G01X1216599Y201710D01*
G03X1216338Y200873I1241J-846D01*
G01Y200845D01*
G03X1219342I1502J19D01*
G01Y200865D01*
G03X1219081Y201711I-1502J0D01*
G01X1219049Y201757D01*
X1219043Y201867D01*
X1219233Y202229D01*
G02X1219410Y202336I177J-93D01*
G37*
G36*
G01X1253449Y1150336D02*
G03X1254246Y1150107I797J1273D01*
G03Y1153111I0J1502D01*
G03X1253403Y1152851I2J-1502D01*
G01X1253356Y1152819D01*
X1253247Y1152813D01*
X1252883Y1153006D01*
G02X1252777Y1153183I94J177D01*
G01Y1184840D01*
G02X1252839Y1184984I200J-1D01*
G03Y1187158I-1038J1087D01*
G02X1252777Y1187302I138J145D01*
G01Y1190768D01*
G02X1252834Y1190908I200J0D01*
G01X1252835Y1190909D01*
X1252916Y1190990D01*
G03X1252975Y1191132I-141J142D01*
G01Y1193140D01*
G02X1253029Y1193277I200J0D01*
G01X1253109Y1193363D01*
G02X1253232Y1193425I146J-137D01*
G03X1254452Y1194362I-176J1492D01*
G01X1254465Y1194396D01*
X1254513Y1194449D01*
X1254816Y1194603D01*
X1254886Y1194610D01*
X1254923Y1194601D01*
G03X1255296Y1194554I373J1455D01*
G03Y1197558I0J1502D01*
G03X1255195Y1197555I-6J-1502D01*
G02X1255009Y1197653I-14J199D01*
G03X1253713Y1198396I-1296J-759D01*
G03X1253446Y1198372I0J-1502D01*
G01X1253445D01*
G02X1253281Y1198416I-35J197D01*
G01X1253046Y1198613D01*
G02X1252975Y1198766I129J153D01*
G01Y1238403D01*
G03X1252916Y1238545I-200J0D01*
G01X1248138Y1243323D01*
G03X1247996Y1243382I-142J-141D01*
G01X1228878D01*
X1228763Y1243491D01*
X1228758Y1243571D01*
G03X1226358I-1200J-68D01*
G01X1226353Y1243491D01*
X1226238Y1243382D01*
X1221398D01*
X1221283Y1243491D01*
X1221278Y1243571D01*
G03X1218878I-1200J-68D01*
G01X1218873Y1243491D01*
X1218758Y1243382D01*
X1213918D01*
X1213803Y1243491D01*
X1213798Y1243571D01*
G03X1211398I-1200J-68D01*
G01X1211393Y1243491D01*
X1211278Y1243382D01*
X1206437D01*
X1206322Y1243491D01*
X1206317Y1243571D01*
G03X1203917I-1200J-68D01*
G01X1203912Y1243491D01*
X1203797Y1243382D01*
X1199042D01*
X1198927Y1243491D01*
X1198923Y1243571D01*
G03X1196351I-1286J-69D01*
G01X1196347Y1243491D01*
X1196232Y1243382D01*
X1191562D01*
X1191447Y1243491D01*
X1191443Y1243571D01*
G03X1188871I-1286J-69D01*
G01X1188867Y1243491D01*
X1188752Y1243382D01*
X1184081D01*
X1183966Y1243491D01*
X1183962Y1243571D01*
G03X1181390I-1286J-69D01*
G01X1181386Y1243491D01*
X1181271Y1243382D01*
X1176601D01*
X1176486Y1243491D01*
X1176482Y1243571D01*
G03X1176476Y1243639I-1285J-79D01*
G01X1176471Y1243684D01*
X1176502Y1243769D01*
X1176788Y1244054D01*
X1176874Y1244083D01*
X1176919Y1244078D01*
G03X1177066Y1244070I144J1293D01*
G03X1178368Y1245371I0J1302D01*
G01Y1249113D01*
G03X1178360Y1249261I-1303J4D01*
G01X1178354Y1249306D01*
X1178384Y1249392D01*
X1178669Y1249678D01*
X1178754Y1249709D01*
X1178799Y1249704D01*
G03X1178936Y1249696I143J1280D01*
G03X1180224Y1250984I0J1288D01*
G03X1180216Y1251120I-1288J-8D01*
G01X1180211Y1251166D01*
X1180242Y1251251D01*
X1180528Y1251536D01*
X1180613Y1251566D01*
X1180659Y1251560D01*
G03X1180806Y1251552I144J1294D01*
G03X1182108Y1252854I0J1302D01*
G01Y1256596D01*
G03X1181996Y1257123I-1302J-1D01*
G01X1181979Y1257161D01*
X1181978Y1257244D01*
X1182109Y1257551D01*
G02X1182225Y1257661I184J-78D01*
G01X1182345Y1257705D01*
X1182375Y1257706D01*
G03X1183684Y1257998I-180J3887D01*
G01X1187582Y1259612D01*
G02X1187590Y1259616I93J-176D01*
G01X1351779Y1319431D01*
G03X1352613Y1319853I-1343J3690D01*
G01X1361664Y1325887D01*
G02X1361704Y1325908I112J-165D01*
G01X1378206Y1332177D01*
G02X1378418Y1332132I71J-187D01*
G01X1378855Y1331695D01*
G02X1378914Y1331553I-141J-142D01*
G01Y1329178D01*
G02X1378791Y1328993I-200J0D01*
G01X1343768Y1314486D01*
G03X1343344Y1314203I499J-1207D01*
G01X1331735Y1302594D01*
G02X1331594Y1302536I-141J142D01*
G01X1329633D01*
G03X1328709Y1302153I0J-1306D01*
G01X1325748Y1299192D01*
G03X1325366Y1298268I924J-923D01*
G01Y1296307D01*
G02X1325307Y1296166I-200J1D01*
G01X1320423Y1291281D01*
G02X1320213Y1291235I-141J142D01*
G01X1319859Y1291363D01*
X1319788Y1291455D01*
X1319783Y1291513D01*
G03X1318287Y1292883I-1496J-132D01*
G03X1316785Y1291381I0J-1502D01*
G03X1318155Y1289885I1502J0D01*
G01X1318213Y1289880D01*
X1318305Y1289809D01*
X1318433Y1289455D01*
G02X1318387Y1289245I-188J-69D01*
G01X1313134Y1283992D01*
X1313092Y1283967D01*
X1313069Y1283960D01*
G03X1312650Y1283754I445J-1434D01*
G02X1312535Y1283718I-114J164D01*
G01X1311541D01*
X1311494Y1283729D01*
X1311472Y1283740D01*
G03X1310773Y1283913I-700J-1329D01*
G03X1310066Y1283736I0J-1502D01*
G01X1310027Y1283716D01*
X1309944Y1283710D01*
X1309581Y1283844D01*
X1309521Y1283902D01*
X1309505Y1283943D01*
G03X1308107Y1284897I-1398J-547D01*
G03Y1281893I0J-1502D01*
G03X1308814Y1282070I0J1502D01*
G01X1308853Y1282090D01*
X1308936Y1282096D01*
X1309299Y1281962D01*
X1309359Y1281904D01*
X1309375Y1281863D01*
G03X1310773Y1280909I1398J547D01*
G03X1311472Y1281082I-1J1502D01*
G01X1311494Y1281093D01*
X1311541Y1281104D01*
X1313029D01*
X1313059Y1281095D01*
G03X1313515Y1281024I456J1431D01*
G03X1314949Y1282080I0J1502D01*
G01X1314956Y1282103D01*
X1314981Y1282145D01*
X1327596Y1294759D01*
G03X1327783Y1294995I-924J924D01*
G01X1327795Y1295015D01*
X1329046Y1296266D01*
X1329187Y1296281D01*
X1329247Y1296242D01*
G03X1330070Y1295996I824J1256D01*
G03X1331572Y1297498I0J1502D01*
G03X1331326Y1298321I-1502J-1D01*
G01X1331287Y1298381D01*
X1331302Y1298522D01*
X1332886Y1300106D01*
X1332906Y1300118D01*
G03X1333142Y1300305I-688J1111D01*
G01X1344980Y1312143D01*
G02X1345045Y1312187I142J-140D01*
G01X1394934Y1332852D01*
G02X1395011Y1332867I76J-185D01*
G01X1424962D01*
G02X1425104Y1332808I0J-200D01*
G01X1427325Y1330587D01*
G02X1427384Y1330445I-141J-142D01*
G01Y1321598D01*
G02X1427325Y1321456I-200J0D01*
G01X1413651Y1307782D01*
G02X1413510Y1307724I-141J142D01*
G01X1410817D01*
G03X1408510Y1305417I0J-2307D01*
G03X1409540Y1303496I2306J0D01*
G01X1409557Y1303485D01*
X1413983Y1299059D01*
G03X1414125Y1299000I142J141D01*
G01X1431917D01*
G03X1432059Y1299059I0J200D01*
G01X1434025Y1301025D01*
G03X1434084Y1301167I-141J142D01*
G01Y1302775D01*
G02X1434143Y1302917I200J0D01*
G01X1435828Y1304602D01*
G02X1435969Y1304660I141J-142D01*
G01X1445194D01*
G03X1446118Y1305043I0J1306D01*
G01X1448302Y1307227D01*
G03X1448684Y1308151I-924J923D01*
G01Y1317376D01*
G02X1448743Y1317517I200J-1D01*
G01X1459878Y1328652D01*
G02X1460019Y1328710I141J-142D01*
G01X1491457D01*
G03X1492381Y1329093I0J1306D01*
G01X1506890Y1343602D01*
G03X1506981Y1343704I-928J920D01*
G02X1507137Y1343778I155J-126D01*
G01X1516981D01*
G03X1517181Y1343978I0J200D01*
G01Y1345457D01*
G02X1517232Y1345590I200J0D01*
G03X1517552Y1346432I-948J842D01*
G01Y1363600D01*
G02X1517609Y1363740I200J0D01*
G01X1517610Y1363741D01*
X1522638Y1368769D01*
G02X1522656Y1368785I142J-141D01*
G03X1523194Y1369889I-864J1104D01*
G03X1523168Y1370159I-1402J1D01*
G01X1523164Y1370178D01*
Y1370682D01*
G02X1523364Y1370882I200J0D01*
G01X1524734D01*
X1528169D01*
G03Y1373888I0J1503D01*
G01X1524769D01*
X1523364D01*
G02X1523164Y1374088I0J200D01*
G01Y1374592D01*
X1523168Y1374611D01*
G03X1523194Y1374881I-1376J269D01*
G03X1523168Y1375151I-1402J1D01*
G01X1523164Y1375170D01*
Y1381512D01*
X1523168Y1381531D01*
G03X1523194Y1381801I-1376J269D01*
G03X1523168Y1382071I-1402J1D01*
G01X1523164Y1382090D01*
Y1382594D01*
G02X1523364Y1382794I200J0D01*
G01X1524734D01*
X1528169D01*
G03Y1385800I0J1503D01*
G01X1524769D01*
X1523364D01*
G02X1523164Y1386000I0J200D01*
G01Y1386504D01*
X1523168Y1386523D01*
G03X1523194Y1386793I-1376J269D01*
G03X1523168Y1387063I-1402J1D01*
G01X1523164Y1387082D01*
Y1393798D01*
X1523168Y1393817D01*
G03X1523194Y1394087I-1376J269D01*
G03X1523168Y1394357I-1402J1D01*
G01X1523164Y1394376D01*
Y1394880D01*
G02X1523364Y1395080I200J0D01*
G01X1525970D01*
G03Y1398086I0J1503D01*
G01X1523364D01*
G02X1523164Y1398286I0J200D01*
G01Y1398790D01*
X1523168Y1398809D01*
G03X1523194Y1399079I-1376J269D01*
G03X1523168Y1399349I-1402J1D01*
G01X1523164Y1399368D01*
Y1400308D01*
G02X1523221Y1400448I200J0D01*
G01X1523222Y1400449D01*
X1542441Y1419668D01*
G02X1542583Y1419726I141J-142D01*
G01X1542915D01*
G03X1543839Y1420109I0J1306D01*
G01X1577803Y1454073D01*
G02X1577945Y1454132I142J-141D01*
G01X1584734D01*
G02X1584876Y1454073I0J-200D01*
G01X1586109Y1452840D01*
G02X1586168Y1452698I-141J-142D01*
G01Y1410198D01*
G02X1585968Y1409998I-200J0D01*
G01X1583770D01*
G03Y1406992I0J-1503D01*
G01X1585968D01*
G02X1586168Y1406792I0J-200D01*
G01Y1401903D01*
X1585299Y1398239D01*
G02X1585105Y1398086I-194J47D01*
G01X1583770D01*
G03Y1395080I0J-1503D01*
G01X1584297D01*
G02X1584454Y1395005I1J-200D01*
G01X1584483Y1394968D01*
X1584503Y1394880D01*
X1582935Y1388271D01*
X1582846Y1388189D01*
X1582784Y1388180D01*
G03X1581590Y1386793I209J-1387D01*
G03X1581669Y1386328I1402J-1D01*
G01X1581686Y1386281D01*
X1581670Y1386182D01*
X1581408Y1385835D01*
X1581316Y1385794D01*
X1581266Y1385797D01*
G03X1581169Y1385800I-95J-1500D01*
G01X1577769D01*
G03X1577030Y1385606I0J-1503D01*
G02X1576963Y1385583I-97J174D01*
G03X1576380Y1385332I208J-1285D01*
G02X1576246Y1385291I-122J159D01*
G01X1576123Y1385299D01*
G02X1575994Y1385358I13J200D01*
G03X1574930Y1385800I-1064J-1060D01*
G01X1571530D01*
G03Y1382794I0J-1503D01*
G01X1574930D01*
G03X1575994Y1383236I0J1502D01*
G02X1576123Y1383295I142J-141D01*
G01X1576246Y1383303D01*
G02X1576380Y1383262I12J-200D01*
G03X1576963Y1383011I791J1034D01*
G02X1577030Y1382988I-30J-197D01*
G03X1577769Y1382794I739J1309D01*
G01X1581169D01*
G03X1581266Y1382797I2J1503D01*
G01X1581316Y1382800D01*
X1581408Y1382759D01*
X1581670Y1382412D01*
X1581686Y1382313D01*
X1581669Y1382266D01*
G03X1581590Y1381801I1323J-464D01*
G03X1582658Y1380439I1402J0D01*
G01X1582726Y1380423D01*
X1582810Y1380315D01*
Y1376367D01*
X1582726Y1376259D01*
X1582658Y1376243D01*
G03X1581590Y1374881I334J-1362D01*
G03X1581669Y1374416I1402J-1D01*
G01X1581686Y1374369D01*
X1581670Y1374270D01*
X1581408Y1373923D01*
X1581316Y1373882D01*
X1581266Y1373885D01*
G03X1581169Y1373888I-95J-1500D01*
G01X1577769D01*
G03X1577030Y1373694I0J-1503D01*
G02X1576963Y1373671I-97J174D01*
G03X1576380Y1373420I208J-1285D01*
G02X1576246Y1373379I-122J159D01*
G01X1576123Y1373387D01*
G02X1575994Y1373446I13J200D01*
G03X1574930Y1373888I-1064J-1060D01*
G01X1571530D01*
G03Y1370882I0J-1503D01*
G01X1574930D01*
G03X1575994Y1371324I0J1502D01*
G02X1576123Y1371383I142J-141D01*
G01X1576246Y1371391D01*
G02X1576380Y1371350I12J-200D01*
G03X1576963Y1371099I791J1034D01*
G02X1577030Y1371076I-30J-197D01*
G03X1577769Y1370882I739J1309D01*
G01X1580440D01*
G02X1580613Y1370782I0J-200D01*
G01X1580674Y1370678D01*
G02X1580681Y1370492I-173J-100D01*
G03X1580545Y1369889I1267J-603D01*
G01Y1369887D01*
G03X1580577Y1369590I1402J1D01*
G02X1580560Y1369459I-196J-41D01*
G01X1580508Y1369354D01*
G02X1580408Y1369259I-179J88D01*
G03X1579179Y1368425I1551J-3608D01*
G01X1577805Y1367049D01*
G02X1577664Y1366990I-142J141D01*
G01X1572536D01*
G03X1572394Y1366931I0J-200D01*
G01X1570083Y1364620D01*
G03X1570024Y1364478I141J-142D01*
G01Y1363901D01*
G02X1569940Y1363738I-200J0D01*
G03Y1361452I812J-1143D01*
G02X1570024Y1361289I-116J-163D01*
G01Y1358909D01*
G02X1569940Y1358746I-200J0D01*
G03Y1356460I812J-1143D01*
G02X1570024Y1356297I-116J-163D01*
G01Y1351989D01*
G02X1569940Y1351826I-200J0D01*
G03Y1349540I812J-1143D01*
G02X1570024Y1349377I-116J-163D01*
G01Y1346903D01*
G02X1569940Y1346740I-200J0D01*
G03X1569350Y1345597I812J-1143D01*
G03X1569561Y1344857I1403J0D01*
G01X1569584Y1344820D01*
X1569595Y1344735D01*
X1569492Y1344404D01*
G02X1569381Y1344280I-191J59D01*
G01X1559827Y1340101D01*
G02X1559792Y1340089I-82J182D01*
G01X1546248Y1336985D01*
G02X1546203Y1336980I-44J195D01*
G01X1530895D01*
G03X1530753Y1336921I0J-200D01*
G01X1529257Y1335425D01*
G03X1529198Y1335283I141J-142D01*
G01Y1333239D01*
G02X1529139Y1333097I-200J0D01*
G01X1529137Y1333095D01*
G02X1529041Y1333042I-141J142D01*
G01X1486588Y1323313D01*
G03X1486284Y1323231I870J-3829D01*
G01X1469530Y1317946D01*
G03X1467935Y1316978I1181J-3745D01*
G01X1444134Y1293178D01*
G03X1443282Y1291903I2776J-2777D01*
G01X1436472Y1275460D01*
G03X1436174Y1273958I3628J-1500D01*
G01Y1251194D01*
G03X1436472Y1249692I3926J-2D01*
G01X1445288Y1228406D01*
G02X1445303Y1228329I-185J-76D01*
G01Y1223220D01*
G02X1445244Y1223078I-200J0D01*
G01X1441789Y1219623D01*
X1441761Y1219594D01*
X1441687Y1219564D01*
X1441415D01*
G02X1441374Y1219568I-1J200D01*
G01X1441333Y1219577D01*
G02X1441299Y1219587I39J196D01*
G03X1440737Y1219696I-562J-1393D01*
G01X1440735D01*
G03X1440156Y1219580I0J-1502D01*
G01X1440119Y1219564D01*
X1437415D01*
G02X1437374Y1219568I-1J200D01*
G01X1437333Y1219577D01*
G02X1437299Y1219587I39J196D01*
G03X1436737Y1219696I-562J-1393D01*
G01X1436735D01*
G03X1436156Y1219580I0J-1502D01*
G01X1436119Y1219564D01*
X1433415D01*
G02X1433374Y1219568I-1J200D01*
G01X1433333Y1219577D01*
G02X1433299Y1219587I39J196D01*
G03X1432737Y1219696I-562J-1393D01*
G01X1432735D01*
G03X1432156Y1219580I0J-1502D01*
G01X1432119Y1219564D01*
X1429415D01*
G02X1429374Y1219568I-1J200D01*
G01X1429333Y1219577D01*
G02X1429299Y1219587I39J196D01*
G03X1428737Y1219696I-562J-1393D01*
G01X1428735D01*
G03X1428156Y1219580I0J-1502D01*
G01X1428119Y1219564D01*
X1425415D01*
G02X1425374Y1219568I-1J200D01*
G01X1425333Y1219577D01*
G02X1425299Y1219587I39J196D01*
G03X1424737Y1219696I-562J-1393D01*
G01X1424735D01*
G03X1424156Y1219580I0J-1502D01*
G01X1424119Y1219564D01*
X1421415D01*
G02X1421374Y1219568I-1J200D01*
G01X1421333Y1219577D01*
G02X1421299Y1219587I39J196D01*
G03X1420737Y1219696I-562J-1393D01*
G01X1420735D01*
G03X1420156Y1219580I0J-1502D01*
G01X1420119Y1219564D01*
X1417415D01*
G02X1417374Y1219568I-1J200D01*
G01X1417333Y1219577D01*
G02X1417299Y1219587I39J196D01*
G03X1416737Y1219696I-562J-1393D01*
G01X1416735D01*
G03X1416156Y1219580I0J-1502D01*
G01X1416119Y1219564D01*
X1413415D01*
G02X1413374Y1219568I-1J200D01*
G01X1413333Y1219577D01*
G02X1413299Y1219587I39J196D01*
G03X1412737Y1219696I-562J-1393D01*
G01X1412735D01*
G03X1412156Y1219580I0J-1502D01*
G01X1412119Y1219564D01*
X1409415D01*
G02X1409374Y1219568I-1J200D01*
G01X1409333Y1219577D01*
G02X1409299Y1219587I39J196D01*
G03X1408737Y1219696I-562J-1393D01*
G01X1408735D01*
G03X1408156Y1219580I0J-1502D01*
G01X1408119Y1219564D01*
X1348451D01*
X1348444D01*
G02X1348272Y1219675I7J200D01*
G02X1348263Y1219697I180J87D01*
G01X1348145Y1220026D01*
G02X1348152Y1220178I188J67D01*
G01X1348195Y1220271D01*
X1348227Y1220298D01*
G03X1348739Y1221428I-991J1130D01*
G03X1345735I-1502J0D01*
G03X1346247Y1220298I1503J0D01*
G01X1346279Y1220271D01*
X1346322Y1220178D01*
G02X1346329Y1220026I-181J-85D01*
G01X1346211Y1219697D01*
G02X1346202Y1219675I-189J65D01*
G02X1346030Y1219564I-179J89D01*
G01X1344451D01*
X1344444D01*
G02X1344272Y1219675I7J200D01*
G02X1344263Y1219697I180J87D01*
G01X1344145Y1220026D01*
G02X1344152Y1220178I188J67D01*
G01X1344195Y1220271D01*
X1344227Y1220298D01*
G03X1344739Y1221428I-991J1130D01*
G03X1341735I-1502J0D01*
G03X1342247Y1220298I1503J0D01*
G01X1342279Y1220271D01*
X1342322Y1220178D01*
G02X1342329Y1220026I-181J-85D01*
G01X1342211Y1219697D01*
G02X1342202Y1219675I-189J65D01*
G02X1342030Y1219564I-179J89D01*
G01X1340451D01*
X1340444D01*
G02X1340272Y1219675I7J200D01*
G02X1340263Y1219697I180J87D01*
G01X1340145Y1220026D01*
G02X1340152Y1220178I188J67D01*
G01X1340195Y1220271D01*
X1340227Y1220298D01*
G03X1340739Y1221428I-991J1130D01*
G03X1337735I-1502J0D01*
G03X1338247Y1220298I1503J0D01*
G01X1338279Y1220271D01*
X1338322Y1220178D01*
G02X1338329Y1220026I-181J-85D01*
G01X1338211Y1219697D01*
G02X1338202Y1219675I-189J65D01*
G02X1338030Y1219564I-179J89D01*
G01X1336451D01*
X1336444D01*
G02X1336272Y1219675I7J200D01*
G02X1336263Y1219697I180J87D01*
G01X1336145Y1220026D01*
G02X1336152Y1220178I188J67D01*
G01X1336195Y1220271D01*
X1336227Y1220298D01*
G03X1336739Y1221428I-991J1130D01*
G03X1333735I-1502J0D01*
G03X1334247Y1220298I1503J0D01*
G01X1334279Y1220271D01*
X1334322Y1220178D01*
G02X1334329Y1220026I-181J-85D01*
G01X1334211Y1219697D01*
G02X1334202Y1219675I-189J65D01*
G02X1334030Y1219564I-179J89D01*
G01X1332451D01*
X1332444D01*
G02X1332272Y1219675I7J200D01*
G02X1332263Y1219697I180J87D01*
G01X1332145Y1220026D01*
G02X1332152Y1220178I188J67D01*
G01X1332195Y1220271D01*
X1332227Y1220298D01*
G03X1332739Y1221428I-991J1130D01*
G03X1329735I-1502J0D01*
G03X1330247Y1220298I1503J0D01*
G01X1330279Y1220271D01*
X1330322Y1220178D01*
G02X1330329Y1220026I-181J-85D01*
G01X1330211Y1219697D01*
G02X1330202Y1219675I-189J65D01*
G02X1330030Y1219564I-179J89D01*
G01X1328451D01*
X1328444D01*
G02X1328272Y1219675I7J200D01*
G02X1328263Y1219697I180J87D01*
G01X1328145Y1220026D01*
G02X1328152Y1220178I188J67D01*
G01X1328195Y1220271D01*
X1328227Y1220298D01*
G03X1328739Y1221428I-991J1130D01*
G03X1325735I-1502J0D01*
G03X1326247Y1220298I1503J0D01*
G01X1326279Y1220271D01*
X1326322Y1220178D01*
G02X1326329Y1220026I-181J-85D01*
G01X1326211Y1219697D01*
G02X1326202Y1219675I-189J65D01*
G02X1326030Y1219564I-179J89D01*
G01X1324451D01*
X1324444D01*
G02X1324272Y1219675I7J200D01*
G02X1324263Y1219697I180J87D01*
G01X1324145Y1220026D01*
G02X1324152Y1220178I188J67D01*
G01X1324195Y1220271D01*
X1324227Y1220298D01*
G03X1324739Y1221428I-991J1130D01*
G03X1321735I-1502J0D01*
G03X1322247Y1220298I1503J0D01*
G01X1322279Y1220271D01*
X1322322Y1220178D01*
G02X1322329Y1220026I-181J-85D01*
G01X1322211Y1219697D01*
G02X1322202Y1219675I-189J65D01*
G02X1322030Y1219564I-179J89D01*
G01X1320451D01*
X1320444D01*
G02X1320272Y1219675I7J200D01*
G02X1320263Y1219697I180J87D01*
G01X1320145Y1220026D01*
G02X1320152Y1220178I188J67D01*
G01X1320195Y1220271D01*
X1320227Y1220298D01*
G03X1320739Y1221428I-991J1130D01*
G03X1317735I-1502J0D01*
G03X1318247Y1220298I1503J0D01*
G01X1318279Y1220271D01*
X1318322Y1220178D01*
G02X1318329Y1220026I-181J-85D01*
G01X1318211Y1219697D01*
G02X1318202Y1219675I-189J65D01*
G02X1318030Y1219564I-179J89D01*
G01X1316451D01*
X1316444D01*
G02X1316272Y1219675I7J200D01*
G02X1316263Y1219697I180J87D01*
G01X1316145Y1220026D01*
G02X1316152Y1220178I188J67D01*
G01X1316195Y1220271D01*
X1316227Y1220298D01*
G03X1316739Y1221428I-991J1130D01*
G03X1313735I-1502J0D01*
G03X1314247Y1220298I1503J0D01*
G01X1314279Y1220271D01*
X1314322Y1220178D01*
G02X1314329Y1220026I-181J-85D01*
G01X1314211Y1219697D01*
G02X1314202Y1219675I-189J65D01*
G02X1314030Y1219564I-179J89D01*
G01X1312451D01*
X1312444D01*
G02X1312272Y1219675I7J200D01*
G02X1312263Y1219697I180J87D01*
G01X1312145Y1220026D01*
G02X1312152Y1220178I188J67D01*
G01X1312195Y1220271D01*
X1312227Y1220298D01*
G03X1312739Y1221428I-991J1130D01*
G03X1309735I-1502J0D01*
G03X1310247Y1220298I1503J0D01*
G01X1310279Y1220271D01*
X1310322Y1220178D01*
G02X1310329Y1220026I-181J-85D01*
G01X1310211Y1219697D01*
G02X1310202Y1219675I-189J65D01*
G02X1310030Y1219564I-179J89D01*
G01X1307907D01*
G03X1307765Y1219505I0J-200D01*
G01X1302623Y1214363D01*
G03X1302564Y1214221I141J-142D01*
G01Y1173238D01*
G02X1302505Y1173096I-200J0D01*
G01X1281549Y1152140D01*
G03X1281490Y1151998I141J-142D01*
G01Y1151023D01*
G02X1281482Y1150968I-200J1D01*
G01X1281459Y1150889D01*
X1281446Y1150866D01*
G03Y1149308I1285J-779D01*
G01X1281459Y1149285D01*
X1281482Y1149206D01*
G02X1281490Y1149151I-192J-56D01*
G01Y1147873D01*
G02X1281482Y1147818I-200J1D01*
G01X1281459Y1147739D01*
X1281446Y1147716D01*
G03Y1146158I1285J-779D01*
G01X1281459Y1146135D01*
X1281482Y1146056D01*
G02X1281490Y1146001I-192J-56D01*
G01Y1138444D01*
G02X1281472Y1138362I-200J1D01*
G01X1281424Y1138253D01*
X1281394Y1138226D01*
G03Y1136032I1028J-1097D01*
G01X1281424Y1136005D01*
X1281472Y1135896D01*
G02X1281490Y1135814I-182J-83D01*
G01Y1131788D01*
G02X1281431Y1131646I-200J0D01*
G01X1280887Y1131102D01*
X1280859Y1131073D01*
X1280785Y1131043D01*
X1269253D01*
X1269244D01*
G02X1269137Y1131080I9J200D01*
G02X1269115Y1131098I115J163D01*
G01X1267773Y1132381D01*
G03X1266706Y1133106I-2690J-2812D01*
G01X1265516Y1133651D01*
G02X1265414Y1133759I84J182D01*
G01X1265298Y1134052D01*
Y1134128D01*
X1265313Y1134164D01*
G03X1265423Y1134719I-1392J564D01*
G01Y1134740D01*
G03X1263921Y1136231I-1502J-11D01*
G03X1262585Y1135416I0J-1503D01*
G01X1262567Y1135381D01*
X1262510Y1135331D01*
X1262211Y1135227D01*
G02X1262062Y1135234I-66J189D01*
G01X1261968Y1135277D01*
X1261917Y1135327D01*
X1261902Y1135360D01*
G03X1260539Y1136231I-1363J-631D01*
G01X1260538D01*
G03X1260129Y1136174I1J-1502D01*
G01X1260126Y1136173D01*
G02X1259989Y1136184I-53J193D01*
G01X1258466Y1136882D01*
G02X1258408Y1136923I85J181D01*
G01X1252836Y1142495D01*
X1252807Y1142523D01*
X1252777Y1142597D01*
Y1144997D01*
G02X1252881Y1145172I200J0D01*
G01X1253237Y1145367D01*
X1253345Y1145364D01*
X1253392Y1145334D01*
G03X1254200Y1145098I808J1265D01*
G03Y1148102I0J1502D01*
G03X1253392Y1147866I0J-1501D01*
G01X1253345Y1147836D01*
X1253237Y1147833D01*
X1252881Y1148028D01*
G02X1252777Y1148203I96J175D01*
G01Y1150035D01*
G02X1252883Y1150212I200J0D01*
G01X1253131Y1150344D01*
G02X1253225Y1150367I93J-177D01*
G01X1253371D01*
X1253425Y1150352D01*
X1253449Y1150336D01*
G37*
G36*
G01X1256555Y54588D02*
X1285191D01*
X1285226D01*
X1285275Y54539D01*
Y52675D01*
X1285191Y52591D01*
X1256555D01*
G03X1250618Y46654I0J-5937D01*
G01Y7874D01*
G02X1244744Y2000I-5874J0D01*
G01X1197500D01*
G02X1191626Y7874I0J5874D01*
G01Y46654D01*
G03X1190170Y50549I-5938J0D01*
G01Y50728D01*
X1190174Y50732D01*
X1192419D01*
X1192602Y50549D01*
G02X1193624Y46654I-6911J-3895D01*
G01Y7874D01*
G03X1197500Y3998I3876J0D01*
G01X1244744D01*
G03X1248620Y7874I0J3876D01*
G01Y46654D01*
G02X1256555Y54588I7935J-1D01*
G37*
G36*
G01X1202207Y275932D02*
X1224142D01*
X1224216Y275902D01*
X1224244Y275873D01*
X1224855Y275262D01*
G02X1224914Y275120I-141J-142D01*
G01Y205020D01*
X1224884Y204946D01*
X1224855Y204918D01*
X1223334Y203397D01*
G02X1223192Y203338I-142J141D01*
G01X1202325D01*
X1202251Y203368D01*
X1202223Y203397D01*
X1202065Y203555D01*
G02X1202007Y203696I142J141D01*
G01Y204858D01*
G02X1202067Y205001I200J0D01*
G01X1202301Y205230D01*
X1202375Y205259D01*
X1202415Y205258D01*
X1202449D01*
G03Y208262I0J1502D01*
G01X1202415D01*
X1202375Y208261D01*
X1202301Y208290D01*
X1202067Y208519D01*
G02X1202007Y208661I140J143D01*
G01Y255107D01*
G02X1202125Y255289I200J0D01*
G01X1202449Y255436D01*
G02X1202620Y255432I81J-183D01*
G01X1202670Y255407D01*
X1202689Y255392D01*
G03X1203663Y255033I975J1143D01*
G03Y258037I0J1502D01*
G03X1202689Y257678I1J-1502D01*
G01X1202670Y257663D01*
X1202620Y257638D01*
G02X1202449Y257634I-90J179D01*
G01X1202125Y257781D01*
G02X1202007Y257963I82J182D01*
G01Y275732D01*
G02X1202207Y275932I200J0D01*
G37*
G36*
G01X1237736Y242420D02*
G03X1237873Y242428I-2J1210D01*
G01X1237885Y242429D01*
X1241046D01*
X1241058Y242428D01*
G03X1241194Y242420I139J1202D01*
G01X1245658D01*
G02X1245694Y242417I1J-200D01*
G01X1245711Y242414D01*
G02X1245814Y242361I-36J-197D01*
G01X1246003Y242180D01*
G02X1246064Y242046I-139J-144D01*
G01Y242042D01*
G03X1246464Y241077I1501J57D01*
G01X1246466Y241075D01*
X1246469Y241072D01*
G03X1246475Y241065I1143J974D01*
G01X1246477Y241063D01*
X1246482Y241057D01*
G03X1247584Y240576I1102J1022D01*
G03X1249086Y242057I0J1502D01*
G01X1249087Y242098D01*
X1249118Y242170D01*
X1249292Y242338D01*
X1249315Y242360D01*
G02X1249419Y242414I140J-143D01*
G01X1249454Y242420D01*
X1253319D01*
G03X1253460Y242428I2J1210D01*
G01X1256862D01*
G03X1257003Y242420I139J1202D01*
G01X1263595D01*
G02X1263690Y242396I0J-200D01*
G01X1263716Y242382D01*
X1266190Y239908D01*
X1266202Y239895D01*
X1266243Y239854D01*
G02X1266266Y239762I-177J-93D01*
G01Y153175D01*
G02X1266263Y153139I-200J-1D01*
G01X1266252Y153081D01*
X1266219Y153023D01*
X1266193Y153000D01*
G03X1265889Y147733I2440J-2783D01*
G01X1265907Y147713D01*
X1265908Y147711D01*
G03X1266098Y147517I2738J2492D01*
G03X1266151Y147469I2511J2719D01*
G01X1266152Y147468D01*
G03X1266169Y147452I2545J2687D01*
G01X1266185Y147437D01*
X1266209Y147404D01*
X1266249Y147312D01*
G02X1266266Y147232I-183J-81D01*
G01Y125108D01*
X1266255Y125076D01*
G03X1266169Y124576I1416J-501D01*
G03X1266255Y124076I1502J1D01*
G01X1266266Y124044D01*
Y122986D01*
G03X1266281Y122910I200J0D01*
G01X1266301Y122863D01*
G02X1266316Y122786I-185J-76D01*
G01Y117488D01*
G02X1266279Y117371I-200J-1D01*
G03X1265997Y116496I1220J-876D01*
G03X1266279Y115621I1502J1D01*
G02X1266316Y115504I-163J-116D01*
G01Y110681D01*
G03X1266329Y110611I200J1D01*
G02X1266341Y110527I-188J-70D01*
G01X1266332Y110411D01*
G02X1266293Y110306I-199J14D01*
G03X1265997Y109410I1206J-895D01*
G03X1267499Y107908I1502J0D01*
G03X1268431Y108232I0J1502D01*
G01X1268492Y108280D01*
X1268642Y108272D01*
X1269246Y107668D01*
G03X1269388Y107609I142J141D01*
G01X1269963D01*
X1269984Y107605D01*
X1269987D01*
G03X1270001Y107602I259J1173D01*
G01X1270004D01*
X1270018Y107600D01*
X1270020D01*
G03X1270089Y107592I173J1189D01*
G03X1270186Y107588I98J1198D01*
G01X1286113D01*
G02X1286312Y107389I0J-200D01*
G01Y104249D01*
G03X1286330Y103999I1803J4D01*
G01Y103997D01*
G03X1286334Y103974I1777J297D01*
G01Y103972D01*
G03X1286344Y103915I1780J283D01*
G01X1286349Y103886D01*
X1286343Y103829D01*
X1286332Y103802D01*
G02X1286261Y103713I-185J75D01*
G01X1286231Y103692D01*
X1286128Y103620D01*
G03X1285338Y103845I-790J-1274D01*
G03X1283836Y102343I0J-1502D01*
G03X1284257Y101300I1502J0D01*
G01X1284260Y101297D01*
X1284262Y101295D01*
G03X1285357Y100821I1095J1028D01*
G03X1286857Y102242I0J1502D01*
G01Y102244D01*
G02X1286951Y102402I200J-12D01*
G01X1287090Y102488D01*
X1287270Y102600D01*
X1287367Y102608D01*
X1287412Y102589D01*
G03X1288106Y102446I704J1660D01*
G01X1288115D01*
G03X1289918Y104249I0J1803D01*
G01Y107389D01*
G02X1290117Y107588I199J-1D01*
G01X1326361D01*
G02X1326501Y107531I0J-200D01*
G01X1326502Y107530D01*
X1327916Y106116D01*
G02X1327975Y105974I-141J-142D01*
G01Y78321D01*
G02X1327962Y78249I-200J-1D01*
G03X1327010Y74961I19341J-7382D01*
G03X1326600Y70866I20292J-4100D01*
G03X1327010Y66771I20702J5D01*
G03X1327962Y63483I20293J4094D01*
G02X1327975Y63411I-187J-71D01*
G01Y34014D01*
X1327877Y33902D01*
X1327802Y33891D01*
G03Y30915I200J-1488D01*
G01X1327877Y30904D01*
X1327975Y30792D01*
Y28947D01*
G02X1327839Y28757I-200J0D01*
G01X1327838D01*
G03X1326815Y27333I480J-1424D01*
G03X1327839Y25909I1502J0D01*
G01X1327900Y25888D01*
X1327975Y25784D01*
Y19962D01*
G02X1327916Y19820I-200J0D01*
G01X1326232Y18136D01*
G02X1326090Y18077I-142J141D01*
G01X1297654D01*
G02X1297512Y18136I0J200D01*
G01X1297046Y18602D01*
G02X1296988Y18743I142J141D01*
G01Y28759D01*
G02X1297062Y28914I200J0D01*
G01X1297338Y29137D01*
X1297426Y29158D01*
X1297470Y29149D01*
G03X1297778Y29116I313J1469D01*
G01X1297795D01*
G03Y32120I-10J1502D01*
G01X1297784D01*
G03X1297478Y32089I-2J-1502D01*
G01X1297469Y32087D01*
X1297449Y32085D01*
G02X1297302Y32128I-22J199D01*
G01X1297062Y32322D01*
G02X1296988Y32477I126J155D01*
G01Y46655D01*
G03X1296729Y48791I-8935J0D01*
G01X1296723Y48814D01*
Y53060D01*
G03X1296678Y53186I-200J0D01*
G01X1296656Y53212D01*
X1296644Y53244D01*
G02X1296632Y53314I188J68D01*
G01Y53315D01*
G02X1296689Y53455I200J0D01*
G01X1296690Y53456D01*
X1296691Y53457D01*
G02X1296780Y53509I142J-141D01*
G03X1302969Y61614I-2213J8105D01*
G03X1286165I-8402J0D01*
G01Y61611D01*
G03X1286674Y58733I8402J2D01*
G01X1286686Y58699D01*
Y58663D01*
X1286765Y58467D01*
X1286784Y58420D01*
X1286774Y58322D01*
X1286653Y58142D01*
X1286560Y58004D01*
G02X1286394Y57916I-166J112D01*
G01X1279249D01*
G02X1279071Y58026I1J200D01*
G01X1278898Y58367D01*
X1278907Y58479D01*
X1278940Y58525D01*
G03X1279649Y60519I-2988J2185D01*
G01X1279652Y60588D01*
G03X1279630Y61129I-3700J121D01*
G03X1279551Y61575I-3678J-421D01*
G03X1279517Y61706I-3599J-864D01*
G01Y61707D01*
X1279512Y61723D01*
G03X1279210Y62466I-3560J-1014D01*
G01X1279186Y62511D01*
Y62611D01*
X1279376Y62963D01*
X1279460Y63018D01*
X1279511Y63022D01*
G03X1281924Y69456I-319J3789D01*
G01X1281923Y69457D01*
G03X1277704Y70338I-2750J-2626D01*
G03X1275824Y65032I1469J-3507D01*
G01X1275825Y65029D01*
X1275831Y65017D01*
X1275837Y65003D01*
G02X1275822Y64817I-184J-79D01*
G01X1275819Y64813D01*
X1275649Y64528D01*
G02X1275477Y64430I-172J102D01*
G01X1268633D01*
G03X1264932Y60729I0J-3701D01*
G01Y60727D01*
G03X1265640Y58552I3701J2D01*
G01X1265673Y58506D01*
X1265682Y58393D01*
X1265634Y58300D01*
X1265496Y58027D01*
G02X1265414Y57943I-178J92D01*
G01X1265412Y57941D01*
G02X1265314Y57916I-97J175D01*
G01X1228620D01*
G02X1228478Y57975I0J200D01*
G01X1227713Y58740D01*
G02X1227672Y58962I142J141D01*
G01Y58963D01*
X1227822Y59302D01*
G02X1227903Y59393I183J-81D01*
G01X1227931Y59410D01*
X1227987Y59424D01*
X1228016Y59422D01*
X1228022D01*
G03X1228097Y59420I78J1500D01*
G03Y62424I0J1502D01*
G03X1227415Y62260I0J-1502D01*
G01X1227368Y62236D01*
X1227265Y62240D01*
X1226929Y62446D01*
G02X1226834Y62616I105J170D01*
G01Y84598D01*
G02X1226857Y84691I200J0D01*
G01X1226909Y84790D01*
X1226938Y84824D01*
X1226956Y84837D01*
G03Y87255I-891J1209D01*
G01X1226938Y87268D01*
X1226909Y87302D01*
X1226857Y87401D01*
G02X1226834Y87494I177J93D01*
G01Y92536D01*
X1226864Y92607D01*
X1226892Y92636D01*
X1227002Y92747D01*
X1227068Y92777D01*
X1227106Y92780D01*
G03X1228519Y94279I-89J1499D01*
G01X1228520D01*
G03X1227148Y95776I-1503J0D01*
G01X1227104Y95779D01*
X1227067Y95798D01*
G02X1227012Y95840I92J178D01*
G01X1226828Y96039D01*
G02X1226775Y96175I147J136D01*
G01Y108877D01*
G02X1226888Y109058I200J1D01*
G01X1226889D01*
G03X1227434Y109500I-648J1355D01*
G01X1227443Y109512D01*
X1227453Y109522D01*
X1227465Y109534D01*
G02X1227577Y109590I141J-142D01*
G01X1227621Y109597D01*
X1227888Y109636D01*
X1227965Y109616D01*
X1227997Y109591D01*
G03X1228910Y109282I913J1194D01*
G03X1230197Y110009I0J1503D01*
G01X1230211Y110031D01*
X1230245Y110066D01*
X1230347Y110125D01*
G02X1230387Y110143I101J-172D01*
G02X1230424Y110152I66J-189D01*
G02X1230448Y110153I20J-199D01*
G01X1230659D01*
G02X1230756Y110128I0J-200D01*
G01X1230857Y110072D01*
X1230893Y110037D01*
X1230907Y110015D01*
G03X1231106Y109759I1279J789D01*
G01X1231108Y109757D01*
X1231110Y109755D01*
G03X1232204Y109282I1094J1029D01*
G03X1233706Y110784I0J1502D01*
G03X1233285Y111827I-1502J0D01*
G01X1233282Y111830D01*
X1233275Y111837D01*
G03X1232185Y112306I-1090J-1032D01*
G03X1230884Y111555I0J-1502D01*
G02X1230711Y111455I-173J100D01*
G01X1230372D01*
G02X1230200Y111553I0J200D01*
G03X1230004Y111813I-1290J-769D01*
G01X1230001Y111816D01*
X1229997Y111821D01*
G03X1229994Y111824I-1064J-1061D01*
G01X1229993Y111825D01*
G03X1228891Y112306I-1102J-1022D01*
G03X1227699Y111718I0J-1502D01*
G01X1227690Y111706D01*
X1227680Y111696D01*
X1227668Y111684D01*
G02X1227556Y111628I-141J142D01*
G01X1227280Y111587D01*
G02X1227131Y111624I-30J198D01*
G03X1227084Y111658I-904J-1200D01*
G01X1227065Y111671D01*
X1227033Y111706D01*
X1226977Y111807D01*
G02X1226952Y111904I175J97D01*
G01Y111924D01*
G02X1226977Y112021I200J0D01*
G01X1226994Y112051D01*
G02X1227060Y112122I175J-97D01*
G01X1227062Y112123D01*
X1227063D01*
G03X1227763Y113394I-804J1271D01*
G03X1227358Y114420I-1502J0D01*
G01X1227356Y114422D01*
X1227353Y114426D01*
G03X1227348Y114431I-1065J-1060D01*
G03X1227346Y114433I-142J-140D01*
G03X1226889Y114770I-1104J-1019D01*
G01X1226836Y114795D01*
X1226775Y114892D01*
Y115049D01*
G02X1226891Y115231I200J0D01*
G03X1227763Y116594I-629J1363D01*
G03X1227343Y117636I-1503J0D01*
G01X1227341Y117638D01*
X1227339Y117640D01*
G03X1227165Y117799I-1097J-1026D01*
G02X1227088Y117957I123J158D01*
G01Y118190D01*
G02X1227109Y118278I200J-1D01*
G01X1227156Y118374D01*
X1227183Y118408D01*
X1227200Y118421D01*
G03X1227763Y119594I-940J1173D01*
G03X1227358Y120620I-1502J0D01*
G01X1227356Y120622D01*
X1227353Y120626D01*
G03X1227348Y120631I-1065J-1060D01*
G03X1227346Y120633I-142J-140D01*
G03X1226889Y120970I-1104J-1019D01*
G01X1226836Y120995D01*
X1226775Y121092D01*
Y122677D01*
X1226870Y122789D01*
X1226942Y122801D01*
G03X1227781Y125321I-247J1482D01*
G01X1227779Y125323D01*
X1227777Y125326D01*
G03X1226940Y125782I-1100J-1023D01*
G01X1226868Y125795D01*
X1226775Y125905D01*
Y131939D01*
G02X1226896Y132123I200J0D01*
G01X1227289Y132292D01*
X1227406Y132271D01*
X1227450Y132229D01*
G03X1227685Y132047I1033J1092D01*
G02X1227695Y132040I-110J-167D01*
G01X1227696Y132039D01*
G02X1227771Y131934I-117J-163D01*
G01X1227857Y131643D01*
X1227851Y131570D01*
X1227835Y131536D01*
G03X1227693Y130898I1360J-638D01*
G03X1230697I1502J0D01*
G03X1229994Y132170I-1502J0D01*
G01X1229963Y132190D01*
X1229918Y132248D01*
X1229823Y132572D01*
X1229826Y132610D01*
X1229829Y132648D01*
X1229845Y132680D01*
G03X1229859Y132712I-1369J618D01*
G02X1229860Y132715I190J-62D01*
G03X1229914Y132853I-1370J616D01*
G01X1229925Y132887D01*
X1229970Y132943D01*
X1230258Y133115D01*
X1230290Y133121D01*
G03X1230651Y133077I361J1459D01*
G03X1232153Y134579I0J1502D01*
G03X1231732Y135622I-1502J0D01*
G01X1231729Y135625D01*
X1231722Y135632D01*
G03X1230632Y136101I-1090J-1032D01*
G03X1229204Y135066I0J-1503D01*
G01X1229203Y135064D01*
G02X1229116Y134955I-190J62D01*
G01X1228859Y134802D01*
X1228789Y134789D01*
X1228753Y134796D01*
G03X1228486Y134820I-267J-1478D01*
G01X1228485D01*
G03X1227450Y134407I0J-1503D01*
G01X1227406Y134366D01*
X1227289Y134345D01*
X1226896Y134513D01*
G02X1226775Y134697I79J184D01*
G01Y167050D01*
G02X1226811Y167163I200J-1D01*
G01Y167164D01*
G02X1226910Y167239I164J-114D01*
G01X1226912Y167240D01*
G03X1227939Y168665I-475J1425D01*
G03X1227516Y169710I-1502J0D01*
G01X1227513Y169713D01*
X1227511Y169715D01*
G03X1226921Y170100I-1093J-1030D01*
G01X1226910Y170104D01*
X1226886Y170116D01*
G02X1226775Y170295I89J179D01*
G01Y171050D01*
G02X1226811Y171163I200J-1D01*
G01Y171164D01*
G02X1226910Y171239I164J-114D01*
G01X1226912Y171240D01*
G03X1227939Y172665I-475J1425D01*
G03X1227516Y173710I-1502J0D01*
G01X1227513Y173713D01*
X1227511Y173715D01*
G03X1226921Y174100I-1093J-1030D01*
G01X1226910Y174104D01*
X1226886Y174116D01*
G02X1226775Y174295I89J179D01*
G01Y175050D01*
G02X1226811Y175163I200J-1D01*
G01Y175164D01*
G02X1226910Y175239I164J-114D01*
G01X1226912Y175240D01*
G03X1227939Y176665I-475J1425D01*
G03X1227516Y177710I-1502J0D01*
G01X1227513Y177713D01*
X1227511Y177715D01*
G03X1226921Y178100I-1093J-1030D01*
G01X1226910Y178104D01*
X1226886Y178116D01*
G02X1226775Y178295I89J179D01*
G01Y179050D01*
G02X1226811Y179163I200J-1D01*
G01Y179164D01*
G02X1226910Y179239I164J-114D01*
G01X1226912Y179240D01*
G03X1227939Y180665I-475J1425D01*
G03X1227516Y181710I-1502J0D01*
G01X1227513Y181713D01*
X1227511Y181715D01*
G03X1226921Y182100I-1093J-1030D01*
G01X1226910Y182104D01*
X1226886Y182116D01*
G02X1226775Y182295I89J179D01*
G01Y185199D01*
X1226858Y185306D01*
X1226925Y185324D01*
G03X1228052Y186778I-374J1454D01*
G03X1228039Y186978I-1502J3D01*
G01X1228038Y186988D01*
G03X1227631Y187821I-1488J-211D01*
G01X1227629Y187823D01*
X1227622Y187831D01*
G03X1226925Y188247I-1090J-1034D01*
G01X1226923Y188248D01*
X1226918Y188250D01*
G02X1226775Y188441I57J192D01*
G01Y191050D01*
G02X1226811Y191163I200J-1D01*
G01Y191164D01*
G02X1226910Y191239I164J-114D01*
G01X1226912Y191240D01*
G03X1227939Y192665I-475J1425D01*
G03X1227516Y193710I-1502J0D01*
G01X1227513Y193713D01*
X1227511Y193715D01*
G03X1226921Y194100I-1093J-1030D01*
G01X1226910Y194104D01*
X1226886Y194116D01*
G02X1226775Y194295I89J179D01*
G01Y195015D01*
G02X1226810Y195128I200J0D01*
G01X1226883Y195236D01*
X1226930Y195272D01*
X1226959Y195284D01*
G03X1226921Y198100I-541J1401D01*
G01X1226910Y198104D01*
X1226886Y198116D01*
G02X1226775Y198295I89J179D01*
G01Y199305D01*
X1226852Y199410D01*
X1226916Y199430D01*
G03X1227971Y200864I-447J1434D01*
G03X1227552Y201905I-1503J0D01*
G01X1227549Y201908D01*
X1227547Y201910D01*
G03X1226913Y202313I-1097J-1026D01*
G01X1226883Y202323D01*
X1226832Y202359D01*
X1226814Y202385D01*
G02X1226775Y202503I161J119D01*
G01Y203305D01*
X1226852Y203410D01*
X1226916Y203430D01*
G03X1227971Y204864I-447J1434D01*
G03X1227552Y205905I-1503J0D01*
G01X1227549Y205908D01*
X1227547Y205910D01*
G03X1226913Y206313I-1097J-1026D01*
G01X1226883Y206323D01*
X1226832Y206359D01*
X1226814Y206385D01*
G02X1226775Y206503I161J119D01*
G01Y207305D01*
X1226852Y207410D01*
X1226916Y207430D01*
G03X1227971Y208864I-447J1434D01*
G03X1227552Y209905I-1503J0D01*
G01X1227549Y209908D01*
X1227547Y209910D01*
G03X1226913Y210313I-1097J-1026D01*
G01X1226883Y210323D01*
X1226832Y210359D01*
X1226814Y210385D01*
G02X1226775Y210503I161J119D01*
G01Y211305D01*
X1226852Y211410D01*
X1226916Y211430D01*
G03X1227971Y212864I-447J1434D01*
G03X1227552Y213905I-1503J0D01*
G01X1227549Y213908D01*
X1227547Y213910D01*
G03X1226913Y214313I-1097J-1026D01*
G01X1226883Y214323D01*
X1226832Y214359D01*
X1226814Y214385D01*
G02X1226775Y214503I161J119D01*
G01Y215305D01*
X1226852Y215410D01*
X1226916Y215430D01*
G03X1227971Y216864I-447J1434D01*
G03X1227552Y217905I-1503J0D01*
G01X1227549Y217908D01*
X1227547Y217910D01*
G03X1226913Y218313I-1097J-1026D01*
G01X1226883Y218323D01*
X1226832Y218359D01*
X1226814Y218385D01*
G02X1226775Y218503I161J119D01*
G01Y220305D01*
X1226852Y220410D01*
X1226916Y220430D01*
G03X1227971Y221864I-447J1434D01*
G03X1227552Y222905I-1503J0D01*
G01X1227549Y222908D01*
X1227547Y222910D01*
G03X1226913Y223313I-1097J-1026D01*
G01X1226883Y223323D01*
X1226832Y223359D01*
X1226814Y223385D01*
G02X1226775Y223503I161J119D01*
G01Y241469D01*
G02X1226834Y241611I200J0D01*
G01X1227617Y242394D01*
X1227696Y242424D01*
X1227739Y242422D01*
G03X1227802Y242420I70J1208D01*
G01X1237736D01*
G37*
G36*
G01X1226908Y276294D02*
X1301882D01*
G02X1302024Y276235I0J-200D01*
G01X1303308Y274951D01*
G02X1303310Y274949I-140J-142D01*
G02X1303367Y274809I-143J-140D01*
G01Y267385D01*
G02X1303254Y267205I-200J0D01*
G01X1302877Y267023D01*
X1302764Y267036D01*
X1302718Y267072D01*
G03X1301784Y267398I-934J-1175D01*
G03Y264394I0J-1502D01*
G03X1302718Y264720I0J1501D01*
G01X1302764Y264756D01*
X1302877Y264769D01*
X1303254Y264587D01*
G02X1303367Y264407I-87J-180D01*
G01Y257901D01*
X1303313Y257809D01*
X1303268Y257782D01*
X1303266D01*
X1302978Y257613D01*
G02X1302824Y257593I-101J173D01*
G01X1302770Y257608D01*
X1302748Y257620D01*
G03X1302026Y257805I-723J-1319D01*
G01X1302025D01*
G03Y254801I0J-1502D01*
G01X1302026D01*
G03X1302748Y254986I-1J1504D01*
G01X1302770Y254998D01*
X1302824Y255013D01*
G02X1302978Y254993I53J-193D01*
G01X1303267Y254824D01*
G02X1303270Y254822I-109J-167D01*
G02X1303367Y254651I-103J-171D01*
G01Y207177D01*
X1303360Y207152D01*
G03X1303309Y206763I1451J-388D01*
G01Y206755D01*
G03X1303360Y206372I1502J5D01*
G01X1303367Y206346D01*
Y202582D01*
G03X1303426Y202440I200J0D01*
G01X1303847Y202019D01*
G03X1303989Y201960I142J141D01*
G01X1306707D01*
G02X1306740Y201957I-2J-200D01*
G02X1306847Y201903I-32J-197D01*
G01X1307103Y201647D01*
G02X1307162Y201505I-141J-142D01*
G01Y193725D01*
G02X1307104Y193585I-200J1D01*
G01X1307091Y193571D01*
X1306825Y193386D01*
G02X1306711Y193350I-114J164D01*
G01X1306624D01*
X1306593Y193361D01*
G03X1306103Y193443I-490J-1420D01*
G01X1306087D01*
G03X1304601Y191941I16J-1502D01*
G03X1306103Y190439I1502J0D01*
G01X1306106D01*
G03X1306624Y190532I-2J1502D01*
G01X1306670Y190549D01*
X1306767Y190537D01*
X1307076Y190321D01*
G02X1307104Y190298I-113J-166D01*
G01Y190297D01*
G02X1307162Y190157I-142J-141D01*
G01Y165176D01*
G02X1307116Y165048I-200J0D01*
G01X1307110Y165041D01*
X1303636Y161567D01*
X1303608Y161538D01*
X1303534Y161508D01*
X1296520D01*
G02X1296349Y161604I0J200D01*
G01X1296172Y161896D01*
G02X1296156Y161930I172J102D01*
G02X1296167Y162094I188J70D01*
G01X1296170Y162100D01*
X1296187Y162135D01*
G03X1296339Y162788I-1350J658D01*
G01Y162790D01*
Y162815D01*
G03X1295936Y163817I-1502J-22D01*
G01X1295935Y163818D01*
G02X1295879Y163957I144J139D01*
G01Y164268D01*
X1295906Y164338D01*
X1295933Y164366D01*
G03Y166420I-1096J1027D01*
G01X1295906Y166448D01*
X1295879Y166518D01*
Y166868D01*
X1295906Y166938D01*
X1295933Y166966D01*
G03X1296339Y167993I-1096J1027D01*
G03X1295969Y168980I-1501J0D01*
G01X1295945Y169008D01*
X1295920Y169074D01*
Y169412D01*
X1295945Y169478D01*
X1295969Y169506D01*
G03X1296339Y170493I-1131J987D01*
G03X1293335I-1502J0D01*
G03X1293705Y169506I1501J0D01*
G01X1293729Y169478D01*
X1293754Y169412D01*
Y169074D01*
X1293729Y169008D01*
X1293705Y168980D01*
G03X1293335Y167993I1131J-987D01*
G03X1293741Y166966I1502J0D01*
G01X1293768Y166938D01*
X1293795Y166868D01*
Y166518D01*
X1293768Y166448D01*
X1293741Y166420D01*
G03Y164366I1096J-1027D01*
G01X1293768Y164338D01*
X1293795Y164268D01*
Y163918D01*
X1293768Y163849D01*
X1293741Y163820D01*
G03X1293335Y162821I1096J-1027D01*
G01Y162793D01*
G03X1293487Y162134I1502J-1D01*
G01X1293516Y162073D01*
G02X1293518Y161930I-186J-74D01*
G02X1293502Y161896I-188J68D01*
G01X1293325Y161605D01*
X1293298Y161559D01*
X1293207Y161508D01*
X1289583D01*
G02X1289425Y161585I0J200D01*
G01X1289202Y161870D01*
X1289183Y161959D01*
X1289194Y162005D01*
G03X1289239Y162368I-1457J365D01*
G03X1287737Y163870I-1502J0D01*
G03X1286710Y163464I0J-1502D01*
G01X1286682Y163437D01*
X1286612Y163410D01*
X1286262D01*
X1286192Y163437D01*
X1286164Y163464D01*
G03X1285137Y163870I-1027J-1096D01*
G03X1283635Y162368I0J-1502D01*
G03X1283680Y162005I1502J2D01*
G01X1283691Y161959D01*
X1283672Y161870D01*
X1283449Y161585D01*
G02X1283291Y161508I-158J123D01*
G01X1268143D01*
G02X1268001Y161567I0J200D01*
G01X1267345Y162223D01*
G02X1267287Y162364I142J141D01*
G01Y240157D01*
G03X1267228Y240298I-200J-1D01*
G01X1266931Y240595D01*
X1266929Y240598D01*
G03X1266916Y240611I-856J-843D01*
G01X1266915Y240612D01*
X1264448Y243079D01*
G03X1264422Y243104I-845J-853D01*
G01X1264420Y243106D01*
X1264174Y243352D01*
G03X1264034Y243410I-141J-142D01*
G01X1263818D01*
X1263801Y243413D01*
G03X1263600Y243430I-201J-1185D01*
G01X1257005D01*
G02X1256847Y243507I0J200D01*
G01X1256624Y243793D01*
X1256605Y243882D01*
X1256617Y243928D01*
G03X1256663Y244297I-1457J369D01*
G03X1255161Y245799I-1502J0D01*
G03X1254794Y245753I2J-1502D01*
G01X1254738Y245739D01*
X1254631Y245773D01*
X1254323Y246131D01*
X1254305Y246242D01*
X1254327Y246295D01*
G03X1254443Y246874I-1387J579D01*
G03X1252941Y248376I-1502J0D01*
G03X1251912Y247968I0J-1502D01*
G01X1251878Y247936D01*
X1251792Y247909D01*
X1251438Y247958D01*
G02X1251430Y247959I21J199D01*
G02X1251293Y248055I36J197D01*
G03X1249999Y248794I-1294J-763D01*
G03Y245790I0J-1502D01*
G03X1251028Y246198I0J1502D01*
G01X1251062Y246230D01*
X1251148Y246257D01*
X1251502Y246208D01*
G02X1251509Y246207I-25J-198D01*
G02X1251650Y246106I-35J-197D01*
G03X1251653Y246100I180J86D01*
G03X1252941Y245372I1288J775D01*
G03X1253020Y245374I1J1502D01*
G01X1253021D01*
G03X1253083Y245378I-66J1501D01*
G01X1253117Y245382D01*
G03X1253199Y245394I-176J1492D01*
G01X1253200D01*
G03X1253308Y245418I-272J1477D01*
G01X1253364Y245432D01*
X1253471Y245398D01*
X1253779Y245040D01*
X1253796Y244930D01*
X1253774Y244876D01*
G03X1253668Y244474I1387J-581D01*
G01X1253663Y244419D01*
G03X1253658Y244297I1498J-122D01*
G01Y244295D01*
G03X1253704Y243927I1503J1D01*
G01X1253716Y243881D01*
X1253697Y243792D01*
X1253475Y243507D01*
G02X1253317Y243430I-158J123D01*
G01X1249465D01*
G03X1249266Y243413I2J-1201D01*
G01X1249249Y243410D01*
X1248302D01*
X1248256Y243422D01*
X1248237Y243431D01*
X1248235Y243432D01*
G03X1247993Y243523I-648J-1355D01*
G03X1247333Y243559I-410J-1445D01*
G03X1246929Y243430I250J-1481D01*
G01X1246909Y243420D01*
X1246865Y243410D01*
X1245881D01*
X1245864Y243413D01*
G03X1245665Y243430I-201J-1184D01*
G01X1241196D01*
G02X1241029Y243520I0J200D01*
G01X1240858Y243781D01*
G02X1240842Y243971I167J110D01*
G03X1240967Y244571I-1377J600D01*
G01Y244590D01*
G03X1237963I-1502J-19D01*
G01Y244570D01*
G03X1238088Y243971I1502J1D01*
G01X1238107Y243928D01*
X1238103Y243838D01*
X1238082Y243797D01*
G02X1238072Y243781I-175J98D01*
G01X1237902Y243521D01*
X1237874Y243478D01*
X1237786Y243430D01*
X1227804D01*
G02X1227662Y243489I0J200D01*
G01X1226073Y245078D01*
X1226044Y245106D01*
X1226014Y245180D01*
Y275400D01*
G02X1226071Y275540I200J0D01*
G01X1226072Y275541D01*
X1226766Y276235D01*
G02X1226768Y276237I142J-140D01*
G02X1226908Y276294I140J-143D01*
G37*
G36*
G01X1321772Y202336D02*
X1325284D01*
G02X1325425Y202278I0J-200D01*
G01X1327465Y200238D01*
X1327480Y200207D01*
G03X1327519Y200132I1352J655D01*
G01X1327520Y200131D01*
G03X1327535Y200105I1308J738D01*
G01X1327548Y200083D01*
X1327564Y200027D01*
X1327577Y199981D01*
Y197600D01*
G02X1327544Y197490I-200J0D01*
G03Y195840I1254J-825D01*
G02X1327577Y195730I-167J-110D01*
G01Y193600D01*
G02X1327544Y193490I-200J0D01*
G03Y191840I1254J-825D01*
G02X1327577Y191730I-167J-110D01*
G01Y187518D01*
X1327567Y187475D01*
X1327556Y187453D01*
G03Y186103I1355J-675D01*
G01X1327567Y186081D01*
X1327577Y186038D01*
Y181600D01*
G02X1327544Y181490I-200J0D01*
G03Y179840I1254J-825D01*
G02X1327577Y179730I-167J-110D01*
G01Y177600D01*
G02X1327544Y177490I-200J0D01*
G03Y175840I1254J-825D01*
G02X1327577Y175730I-167J-110D01*
G01Y173600D01*
G02X1327544Y173490I-200J0D01*
G03Y171840I1254J-825D01*
G02X1327577Y171730I-167J-110D01*
G01Y169600D01*
G02X1327544Y169490I-200J0D01*
G03Y167840I1254J-825D01*
G02X1327577Y167730I-167J-110D01*
G01Y117138D01*
X1327465Y116958D01*
Y111688D01*
G03X1327495Y111583I200J0D01*
G01X1327546Y111504D01*
G02X1327577Y111396I-169J-107D01*
G01Y109734D01*
G02X1327518Y109592I-200J0D01*
G01X1326575Y108649D01*
G02X1326433Y108590I-142J141D01*
G01X1289761D01*
G02X1289597Y108676I0J200D01*
G03X1286633I-1482J-1027D01*
G02X1286469Y108590I-164J114D01*
G01X1270188D01*
G02X1270046Y108649I0J200D01*
G01X1268987Y109708D01*
X1268962Y109753D01*
X1268955Y109780D01*
G03X1267869Y110866I-1456J-370D01*
G01X1267842Y110873D01*
X1267797Y110898D01*
X1267735Y110960D01*
G02X1267676Y111102I141J142D01*
G01Y114907D01*
X1267763Y115016D01*
X1267832Y115031D01*
G03Y117961I-333J1465D01*
G01X1267763Y117976D01*
X1267676Y118085D01*
Y122963D01*
X1267776Y123076D01*
X1267852Y123085D01*
G03Y126067I-181J1491D01*
G01X1267776Y126076D01*
X1267676Y126189D01*
Y159263D01*
G02X1267735Y159405I200J0D01*
G01X1268598Y160268D01*
G02X1268740Y160327I142J-141D01*
G01X1304257D01*
G03X1304399Y160386I0J200D01*
G01X1308104Y164091D01*
G03X1308163Y164233I-141J142D01*
G01Y165144D01*
G03X1308164Y165174I-1200J55D01*
G01Y190158D01*
G03X1308163Y190189I-1201J-23D01*
G01Y193693D01*
G03X1308164Y193724I-1200J54D01*
G01Y201568D01*
G02X1308222Y201709I200J0D01*
G01X1308790Y202277D01*
G02X1308932Y202336I142J-141D01*
G01X1318632D01*
G02X1318809Y202229I0J-200D01*
G01X1318973Y201916D01*
G02X1318962Y201711I-177J-93D01*
G01X1318961Y201710D01*
G03X1318700Y200873I1241J-846D01*
G01Y200845D01*
G03X1321704I1502J19D01*
G01Y200865D01*
G03X1321443Y201711I-1502J0D01*
G01X1321411Y201757D01*
X1321405Y201867D01*
X1321595Y202229D01*
G02X1321772Y202336I177J-93D01*
G37*
G36*
G01X1303119Y900746D02*
X1303279D01*
G02X1303419Y900689I0J-200D01*
G01X1303420Y900688D01*
X1304402Y899706D01*
X1304429Y899601D01*
X1304414Y899548D01*
G03X1304359Y899161I1347J-389D01*
G03X1305761Y897759I1402J0D01*
G03X1306148Y897814I-2J1402D01*
G01X1306201Y897829D01*
X1306306Y897802D01*
X1310642Y893466D01*
G03X1310784Y893407I142J141D01*
G01X1315210D01*
G02X1315358Y893342I0J-200D01*
G01X1315586Y893094D01*
X1315612Y893016D01*
X1315609Y892973D01*
G03X1315604Y892862I1297J-114D01*
G03X1318208I1302J0D01*
G03X1318173Y893160I-1302J-2D01*
G01X1318168Y893183D01*
Y893207D01*
G02X1318368Y893407I200J0D01*
G01X1318593D01*
G02X1318793Y893207I0J-200D01*
G01Y893183D01*
X1318788Y893160D01*
G03X1318753Y892862I1267J-300D01*
G03X1321357I1302J0D01*
G03X1321322Y893160I-1302J-2D01*
G01X1321317Y893183D01*
Y893207D01*
G02X1321517Y893407I200J0D01*
G01X1321743D01*
G02X1321943Y893207I0J-200D01*
G01Y893183D01*
X1321938Y893160D01*
G03X1321903Y892862I1267J-300D01*
G03X1324507I1302J0D01*
G03X1324472Y893160I-1302J-2D01*
G01X1324467Y893183D01*
Y893207D01*
G02X1324667Y893407I200J0D01*
G01X1324893D01*
G02X1325093Y893207I0J-200D01*
G01Y893183D01*
X1325088Y893160D01*
G03X1325053Y892862I1267J-300D01*
G03X1326355Y891560I1302J0D01*
G03X1327000Y891731I0J1302D01*
G01X1327059Y891765D01*
X1327193Y891747D01*
X1328341Y890599D01*
G02X1328398Y890484I-141J-142D01*
G01X1328403Y890450D01*
X1328390Y890387D01*
X1328373Y890358D01*
G03X1328202Y889712I1131J-645D01*
G03X1329504Y888410I1302J0D01*
G03X1330150Y888581I1J1302D01*
G02X1330276Y888606I100J-173D01*
G02X1330391Y888549I-27J-198D01*
G01X1331491Y887449D01*
G02X1331548Y887334I-141J-142D01*
G01X1331553Y887300D01*
X1331540Y887237D01*
X1331523Y887208D01*
G03X1331352Y886562I1131J-645D01*
G03X1332654Y885260I1302J0D01*
G03X1333300Y885431I1J1302D01*
G02X1333426Y885456I100J-173D01*
G02X1333541Y885399I-27J-198D01*
G01X1334640Y884300D01*
G02X1334697Y884185I-141J-142D01*
G01X1334702Y884151D01*
X1334689Y884088D01*
X1334672Y884059D01*
G03X1334501Y883413I1131J-645D01*
G03X1335803Y882111I1302J0D01*
G03X1336449Y882282I1J1302D01*
G02X1336575Y882307I100J-173D01*
G02X1336690Y882250I-27J-198D01*
G01X1336984Y881956D01*
G02X1336986Y881954I-140J-142D01*
G02X1337043Y881814I-143J-140D01*
G01Y881743D01*
Y881733D01*
G02X1336964Y881583I-200J10D01*
G02X1336943Y881570I-116J163D01*
G01X1336598Y881369D01*
X1336493D01*
X1336446Y881395D01*
G03X1335803Y881565I-643J-1131D01*
G03Y878961I0J-1302D01*
G03X1336446Y879131I0J1301D01*
G01X1336493Y879157D01*
X1336598D01*
X1336943Y878956D01*
G02X1336964Y878943I-95J-176D01*
G02X1337043Y878793I-121J-160D01*
G01Y878594D01*
Y878584D01*
G02X1336964Y878434I-200J10D01*
G02X1336943Y878421I-116J163D01*
G01X1336598Y878220D01*
X1336493D01*
X1336446Y878246D01*
G03X1335803Y878416I-643J-1131D01*
G03Y875812I0J-1302D01*
G03X1336446Y875982I0J1301D01*
G01X1336493Y876008D01*
X1336598D01*
X1336943Y875807D01*
G02X1336964Y875794I-95J-176D01*
G02X1337043Y875644I-121J-160D01*
G01Y870471D01*
G02X1336984Y870329I-200J0D01*
G01X1336329Y869674D01*
X1336301Y869645D01*
X1336227Y869615D01*
X1334156D01*
G02X1334025Y869665I1J200D01*
G01X1334001Y869685D01*
X1333809Y870005D01*
G02X1333803Y870202I171J104D01*
G01X1333804Y870203D01*
Y870204D01*
G03X1333956Y870818I-1150J610D01*
G01Y870836D01*
G03X1331352I-1302J-22D01*
G01Y870818D01*
G03X1331504Y870204I1302J-4D01*
G01Y870203D01*
X1331505Y870202D01*
G02X1331499Y870005I-177J-93D01*
G01X1331323Y869712D01*
G02X1331283Y869665I-170J104D01*
G02X1331152Y869615I-132J150D01*
G01X1331006D01*
G02X1330875Y869665I1J200D01*
G01X1330851Y869685D01*
X1330659Y870005D01*
G02X1330653Y870202I171J104D01*
G01X1330654Y870203D01*
Y870204D01*
G03X1330806Y870818I-1150J610D01*
G01Y870836D01*
G03X1328202I-1302J-22D01*
G01Y870818D01*
G03X1328354Y870204I1302J-4D01*
G01Y870203D01*
X1328355Y870202D01*
G02X1328349Y870005I-177J-93D01*
G01X1328173Y869712D01*
G02X1328133Y869665I-170J104D01*
G02X1328002Y869615I-132J150D01*
G01X1327857D01*
G02X1327726Y869665I1J200D01*
G01X1327702Y869685D01*
X1327510Y870005D01*
G02X1327504Y870202I171J104D01*
G01X1327505Y870203D01*
Y870204D01*
G03X1327657Y870818I-1150J610D01*
G01Y870836D01*
G03X1325053I-1302J-22D01*
G01Y870818D01*
G03X1325205Y870204I1302J-4D01*
G01Y870203D01*
X1325206Y870202D01*
G02X1325200Y870005I-177J-93D01*
G01X1325024Y869712D01*
G02X1324984Y869665I-170J104D01*
G02X1324853Y869615I-132J150D01*
G01X1324707D01*
G02X1324576Y869665I1J200D01*
G01X1324552Y869685D01*
X1324360Y870005D01*
G02X1324354Y870202I171J104D01*
G01X1324355Y870203D01*
Y870204D01*
G03X1324507Y870818I-1150J610D01*
G01Y870836D01*
G03X1321903I-1302J-22D01*
G01Y870818D01*
G03X1322055Y870204I1302J-4D01*
G01Y870203D01*
X1322056Y870202D01*
G02X1322050Y870005I-177J-93D01*
G01X1321874Y869712D01*
G02X1321834Y869665I-170J104D01*
G02X1321703Y869615I-132J150D01*
G01X1321557D01*
G02X1321426Y869665I1J200D01*
G01X1321402Y869685D01*
X1321210Y870005D01*
G02X1321204Y870202I171J104D01*
G01X1321205Y870203D01*
Y870204D01*
G03X1321357Y870818I-1150J610D01*
G01Y870836D01*
G03X1318753I-1302J-22D01*
G01Y870818D01*
G03X1318905Y870204I1302J-4D01*
G01Y870203D01*
X1318906Y870202D01*
G02X1318900Y870005I-177J-93D01*
G01X1318724Y869712D01*
G02X1318684Y869665I-170J104D01*
G02X1318553Y869615I-132J150D01*
G01X1312168D01*
G02X1312147Y869616I-1J200D01*
G02X1312015Y869687I22J199D01*
G02X1312000Y869708I155J126D01*
G01X1311791Y870035D01*
X1311784Y870137D01*
X1311806Y870183D01*
G03X1311937Y870775I-1272J592D01*
G03X1309133I-1402J0D01*
G03X1309264Y870183I1403J0D01*
G01X1309286Y870137D01*
X1309279Y870035D01*
X1309070Y869708D01*
G02X1309055Y869687I-170J105D01*
G02X1308923Y869616I-154J128D01*
G02X1308902Y869615I-20J199D01*
G01X1285060D01*
G02X1284918Y869674I0J200D01*
G01X1280850Y873742D01*
X1280826Y873860D01*
X1280849Y873916D01*
G03X1280962Y874487I-1389J572D01*
G03X1280253Y875763I-1503J0D01*
G01X1280231Y875776D01*
X1280198Y875811D01*
X1280138Y875915D01*
G02X1280111Y876015I173J100D01*
G01Y877959D01*
G02X1280138Y878059I200J0D01*
G01X1280197Y878163D01*
X1280231Y878197D01*
X1280253Y878211D01*
G03X1280817Y878842I-793J1276D01*
G01X1280836Y878883D01*
X1280905Y878939D01*
X1281294Y879035D01*
X1281381Y879018D01*
X1281417Y878990D01*
G03X1282317Y878691I899J1203D01*
G03X1283819Y880193I0J1502D01*
G01Y880214D01*
X1283818Y880271D01*
X1283875Y880367D01*
X1284289Y880587D01*
X1284400Y880581D01*
X1284447Y880548D01*
G03X1285302Y880281I855J1235D01*
G03X1283800Y881783I0J1502D01*
G01Y881762D01*
X1283801Y881705D01*
X1283744Y881609D01*
X1283330Y881389D01*
X1283219Y881395D01*
X1283172Y881428D01*
G03X1282317Y881695I-855J-1235D01*
G03X1280961Y880838I0J-1501D01*
G01X1280941Y880797D01*
X1280872Y880741D01*
X1280483Y880645D01*
X1280397Y880663D01*
X1280360Y880690D01*
G03X1280253Y880763I-899J-1203D01*
G01X1280231Y880777D01*
X1280197Y880811D01*
X1280138Y880915D01*
G02X1280111Y881015I173J100D01*
G01Y882959D01*
G02X1280138Y883059I200J0D01*
G01X1280197Y883163D01*
X1280231Y883197D01*
X1280253Y883211D01*
G03Y885763I-794J1276D01*
G01X1280231Y885777D01*
X1280197Y885811D01*
X1280138Y885915D01*
G02X1280111Y886015I173J100D01*
G01Y887959D01*
G02X1280138Y888059I200J0D01*
G01X1280197Y888163D01*
X1280231Y888197D01*
X1280253Y888211D01*
G03Y890763I-794J1276D01*
G01X1280231Y890777D01*
X1280197Y890811D01*
X1280138Y890915D01*
G02X1280111Y891015I173J100D01*
G01Y896492D01*
G02X1280168Y896632I200J0D01*
G01X1280169Y896633D01*
X1281108Y897572D01*
G02X1281360Y897598I142J-141D01*
G03X1282169Y897352I824J1257D01*
G01X1282184D01*
G03X1283676Y898678I0J1502D01*
G01X1283682Y898733D01*
G03X1283687Y898854I-1498J123D01*
G03X1283440Y899679I-1503J0D01*
G02X1283466Y899930I167J109D01*
G01X1284223Y900687D01*
G02X1284225Y900689I142J-140D01*
G02X1284365Y900746I140J-143D01*
G01X1286952D01*
G02X1287134Y900630I0J-200D01*
G01Y900629D01*
G03X1289866I1366J625D01*
G01Y900630D01*
G02X1290048Y900746I182J-84D01*
G01X1290484D01*
X1290581Y900686D01*
X1290606Y900634D01*
G03X1293304I1349J661D01*
G01X1293329Y900686D01*
X1293426Y900746D01*
X1300195D01*
G02X1300376Y900631I0J-200D01*
G01X1300555Y900249D01*
X1300540Y900135D01*
X1300503Y900090D01*
G03X1300155Y899129I1153J-961D01*
G03X1303159I1502J0D01*
G03X1302811Y900090I-1501J0D01*
G01X1302774Y900135D01*
X1302759Y900249D01*
X1302938Y900631D01*
G02X1303119Y900746I181J-85D01*
G37*
G36*
G01X1311048Y1215938D02*
G03X1311237Y1215926I189J1490D01*
G03X1312576Y1216745I0J1504D01*
G01X1312602Y1216795D01*
X1312698Y1216854D01*
X1313707D01*
G02X1313734Y1216852I-1J-200D01*
G01X1313775Y1216846D01*
X1313815Y1216835D01*
X1313879Y1216783D01*
X1313899Y1216745D01*
Y1216744D01*
G03X1316575I1338J685D01*
G01Y1216746D01*
G02X1316648Y1216824I177J-93D01*
G01X1316649D01*
G02X1316754Y1216854I105J-170D01*
G01X1317707D01*
G02X1317734Y1216852I-1J-200D01*
G01X1317775Y1216846D01*
X1317815Y1216835D01*
X1317879Y1216783D01*
X1317899Y1216745D01*
Y1216744D01*
G03X1320575I1338J685D01*
G01Y1216746D01*
G02X1320648Y1216824I177J-93D01*
G01X1320649D01*
G02X1320754Y1216854I105J-170D01*
G01X1321707D01*
G02X1321734Y1216852I-1J-200D01*
G01X1321775Y1216846D01*
X1321815Y1216835D01*
X1321879Y1216783D01*
X1321899Y1216745D01*
Y1216744D01*
G03X1324575I1338J685D01*
G01Y1216746D01*
G02X1324648Y1216824I177J-93D01*
G01X1324649D01*
G02X1324754Y1216854I105J-170D01*
G01X1325707D01*
G02X1325734Y1216852I-1J-200D01*
G01X1325775Y1216846D01*
X1325815Y1216835D01*
X1325879Y1216783D01*
X1325899Y1216745D01*
Y1216744D01*
G03X1328575I1338J685D01*
G01Y1216746D01*
G02X1328648Y1216824I177J-93D01*
G01X1328649D01*
G02X1328754Y1216854I105J-170D01*
G01X1329707D01*
G02X1329734Y1216852I-1J-200D01*
G01X1329775Y1216846D01*
X1329815Y1216835D01*
X1329879Y1216783D01*
X1329899Y1216745D01*
Y1216744D01*
G03X1332575I1338J685D01*
G01Y1216746D01*
G02X1332648Y1216824I177J-93D01*
G01X1332649D01*
G02X1332754Y1216854I105J-170D01*
G01X1333707D01*
G02X1333734Y1216852I-1J-200D01*
G01X1333775Y1216846D01*
X1333815Y1216835D01*
X1333879Y1216783D01*
X1333899Y1216745D01*
Y1216744D01*
G03X1336575I1338J685D01*
G01Y1216746D01*
G02X1336648Y1216824I177J-93D01*
G01X1336649D01*
G02X1336754Y1216854I105J-170D01*
G01X1337707D01*
G02X1337734Y1216852I-1J-200D01*
G01X1337775Y1216846D01*
X1337815Y1216835D01*
X1337879Y1216783D01*
X1337899Y1216745D01*
Y1216744D01*
G03X1340575I1338J685D01*
G01Y1216746D01*
G02X1340648Y1216824I177J-93D01*
G01X1340649D01*
G02X1340754Y1216854I105J-170D01*
G01X1341707D01*
G02X1341734Y1216852I-1J-200D01*
G01X1341775Y1216846D01*
X1341815Y1216835D01*
X1341879Y1216783D01*
X1341899Y1216745D01*
Y1216744D01*
G03X1344575I1338J685D01*
G01Y1216746D01*
G02X1344648Y1216824I177J-93D01*
G01X1344649D01*
G02X1344754Y1216854I105J-170D01*
G01X1345707D01*
G02X1345734Y1216852I-1J-200D01*
G01X1345775Y1216846D01*
X1345815Y1216835D01*
X1345879Y1216783D01*
X1345899Y1216745D01*
Y1216744D01*
G03X1348575I1338J685D01*
G01Y1216746D01*
G02X1348648Y1216824I177J-93D01*
G01X1348649D01*
G02X1348754Y1216854I105J-170D01*
G01X1408056D01*
X1408096Y1216835D01*
G03X1408736Y1216692I640J1359D01*
G03X1409376Y1216835I0J1502D01*
G01X1409416Y1216854D01*
X1412056D01*
X1412096Y1216835D01*
G03X1412736Y1216692I640J1359D01*
G03X1413376Y1216835I0J1502D01*
G01X1413416Y1216854D01*
X1416056D01*
X1416096Y1216835D01*
G03X1416736Y1216692I640J1359D01*
G03X1417376Y1216835I0J1502D01*
G01X1417416Y1216854D01*
X1420056D01*
X1420096Y1216835D01*
G03X1420736Y1216692I640J1359D01*
G03X1421376Y1216835I0J1502D01*
G01X1421416Y1216854D01*
X1424056D01*
X1424096Y1216835D01*
G03X1424736Y1216692I640J1359D01*
G03X1425376Y1216835I0J1502D01*
G01X1425416Y1216854D01*
X1428056D01*
X1428096Y1216835D01*
G03X1428736Y1216692I640J1359D01*
G03X1429376Y1216835I0J1502D01*
G01X1429416Y1216854D01*
X1432056D01*
X1432096Y1216835D01*
G03X1432736Y1216692I640J1359D01*
G03X1433376Y1216835I0J1502D01*
G01X1433416Y1216854D01*
X1436056D01*
X1436096Y1216835D01*
G03X1436736Y1216692I640J1359D01*
G03X1437376Y1216835I0J1502D01*
G01X1437416Y1216854D01*
X1440056D01*
X1440096Y1216835D01*
G03X1440736Y1216692I640J1359D01*
G03X1441376Y1216835I0J1502D01*
G01X1441416Y1216854D01*
X1444775D01*
G02X1444915Y1216797I0J-200D01*
G01X1444916Y1216796D01*
X1458469Y1203243D01*
G02X1458504Y1203195I-142J-140D01*
G01X1460436Y1199581D01*
G03X1461123Y1198656I3461J1853D01*
G01X1471238Y1188541D01*
G03X1471872Y1188026I2779J2773D01*
G02X1471963Y1187859I-109J-168D01*
G01Y1186384D01*
G02X1471905Y1186243I-200J0D01*
G01X1471118Y1185455D01*
X1470486Y1184823D01*
X1470483Y1184821D01*
G03X1470118Y1183961I837J-863D01*
G01Y1120548D01*
G03X1470285Y1119938I1202J1D01*
G01X1470298Y1119917D01*
X1470308Y1119886D01*
G02X1470303Y1119749I-190J-62D01*
G01X1470274Y1119678D01*
X1470250Y1119651D01*
G03Y1117657I1125J-997D01*
G01X1470274Y1117630D01*
X1470303Y1117559D01*
G02X1470308Y1117422I-185J-75D01*
G01X1470298Y1117391D01*
X1470285Y1117370D01*
G03X1470118Y1116760I1035J-611D01*
G01Y1100764D01*
G03X1470134Y1100686I200J0D01*
G01X1470149Y1100650D01*
X1470352Y1100447D01*
X1470755Y1100043D01*
X1471904Y1098894D01*
G02X1471963Y1098753I-141J-142D01*
G01Y1076448D01*
G02X1471954Y1076389I-200J0D01*
G01X1471931Y1076315D01*
X1471918Y1076294D01*
G03X1469331Y1068854I16073J-9759D01*
G01X1469327Y1068820D01*
X1469298Y1068761D01*
X1457049Y1056512D01*
G03X1456990Y1056370I141J-142D01*
G01Y1032273D01*
G02X1456931Y1032131I-200J0D01*
G01X1455133Y1030333D01*
X1455105Y1030304D01*
X1455031Y1030274D01*
X1435197D01*
G03Y1026470I0J-1902D01*
G01X1450305D01*
G02X1450587Y1025787I-1J-400D01*
G01X1450538Y1025738D01*
G03X1450479Y1025596I141J-142D01*
G01Y1006325D01*
G02X1450420Y1006183I-200J0D01*
G01X1428411Y984174D01*
X1428383Y984145D01*
X1428309Y984115D01*
X1421445D01*
G02X1421261Y984238I1J200D01*
G01X1421237Y984295D01*
X1421260Y984413D01*
X1431746Y994898D01*
G03X1432128Y995822I-924J923D01*
G01Y1018267D01*
G03X1431746Y1019191I-1306J1D01*
G01X1430290Y1020647D01*
X1430265Y1020689D01*
X1430257Y1020712D01*
G03X1428823Y1021768I-1434J-446D01*
G03X1427321Y1020266I0J-1502D01*
G03X1428377Y1018832I1502J0D01*
G01X1428400Y1018824D01*
X1428442Y1018799D01*
X1428839Y1018402D01*
G02X1428886Y1018192I-141J-142D01*
G01X1428757Y1017838D01*
X1428665Y1017767D01*
X1428607Y1017762D01*
G03X1427238Y1016266I133J-1496D01*
G03X1428730Y1014764I1502J0D01*
G01X1428741D01*
G03X1429067Y1014800I-1J1502D01*
G01X1429069D01*
G02X1429237Y1014761I43J-195D01*
G01X1429440Y1014598D01*
G02X1429516Y1014442I-124J-157D01*
G01Y1002590D01*
G02X1429440Y1002434I-200J1D01*
G01X1429237Y1002271D01*
G02X1429069Y1002232I-125J156D01*
G01X1429067D01*
G03X1428749Y1002268I-327J-1466D01*
G01X1428730D01*
G03Y999264I10J-1502D01*
G01X1428741D01*
G03X1429067Y999300I-1J1502D01*
G01X1429069D01*
G02X1429237Y999261I43J-195D01*
G01X1429440Y999098D01*
G02X1429516Y998942I-124J-157D01*
G01Y998611D01*
G02X1429446Y998460I-200J1D01*
G01X1429256Y998296D01*
G02X1429179Y998255I-130J152D01*
G01X1429135Y998243D01*
G03X1428864Y998268I-273J-1477D01*
G03X1427430Y997212I0J-1502D01*
G01X1427422Y997189D01*
X1427397Y997147D01*
X1416152Y985902D01*
G02X1415970Y985848I-141J142D01*
G01X1415638Y985917D01*
X1415562Y985982D01*
X1415543Y986030D01*
G03X1414143Y986988I-1400J-544D01*
G03X1412641Y985510I0J-1502D01*
G01Y985485D01*
G03X1412851Y984720I1502J1D01*
G01X1412852Y984718D01*
G02X1412853Y984518I-173J-101D01*
G01X1412681Y984216D01*
G02X1412507Y984115I-174J99D01*
G01X1320188D01*
G02X1320046Y984174I0J200D01*
G01X1319130Y985090D01*
X1319101Y985118D01*
X1319071Y985192D01*
Y987998D01*
G02X1319073Y988023I200J-3D01*
G02X1319124Y988133I198J-25D01*
G02X1319146Y988153I145J-137D01*
G01X1319423Y988377D01*
X1319511Y988398D01*
X1319556Y988388D01*
G03X1319874Y988354I318J1468D01*
G01X1319900D01*
G03X1320394Y988446I-24J1502D01*
G01X1320438Y988463D01*
X1320531Y988453D01*
X1320878Y988230D01*
X1320926Y988150D01*
X1320930Y988103D01*
G03X1322427Y986719I1497J118D01*
G03X1323926Y988132I0J1502D01*
G01X1323929Y988176D01*
X1323970Y988253D01*
X1324283Y988490D01*
X1324370Y988509D01*
X1324413Y988499D01*
G03X1324735Y988464I322J1467D01*
G01X1324745D01*
G03X1325235Y988549I-8J1502D01*
G01X1325280Y988565D01*
X1325372Y988554D01*
X1325719Y988322D01*
X1325764Y988241D01*
X1325767Y988193D01*
G03X1327267Y986769I1500J78D01*
G03X1328221Y987111I0J1502D01*
G01X1328250Y987135D01*
X1328321Y987158D01*
X1328666Y987139D01*
X1328734Y987108D01*
X1328761Y987081D01*
G03X1329834Y986630I1073J1051D01*
G03X1330885Y987058I1J1502D01*
G01X1330912Y987085D01*
X1330980Y987114D01*
X1331326Y987125D01*
X1331396Y987101D01*
X1331425Y987076D01*
G03X1332404Y986713I979J1139D01*
G03X1333906Y988215I0J1502D01*
G03X1333883Y988476I-1502J-1D01*
G01X1333874Y988529D01*
X1333910Y988629D01*
X1334255Y988922D01*
X1334359Y988941D01*
X1334410Y988923D01*
G03X1334909Y988838I498J1417D01*
G03X1335486Y988953I1J1502D01*
G01X1335537Y988975D01*
X1335645Y988960D01*
X1336005Y988672D01*
X1336044Y988570D01*
X1336034Y988516D01*
G03X1336012Y988259I1480J-256D01*
G03X1337514Y989761I1502J0D01*
G03X1336937Y989646I-1J-1502D01*
G01X1336886Y989624D01*
X1336778Y989639D01*
X1336418Y989927D01*
X1336379Y990029D01*
X1336389Y990083D01*
G03X1336411Y990340I-1480J256D01*
G03X1333407I-1502J0D01*
G03X1333430Y990079I1502J1D01*
G01X1333439Y990026D01*
X1333403Y989926D01*
X1333058Y989633D01*
X1332954Y989614D01*
X1332903Y989632D01*
G03X1332404Y989717I-498J-1417D01*
G03X1331292Y989225I0J-1503D01*
G02X1331150Y989159I-149J134D01*
G01X1331024Y989155D01*
G02X1330879Y989211I-6J200D01*
G03X1330781Y989298I-1045J-1079D01*
G03X1331005Y990088I-1278J789D01*
G03X1330939Y990529I-1502J1D01*
G02Y990647I191J59D01*
G03X1331005Y991088I-1436J440D01*
G03X1328001I-1502J0D01*
G03X1328067Y990646I1502J-2D01*
G02Y990529I-191J-58D01*
G03X1328002Y990133I1436J-439D01*
G01Y990132D01*
X1328000Y990088D01*
X1327981Y990050D01*
G02X1327928Y989982I-181J86D01*
G01X1327658Y989763D01*
X1327576Y989742D01*
X1327532Y989750D01*
G03X1327267Y989773I-262J-1479D01*
G03X1326767Y989688I-2J-1502D01*
G01X1326722Y989672D01*
X1326630Y989683D01*
X1326283Y989915D01*
X1326238Y989996D01*
X1326235Y990044D01*
G03X1324735Y991468I-1500J-78D01*
G03X1323236Y990055I0J-1502D01*
G01X1323233Y990011D01*
X1323192Y989934D01*
X1322879Y989697D01*
X1322792Y989678D01*
X1322749Y989688D01*
G03X1322427Y989723I-322J-1467D01*
G01X1322426D01*
G03X1321907Y989631I-1J-1502D01*
G01X1321863Y989614D01*
X1321770Y989624D01*
X1321423Y989847D01*
X1321375Y989927D01*
X1321371Y989974D01*
G03X1319874Y991358I-1497J-118D01*
G03X1319556Y991324I0J-1502D01*
G01X1319511Y991314D01*
X1319423Y991335D01*
X1319146Y991559D01*
G02X1319124Y991579I123J157D01*
G02X1319073Y991689I147J135D01*
G02X1319071Y991714I198J28D01*
G01Y994278D01*
G03X1319041Y994383I-200J0D01*
G01X1319027Y994407D01*
X1319012Y994459D01*
Y1014429D01*
G02X1319069Y1014569I200J0D01*
G01X1319070Y1014570D01*
X1322941Y1018441D01*
G03X1323000Y1018583I-141J142D01*
G01Y1033417D01*
G02X1323057Y1033557I200J0D01*
G01X1323058Y1033558D01*
X1325441Y1035941D01*
G03X1325500Y1036083I-141J142D01*
G01Y1041917D01*
G03X1325441Y1042059I-200J0D01*
G01X1322559Y1044941D01*
G03X1322417Y1045000I-142J-141D01*
G01X1314583D01*
G02X1314441Y1045059I0J200D01*
G01X1312787Y1046713D01*
X1312758Y1046741D01*
X1312728Y1046815D01*
Y1051893D01*
G02X1312738Y1051955I200J0D01*
G01X1315067Y1059059D01*
G03X1315109Y1059195I-3698J1217D01*
G01X1315110Y1059199D01*
X1315243Y1059601D01*
G03X1315253Y1059661I-190J63D01*
G01X1315257Y1060080D01*
Y1060092D01*
G03X1315261Y1060271I-3889J176D01*
G01Y1060273D01*
G03X1315260Y1060302I-3890J-120D01*
G01Y1060306D01*
X1315432Y1076344D01*
Y1076346D01*
G03X1315434Y1076467I-3889J125D01*
G01Y1076750D01*
G03X1315003Y1078529I-3892J-1D01*
G01X1306500Y1095067D01*
X1306257Y1095537D01*
Y1096021D01*
G03X1306198Y1096163I-200J0D01*
G01X1282914Y1119447D01*
G02X1282855Y1119589I141J142D01*
G01Y1135612D01*
X1282923Y1135712D01*
X1282980Y1135735D01*
G03Y1138523I-559J1394D01*
G01X1282923Y1138546D01*
X1282855Y1138646D01*
Y1145326D01*
X1282953Y1145438D01*
X1283029Y1145448D01*
G03X1284332Y1146937I-199J1489D01*
G03X1283584Y1148236I-1502J0D01*
G02X1283484Y1148409I100J173D01*
G01Y1148615D01*
G02X1283584Y1148788I200J0D01*
G03X1284332Y1150087I-754J1299D01*
G03X1283707Y1151307I-1503J0D01*
G01X1283669Y1151334D01*
X1283626Y1151414D01*
X1283615Y1151675D01*
G02X1283673Y1151824I200J8D01*
G01X1304425Y1172576D01*
G03X1304484Y1172718I-141J142D01*
G01Y1209401D01*
G02X1304543Y1209543I200J0D01*
G01X1310881Y1215881D01*
G02X1311048Y1215938I141J-141D01*
G37*
G36*
G01X1406555Y54588D02*
X1435515D01*
X1435890Y54213D01*
Y52966D01*
X1435515Y52591D01*
X1406555D01*
G03X1400618Y46654I0J-5937D01*
G01Y7874D01*
G02X1394744Y2000I-5874J0D01*
G01X1299862D01*
G02X1293988Y7874I0J5874D01*
G01Y46654D01*
G03X1292425Y50669I-5938J0D01*
G01Y50696D01*
X1292470Y50741D01*
X1294823D01*
X1294895Y50669D01*
G02X1295986Y46654I-6842J-4015D01*
G01Y7874D01*
G03X1299862Y3998I3876J0D01*
G01X1394744D01*
G03X1398620Y7874I0J3876D01*
G01Y46654D01*
G02X1406555Y54588I7935J-1D01*
G37*
G36*
G01X1306648Y797543D02*
X1300318D01*
G02X1300142Y797647I-1J200D01*
G01X1299947Y798005D01*
X1299951Y798113D01*
X1299982Y798160D01*
G03X1300222Y798975I-1262J815D01*
G03X1298720Y800477I-1502J0D01*
G03X1297407Y799705I0J-1503D01*
G01X1297382Y799659D01*
X1297294Y799605D01*
X1296850Y799584D01*
X1296758Y799629D01*
X1296728Y799673D01*
G03X1295491Y800323I-1237J-852D01*
G03X1294714Y800106I1J-1502D01*
G01X1294667Y800078D01*
X1294560Y800076D01*
X1294209Y800274D01*
G02X1294107Y800449I98J174D01*
G01Y810317D01*
G02X1294166Y810459I200J0D01*
G01X1295172Y811465D01*
G02X1295314Y811524I142J-141D01*
G01X1301043D01*
G02X1301172Y811477I0J-200D01*
G03X1302140Y811123I968J1148D01*
G03X1303108Y811477I0J1502D01*
G02X1303237Y811524I129J-153D01*
G01X1303797D01*
X1304114Y811841D01*
Y813315D01*
X1304514Y813715D01*
X1306368D01*
X1308670Y811413D01*
Y810639D01*
Y799482D01*
X1306790Y797602D01*
G02X1306648Y797543I-142J141D01*
G37*
G36*
G01X1300743Y978507D02*
G02X1300772Y978505I1J-200D01*
G01X1309552Y969725D01*
G03X1311000Y968622I1448J399D01*
G03X1312502Y970124I0J1502D01*
G03X1312342Y970797I-1502J-2D01*
G01Y970798D01*
X1312341Y970800D01*
G02X1312351Y970993I180J87D01*
G01X1312529Y971282D01*
G02X1312580Y971338I171J-104D01*
G01X1315214D01*
X1320467Y966085D01*
X1320436Y965839D01*
G02X1320340Y965692I-198J25D01*
G01X1320339Y965691D01*
G03X1319602Y964398I766J-1293D01*
G03X1321104Y962896I1502J0D01*
G03X1322397Y963633I0J1503D01*
G01X1322398Y963634D01*
G02X1322545Y963730I172J-102D01*
G01X1322791Y963761D01*
X1324244Y962308D01*
Y961186D01*
G03X1324048Y960445I1306J-742D01*
G03X1325550Y958943I1502J0D01*
G03X1326548Y959323I0J1502D01*
G01X1326551Y959326D01*
G02X1326625Y959366I130J-152D01*
G01X1326669Y959379D01*
X1327064Y959317D01*
X1327138Y959267D01*
X1327161Y959227D01*
G03X1328457Y958484I1296J759D01*
G03Y961488I0J1502D01*
G03X1327459Y961108I0J-1502D01*
G01X1327456Y961105D01*
G02X1327382Y961065I-130J152D01*
G01X1327338Y961052D01*
X1326943Y961114D01*
X1326868Y961165D01*
X1326856Y961186D01*
Y963390D01*
X1326662Y963584D01*
G03X1326446Y963873I-1112J-606D01*
G01X1324461Y965857D01*
G02X1324403Y966009I142J141D01*
G01X1324422Y966349D01*
X1324460Y966424D01*
X1324494Y966451D01*
G03X1325056Y967623I-941J1172D01*
G03X1323554Y969125I-1502J0D01*
G03X1322382Y968563I0J-1503D01*
G01X1322355Y968529D01*
X1322280Y968491D01*
X1321940Y968472D01*
G02X1321788Y968530I-11J200D01*
G01X1316779Y973540D01*
G03X1316490Y973756I-895J-896D01*
G01X1316296Y973950D01*
X1311979D01*
X1308018Y977911D01*
G02X1308020Y977985I197J32D01*
G01X1308104Y978363D01*
X1308171Y978440D01*
X1308219Y978458D01*
G03X1308301Y978490I-505J1415D01*
G01X1308339Y978507D01*
X1416773D01*
G02X1416913Y978450I0J-200D01*
G01X1417923Y977440D01*
X1417953Y977359D01*
X1417949Y977314D01*
G03X1417944Y977192I1497J-122D01*
G03X1419446Y975690I1502J0D01*
G03X1419568Y975695I0J1502D01*
G01X1419613Y975699D01*
X1419694Y975669D01*
X1420953Y974410D01*
G02X1420955Y974408I-140J-142D01*
G02X1421012Y974268I-143J-140D01*
G01Y967455D01*
G03X1421027Y967379I200J0D01*
G01X1421071Y967275D01*
Y959908D01*
G03X1420699Y959955I-373J-1456D01*
G03X1419196Y958452I0J-1503D01*
G03X1419199Y958352I1503J-5D01*
G03X1419196Y958252I1500J-95D01*
G03X1420699Y956749I1503J0D01*
G03X1421071Y956796I-1J1503D01*
G01Y943642D01*
G02X1420391Y943357I-400J0D01*
G03X1419337Y943788I-1054J-1073D01*
G03X1418116Y943161I0J-1502D01*
G02X1417465I-325J233D01*
G03X1416244Y943788I-1221J-875D01*
G03Y940782I0J-1503D01*
G03X1417465Y941409I0J1502D01*
G02X1418116I326J-233D01*
G03X1419337Y940782I1221J875D01*
G03X1420391Y941213I0J1504D01*
G02X1421071Y940928I280J-285D01*
G01Y908278D01*
X1421041Y908204D01*
X1421012Y908176D01*
X1418916Y906080D01*
G02X1418774Y906021I-142J141D01*
G01X1410264D01*
X1410190Y906051D01*
X1410162Y906080D01*
X1406125Y910117D01*
G02X1406080Y910331I141J141D01*
G01X1406081Y910333D01*
Y910334D01*
G03X1406191Y910897I-1391J564D01*
G03X1404689Y912399I-1502J0D01*
G03X1403194Y911042I0J-1502D01*
G01X1403187Y910965D01*
X1403072Y910861D01*
X1389074D01*
G02X1388796Y911549I0J400D01*
G03X1389255Y912629I-1043J1081D01*
G03X1386251I-1502J0D01*
G03X1387169Y911245I1502J0D01*
G01X1387225Y911222D01*
X1387291Y911122D01*
Y911061D01*
G02X1387091Y910861I-200J0D01*
G01X1386724D01*
G02X1386582Y910920I0J200D01*
G01X1386017Y911485D01*
G03X1385875Y911544I-142J-141D01*
G01X1362250D01*
G02X1362108Y911603I0J200D01*
G01X1359762Y913949D01*
G03X1359620Y914008I-142J-141D01*
G01X1348509D01*
G02X1348367Y914067I0J200D01*
G01X1338965Y923468D01*
G02X1338910Y923647I141J141D01*
G01X1338973Y923973D01*
G02X1339089Y924119I197J-37D01*
G01X1339090D01*
G03X1340002Y925500I-590J1381D01*
G03X1338500Y927002I-1502J0D01*
G03X1337119Y926091I0J-1502D01*
G01Y926089D01*
G02X1336973Y925973I-183J81D01*
G01X1336647Y925910D01*
G02X1336468Y925965I-38J196D01*
G01X1334107Y928326D01*
G03X1333965Y928385I-142J-141D01*
G01X1321952D01*
X1321524Y928813D01*
X1321361D01*
X1321168Y929006D01*
X1312825D01*
G03X1311325Y930421I-1500J-88D01*
G03X1309822Y928918I0J-1503D01*
G03X1309826Y928813I1503J5D01*
G02X1309427Y928385I-399J-28D01*
G01X1306569D01*
X1306453Y928498D01*
X1306451Y928580D01*
G03X1304949Y930048I-1502J-34D01*
G03X1303985Y929698I0J-1503D01*
G01X1303857Y929651D01*
G02X1303715Y929710I0J200D01*
G01X1299488Y933937D01*
Y936385D01*
X1299512Y936409D01*
X1299571D01*
G03X1300882Y935641I1311J735D01*
G03X1301062Y938636I0J1503D01*
G01X1300932Y938766D01*
X1301451Y939286D01*
Y942399D01*
X1299817Y944033D01*
X1296972D01*
X1296416Y944589D01*
Y953256D01*
X1295666Y954006D01*
Y969635D01*
G03X1295342Y970802I-2267J-1D01*
G01X1295328Y970825D01*
X1295306Y970902D01*
G02X1295298Y970957I192J56D01*
G01Y977227D01*
G02X1295355Y977367I200J0D01*
G01X1296436Y978448D01*
G02X1296438Y978450I142J-140D01*
G02X1296578Y978507I140J-143D01*
G01X1300743D01*
G37*
G36*
G01X1304569Y275932D02*
X1326504D01*
X1326578Y275902D01*
X1326606Y275873D01*
X1327217Y275262D01*
G02X1327276Y275120I-141J-142D01*
G01Y205020D01*
X1327246Y204946D01*
X1327217Y204918D01*
X1325696Y203397D01*
G02X1325554Y203338I-142J141D01*
G01X1304687D01*
X1304613Y203368D01*
X1304585Y203397D01*
X1304427Y203555D01*
G02X1304369Y203696I142J141D01*
G01Y204858D01*
G02X1304429Y205001I200J0D01*
G01X1304663Y205230D01*
X1304737Y205259D01*
X1304777Y205258D01*
X1304811D01*
G03Y208262I0J1502D01*
G01X1304777D01*
X1304737Y208261D01*
X1304663Y208290D01*
X1304429Y208519D01*
G02X1304369Y208661I140J143D01*
G01Y255107D01*
G02X1304487Y255289I200J0D01*
G01X1304811Y255436D01*
G02X1304982Y255432I81J-183D01*
G01X1305032Y255407D01*
X1305051Y255392D01*
G03X1306025Y255033I975J1143D01*
G03Y258037I0J1502D01*
G03X1305051Y257678I1J-1502D01*
G01X1305032Y257663D01*
X1304982Y257638D01*
G02X1304811Y257634I-90J179D01*
G01X1304487Y257781D01*
G02X1304369Y257963I82J182D01*
G01Y275732D01*
G02X1304569Y275932I200J0D01*
G37*
G36*
G01X1588069Y441464D02*
G02X1588033Y441414I-178J90D01*
G01X1588022Y441403D01*
Y299498D01*
G03X1588081Y299356I200J0D01*
G01X1588358Y299079D01*
G03X1588370Y299066I889J809D01*
G01X1588371Y299065D01*
G03X1588374Y299062I851J848D01*
G01X1591689Y295747D01*
X1591695Y295742D01*
X1591706Y295731D01*
X1591742Y295716D01*
G03X1591820Y295700I78J184D01*
G01X1592486D01*
G02X1592500Y295699I-7J-199D01*
G01X1592507D01*
G02X1592629Y295646I-14J-200D01*
G01X1593290Y294984D01*
G03X1593431Y294926I141J142D01*
G01X1594588D01*
G02X1594630Y294922I2J-200D01*
G01X1594637Y294920D01*
X1594658Y294915D01*
G02X1594784Y294824I-45J-195D01*
G01X1594809Y294777D01*
X1594810Y294775D01*
X1594952Y294512D01*
G02X1594970Y294446I-181J-85D01*
G01X1594911Y294359D01*
G03X1594638Y293478I1286J-881D01*
G01Y293477D01*
G03X1597756I1559J0D01*
G01Y293479D01*
G03X1597483Y294360I-1559J0D01*
G01X1597423Y294446D01*
G02X1597441Y294510I199J-21D01*
G01X1597442Y294513D01*
X1597528Y294672D01*
Y294674D01*
X1597613Y294829D01*
G02X1597783Y294926I171J-103D01*
G01X1779069D01*
G02X1779106Y294922I-3J-200D01*
G01X1779108D01*
G02X1779209Y294869I-39J-196D01*
G01X1783915Y290163D01*
G02X1783968Y290062I-143J-140D01*
G01Y290060D01*
G02X1783972Y290023I-196J-40D01*
G01Y287559D01*
G02X1783950Y287468I-200J0D01*
G02X1783914Y287418I-178J90D01*
G01X1775266Y278770D01*
G02X1775216Y278734I-140J142D01*
G02X1775125Y278712I-91J178D01*
G01X1408069D01*
G03X1407927Y278653I0J-200D01*
G01X1407633Y278359D01*
G02X1407583Y278323I-140J142D01*
G02X1407492Y278301I-91J178D01*
G01X1397276D01*
G02X1397162Y278337I0J200D01*
G01X1397125Y278374D01*
G02X1397102Y278402I142J140D01*
G01X1397094Y278414D01*
X1396920Y278667D01*
G02X1396893Y278809I170J106D01*
G01X1396896Y278823D01*
X1396903Y278843D01*
G03X1398262Y286220I-19343J7377D01*
G03X1356856I-20703J0D01*
G03X1373737Y265872I20704J0D01*
G01X1373771Y265866D01*
X1373811Y265843D01*
G02X1373850Y265809I-111J-167D01*
G01X1373896Y265754D01*
G02X1373898Y265752I-140J-142D01*
G01X1373931Y265711D01*
G02X1373933Y265709I-138J-140D01*
G01X1373947Y265686D01*
G02X1373967Y265633I-175J-96D01*
G02X1373971Y265595I-196J-40D01*
G01Y162400D01*
G02X1373962Y162344I-200J3D01*
G01X1373927Y162242D01*
X1373907Y162216D01*
G03Y160396I1195J-910D01*
G01X1373927Y160370D01*
X1373962Y160268D01*
G02X1373971Y160212I-191J-59D01*
G01Y158829D01*
G02X1373970Y158810I-200J1D01*
G02X1373863Y158653I-199J21D01*
G02X1373854Y158649I-86J181D01*
G01X1373846Y158645D01*
G02X1373840Y158643I-66J189D01*
G01X1373570Y158518D01*
X1373520Y158495D01*
G02X1373392Y158496I-63J190D01*
G01X1373349Y158511D01*
G02X1373292Y158543I68J188D01*
G03X1372354Y158872I-938J-1174D01*
G03Y155868I0J-1502D01*
G01X1372407D01*
G03X1373295Y156197I-52J1502D01*
G01X1373312Y156210D01*
X1373351Y156230D01*
X1373401Y156247D01*
G02X1373521Y156245I57J-192D01*
G01X1373569Y156222D01*
X1373571D01*
X1373841Y156097D01*
X1373863Y156087D01*
G02X1373874Y156081I-90J-178D01*
G02X1373970Y155933I-103J-172D01*
G02X1373971Y155916I-199J-20D01*
G01Y151308D01*
G02X1373771Y151108I-200J0D01*
G01X1368447D01*
G02X1368433Y151109I7J199D01*
G01X1368427D01*
G02X1368294Y151174I15J199D01*
G01X1368275Y151195D01*
X1368237Y151266D01*
X1368073Y151574D01*
X1368076Y151630D01*
X1368079Y151683D01*
X1368108Y151728D01*
X1368109Y151730D01*
G03X1368361Y152562I-1250J833D01*
G03X1366859Y154064I-1502J0D01*
G03X1365589Y153366I0J-1504D01*
G01X1365575Y153344D01*
X1365560Y153329D01*
G02X1365527Y153304I-137J146D01*
G01X1365445Y153252D01*
G02X1365356Y153224I-103J171D01*
G01X1365076Y153206D01*
G02X1364908Y153279I-13J200D01*
G01X1364882Y153313D01*
G03X1363710Y153875I-1172J-942D01*
G01X1363709D01*
G03X1362207Y152373I0J-1502D01*
G03X1362372Y151689I1502J0D01*
G01X1362378Y151677D01*
G02X1362394Y151590I-184J-79D01*
G01X1362392Y151539D01*
X1362186Y151203D01*
G02X1362182Y151197I-168J108D01*
G01X1362171Y151185D01*
G03X1362167Y151180I152J-126D01*
G01X1362153Y151163D01*
G02X1362016Y151108I-138J145D01*
G01X1352700D01*
G02X1352559Y151166I0J200D01*
G01X1351438Y152287D01*
X1351432Y152292D01*
X1351429Y152295D01*
G03X1350017Y152878I-1412J-1418D01*
G01X1343657D01*
G03X1342242Y152292I0J-2001D01*
G01X1338905Y148956D01*
G03X1338596Y148558I1414J-1417D01*
G01Y148557D01*
G02X1338590Y148547I-174J98D01*
G03X1338525Y148424I1736J-996D01*
G02X1338521Y148416I-181J85D01*
G03X1338515Y148405I1752J-963D01*
G03X1338513Y148403I133J-135D01*
G03X1338399Y148103I1808J-859D01*
G01Y148102D01*
X1338395Y148087D01*
G03X1338382Y148043I1912J-589D01*
G01Y148042D01*
X1338376Y148018D01*
G03X1338348Y147888I1942J-486D01*
G01Y147886D01*
X1338345Y147870D01*
G03X1338341Y147842I1979J-297D01*
G01Y147840D01*
G03X1338331Y147762I1980J-293D01*
G01Y147758D01*
G03X1338328Y147737I1979J-293D01*
G01Y147733D01*
G03X1338321Y147638I1992J-195D01*
G01X1338320Y147634D01*
G03X1338319Y147617I1998J-126D01*
G01Y147616D01*
G03X1340291Y145538I2001J-76D01*
G01X1340327D01*
G03X1340822Y145602I-7J2002D01*
G03X1341362Y145831I-503J1937D01*
G01X1341364Y145832D01*
X1341367Y145834D01*
G03X1341391Y145849I-1049J1704D01*
G01X1341396Y145852D01*
X1341398Y145853D01*
G03X1341549Y145960I-1081J1685D01*
G03X1341607Y146007I-1231J1578D01*
G03X1341736Y146125I-1285J1534D01*
G01X1342957Y147346D01*
X1344430Y148820D01*
G02X1344530Y148872I139J-144D01*
G01X1344532D01*
G02X1344569Y148876I40J-196D01*
G01X1347048D01*
G02X1347128Y148859I-1J-200D01*
G01X1347165Y148843D01*
X1347192Y148814D01*
G02X1347197Y148809I-139J-144D01*
G01X1347395Y148588D01*
X1347396Y148587D01*
G02X1347437Y148514I-150J-132D01*
G01X1347449Y148474D01*
X1347445Y148433D01*
G03X1347437Y148299I1494J-156D01*
G01Y148271D01*
G03X1347828Y147267I1502J7D01*
G02X1347832Y147263I-139J-143D01*
G01X1347851Y147241D01*
X1347872Y147139D01*
X1348041Y147070D01*
X1348085Y147041D01*
G02X1348089Y147039I-87J-180D01*
G03X1348939Y146775I850J1238D01*
G03X1349139Y146788I3J1502D01*
G01X1349140D01*
G03X1349160Y146791I-213J1487D01*
G01X1349164D01*
G03X1349208Y146799I-247J1482D01*
G01X1349210D01*
G03X1349255Y146808I-272J1478D01*
G03X1350128Y147358I-316J1469D01*
G01X1350142Y147376D01*
G02X1350245Y147431I142J-141D01*
G01X1350315Y147443D01*
X1350329Y147445D01*
G02X1350354Y147447I28J-198D01*
G01X1350609D01*
G02X1350685Y147432I0J-200D01*
G01X1350714Y147417D01*
X1350721Y147412D01*
G03X1350781Y147376I1060J1698D01*
G03X1351144Y147210I1010J1729D01*
G01X1351147Y147209D01*
G02X1351156Y147206I-59J-191D01*
G03X1351158Y147205I89J176D01*
G03X1351837Y147104I630J1900D01*
G01X1373771D01*
G02X1373971Y146904I0J-200D01*
G01Y19855D01*
G02X1373949Y19764I-200J0D01*
G02X1373913Y19714I-178J90D01*
G01X1365103Y10904D01*
G02X1365053Y10868I-140J142D01*
G02X1364962Y10846I-91J178D01*
G01X1338968D01*
G02X1338877Y10868I0J200D01*
G02X1338827Y10904I90J178D01*
G01X1330633Y19098D01*
G02X1330597Y19148I142J140D01*
G02X1330575Y19239I178J91D01*
G01Y31510D01*
G02X1330632Y31640I200J-10D01*
G01X1330712Y31716D01*
X1330854Y31851D01*
G02X1330985Y31900I131J-151D01*
G01X1331000D01*
G03X1331073Y31898I78J1500D01*
G03Y34902I0J1502D01*
G03X1330997Y34900I1J-1502D01*
G01X1330956Y34898D01*
X1330905Y34918D01*
G02X1330858Y34947I80J183D01*
G01X1330638Y35155D01*
G02X1330614Y35182I137J146D01*
G02X1330575Y35291I161J119D01*
G01Y224310D01*
G03X1330516Y224452I-200J0D01*
G01X1329337Y225631D01*
G02X1329278Y225773I141J142D01*
G01Y275121D01*
G03X1328631Y276678I-2202J-2D01*
G01X1328251Y277058D01*
G02X1328193Y277200I142J141D01*
G01Y300736D01*
G02X1328252Y300878I200J0D01*
G01X1332516Y305142D01*
G02X1332658Y305201I142J-141D01*
G01X1341500D01*
G02X1341700Y305001I0J-200D01*
G01Y280443D01*
G02X1341636Y280387I-161J119D01*
G01X1341444Y280297D01*
X1341442D01*
X1341295Y280229D01*
G02X1341249Y280214I-84J181D01*
G02X1341183Y280212I-39J196D01*
G01X1341155Y280216D01*
X1341104Y280239D01*
X1341081Y280258D01*
X1341080Y280259D01*
G03X1340104Y280619I-976J-1143D01*
G03Y277615I0J-1502D01*
G01X1340105D01*
G03X1341277Y278178I0J1502D01*
G01Y278179D01*
X1341287Y278191D01*
G02X1341445Y278254I146J-137D01*
G01X1341681Y278226D01*
X1341683D01*
X1341744Y278218D01*
G02X1341832Y278185I-24J-199D01*
G01X1341854Y278169D01*
X1341886Y278146D01*
X1341908Y278098D01*
G03X1344007Y276748I2099J957D01*
G03X1346314Y279054I0J2307D01*
G01Y314349D01*
G02X1346332Y314370I160J-119D01*
G01X1359561Y327599D01*
G03X1359620Y327741I-141J142D01*
G01Y331823D01*
X1359623Y331841D01*
G03X1359660Y332251I-2269J411D01*
G01Y361344D01*
G02X1359719Y361486I200J0D01*
G01X1377224Y378991D01*
G02X1377366Y379050I142J-141D01*
G01X1382202D01*
G02X1382616Y378900I93J-389D01*
G02X1382656Y378781I-160J-120D01*
G01Y367470D01*
G02X1382633Y367377I-200J0D01*
G03X1382460Y366677I1330J-700D01*
G01X1382462Y366617D01*
G03X1385464I1501J58D01*
G01X1385466Y366677D01*
G03X1385293Y367377I-1503J0D01*
G02X1385270Y367470I177J93D01*
G01Y407597D01*
G02X1385329Y407739I200J0D01*
G01X1396224Y418634D01*
G03X1396606Y419556I-924J923D01*
G01Y432002D01*
G03X1396224Y432924I-1306J-1D01*
G01X1389300Y439848D01*
G02X1389241Y439990I141J142D01*
G01Y450707D01*
G02X1389300Y450849I200J0D01*
G01X1390534Y452083D01*
G02X1390676Y452142I142J-141D01*
G01X1392971D01*
G02X1393113Y452083I0J-200D01*
G01X1421602Y423594D01*
G02X1421604Y423566I-198J-28D01*
G01Y409508D01*
G02X1421603Y409489I-200J1D01*
G02X1421561Y409384I-199J19D01*
G02X1421537Y409358I-158J122D01*
G01X1421315Y409160D01*
G02X1421244Y409119I-133J149D01*
G01X1421204Y409106D01*
X1421162Y409110D01*
G03X1421005Y409118I-155J-1494D01*
G03Y406114I0J-1502D01*
G03X1421162Y406122I2J1502D01*
G01X1421204Y406126D01*
X1421244Y406113D01*
G02X1421315Y406072I-62J-190D01*
G01X1421537Y405874D01*
G02X1421561Y405848I-134J-148D01*
G02X1421603Y405743I-157J-124D01*
G02X1421604Y405724I-199J-20D01*
G01Y361297D01*
G02X1421602Y361269I-200J0D01*
G01X1409431Y349098D01*
X1409392Y349085D01*
G03X1408328Y347649I437J-1436D01*
G03X1409830Y346147I1502J0D01*
G03X1411266Y347211I0J1501D01*
G01X1411279Y347250D01*
X1424124Y360095D01*
G03X1424506Y361017I-924J923D01*
G01Y422654D01*
G02X1424630Y422839I200J0D01*
G01X1424686Y422863D01*
X1424804Y422839D01*
X1444541Y403103D01*
G02X1444600Y402961I-141J-142D01*
G01Y366773D01*
X1444584Y366741D01*
G03X1444404Y366032I1322J-713D01*
G03Y366028I1502J-2D01*
G01Y366019D01*
G03X1444514Y365465I1502J10D01*
G01Y365464D01*
G02X1444499Y365284I-185J-75D01*
G01X1444425Y365174D01*
X1444309Y365002D01*
G02X1444263Y364954I-165J112D01*
G01X1443784D01*
X1443752Y364970D01*
G03X1443041Y365150I-713J-1322D01*
G03Y362146I0J-1502D01*
G03X1443752Y362326I-2J1502D01*
G01X1443784Y362342D01*
X1446471D01*
G02X1446595Y361982I4J-200D01*
G03X1446000Y360785I907J-1197D01*
G03X1447502Y362287I1502J0D01*
G03X1447416Y362285I-8J-1502D01*
G01X1447405D01*
G02X1447205Y362485I0J200D01*
G01X1447259Y362600D01*
G02X1447309Y362665I180J-87D01*
G03X1447372Y362724I-861J983D01*
G01X1449124Y364476D01*
G03X1449506Y365398I-924J923D01*
G01Y403502D01*
G03X1449124Y404424I-1306J-1D01*
G01X1392765Y460782D01*
G02X1392706Y460924I141J142D01*
G01Y485094D01*
G03X1392324Y486016I-1306J-1D01*
G01X1392175Y486165D01*
G02X1392116Y486307I141J142D01*
G01Y486690D01*
G03X1392057Y486832I-200J0D01*
G01X1388865Y490025D01*
G02X1388806Y490167I141J142D01*
G01Y582876D01*
G02X1388865Y583018I200J0D01*
G01X1393124Y587276D01*
G03X1393506Y588198I-924J923D01*
G01Y603476D01*
G02X1393565Y603618I200J0D01*
G01X1395124Y605176D01*
G03X1395506Y606098I-924J923D01*
G01Y616902D01*
G03X1395124Y617824I-1306J-1D01*
G01X1394865Y618082D01*
G02X1394806Y618224I141J142D01*
G01Y628802D01*
G03X1394424Y629724I-1306J-1D01*
G01X1389873Y634275D01*
G02X1389814Y634417I141J142D01*
G01Y664211D01*
G02X1389818Y664249I200J-2D01*
G02X1389871Y664351I196J-37D01*
G01X1396754Y671234D01*
G03X1396813Y671376I-141J142D01*
G01Y697216D01*
G02X1396866Y697350I200J-1D01*
G01X1396929Y697414D01*
G02X1396989Y697456I143J-140D01*
G01X1397085Y697500D01*
X1397086D01*
G03X1397099Y697501I-109J1498D01*
G01X1397120Y697502D01*
G03Y700498I-120J1498D01*
G01X1397099Y700499D01*
G03X1397086Y700500I-122J-1497D01*
G01X1397085D01*
X1396989Y700544D01*
G02X1396929Y700586I83J182D01*
G01X1396866Y700650D01*
G02X1396813Y700784I147J135D01*
G01Y701216D01*
G02X1396866Y701350I200J-1D01*
G01X1396929Y701414D01*
G02X1396989Y701456I143J-140D01*
G01X1397085Y701500D01*
X1397086D01*
G03X1397099Y701501I-109J1498D01*
G01X1397120Y701502D01*
G03Y704498I-120J1498D01*
G01X1397099Y704499D01*
G03X1397086Y704500I-122J-1497D01*
G01X1397085D01*
X1396989Y704544D01*
G02X1396929Y704586I83J182D01*
G01X1396866Y704650D01*
G02X1396813Y704784I147J135D01*
G01Y705216D01*
G02X1396866Y705350I200J-1D01*
G01X1396929Y705414D01*
G02X1396989Y705456I143J-140D01*
G01X1397085Y705500D01*
X1397086D01*
G03X1397099Y705501I-109J1498D01*
G01X1397120Y705502D01*
G03Y708498I-120J1498D01*
G01X1397099Y708499D01*
G03X1397086Y708500I-122J-1497D01*
G01X1397085D01*
X1396989Y708544D01*
G02X1396929Y708586I83J182D01*
G01X1396866Y708650D01*
G02X1396813Y708784I147J135D01*
G01Y732824D01*
G02X1396817Y732862I200J-2D01*
G02X1396870Y732964I196J-37D01*
G01X1408135Y744229D01*
G02X1408146Y744239I140J-143D01*
G01X1408152Y744244D01*
G02X1408289Y744286I123J-157D01*
G01X1408602Y744255D01*
G02X1408687Y744227I-18J-199D01*
G01X1408688D01*
G02X1408749Y744168I-105J-170D01*
G01X1408750Y744167D01*
G03X1410000Y743498I1250J833D01*
G03X1411502Y745000I0J1502D01*
G03X1410833Y746250I-1502J0D01*
G01X1410832D01*
Y746251D01*
G02X1410773Y746312I111J166D01*
G01Y746313D01*
G02X1410745Y746398I171J103D01*
G01X1410714Y746711D01*
G02X1410756Y746848I199J14D01*
G01X1410761Y746854D01*
G02X1410771Y746865I153J-129D01*
G01X1411489Y747583D01*
G02X1411659Y747639I141J-142D01*
G01X1413533Y745765D01*
G02X1413592Y745623I-141J-142D01*
G01Y742101D01*
G03X1414268Y740470I2307J1D01*
G01X1416369Y738369D01*
G03X1418000Y737694I1630J1631D01*
G03X1418205Y737703I1J2306D01*
G01X1418288Y737710D01*
G02X1418319Y737687I-103J-171D01*
G01X1418534Y737487D01*
G02X1418598Y737341I-136J-147D01*
G01Y734892D01*
G02X1418597Y734871I-200J-1D01*
G02X1418549Y734760I-199J20D01*
G02X1418532Y734743I-150J133D01*
G01X1418310Y734544D01*
G02X1418239Y734503I-133J149D01*
G01X1418199Y734490D01*
X1418157Y734494D01*
G03X1418000Y734502I-155J-1494D01*
G03Y731498I0J-1502D01*
G03X1418157Y731506I2J1502D01*
G01X1418199Y731510D01*
X1418239Y731497D01*
G02X1418310Y731456I-62J-190D01*
G01X1418532Y731257D01*
G02X1418549Y731240I-133J-150D01*
G02X1418597Y731129I-151J-131D01*
G02X1418598Y731108I-199J-20D01*
G01Y730892D01*
G02X1418597Y730871I-200J-1D01*
G02X1418549Y730760I-199J20D01*
G02X1418532Y730743I-150J133D01*
G01X1418310Y730544D01*
G02X1418239Y730503I-133J149D01*
G01X1418199Y730490D01*
X1418157Y730494D01*
G03X1418000Y730502I-155J-1494D01*
G03Y727498I0J-1502D01*
G03X1418157Y727506I2J1502D01*
G01X1418199Y727510D01*
X1418239Y727497D01*
G02X1418310Y727456I-62J-190D01*
G01X1418532Y727257D01*
G02X1418549Y727240I-133J-150D01*
G02X1418597Y727129I-151J-131D01*
G02X1418598Y727108I-199J-20D01*
G01Y725892D01*
G02X1418597Y725871I-200J-1D01*
G02X1418549Y725760I-199J20D01*
G02X1418532Y725743I-150J133D01*
G01X1418310Y725544D01*
G02X1418239Y725503I-133J149D01*
G01X1418199Y725490D01*
X1418157Y725494D01*
G03X1418000Y725502I-155J-1494D01*
G03X1416498Y724000I0J-1502D01*
G03X1417121Y722782I1502J0D01*
G01X1417141Y722768D01*
X1417171Y722733D01*
X1417182Y722711D01*
G02X1417203Y722618I-179J-89D01*
G01X1417201Y722339D01*
G02X1417177Y722248I-200J4D01*
G01X1417115Y722130D01*
X1417106Y722123D01*
G03X1416467Y720894I862J-1229D01*
G03X1417969Y719392I1502J0D01*
G03X1418145Y719402I3J1502D01*
G01X1418151Y719403D01*
X1418174Y719404D01*
G02X1418307Y719354I1J-200D01*
G01X1418530Y719157D01*
G02X1418552Y719134I-133J-149D01*
G02X1418597Y719024I-154J-127D01*
G02X1418598Y719007I-199J-20D01*
G01Y718892D01*
G02X1418597Y718871I-200J-1D01*
G02X1418549Y718760I-199J20D01*
G02X1418532Y718743I-150J133D01*
G01X1418310Y718544D01*
G02X1418239Y718503I-133J149D01*
G01X1418199Y718490D01*
X1418157Y718494D01*
G03X1418000Y718502I-155J-1494D01*
G03Y715498I0J-1502D01*
G03X1418157Y715506I2J1502D01*
G01X1418199Y715510D01*
X1418239Y715497D01*
G02X1418310Y715456I-62J-190D01*
G01X1418532Y715257D01*
G02X1418549Y715240I-133J-150D01*
G02X1418597Y715129I-151J-131D01*
G02X1418598Y715108I-199J-20D01*
G01Y706892D01*
G02X1418597Y706871I-200J-1D01*
G02X1418549Y706760I-199J20D01*
G02X1418532Y706743I-150J133D01*
G01X1418310Y706544D01*
G02X1418239Y706503I-133J149D01*
G01X1418199Y706490D01*
X1418157Y706494D01*
G03X1418000Y706502I-155J-1494D01*
G03Y703498I0J-1502D01*
G03X1418157Y703506I2J1502D01*
G01X1418199Y703510D01*
X1418239Y703497D01*
G02X1418310Y703456I-62J-190D01*
G01X1418532Y703257D01*
G02X1418549Y703240I-133J-150D01*
G02X1418597Y703129I-151J-131D01*
G02X1418598Y703108I-199J-20D01*
G01Y702892D01*
G02X1418597Y702871I-200J-1D01*
G02X1418549Y702760I-199J20D01*
G02X1418532Y702743I-150J133D01*
G01X1418310Y702544D01*
G02X1418239Y702503I-133J149D01*
G01X1418199Y702490D01*
X1418157Y702494D01*
G03X1418000Y702502I-155J-1494D01*
G03Y699498I0J-1502D01*
G03X1418157Y699506I2J1502D01*
G01X1418199Y699510D01*
X1418239Y699497D01*
G02X1418310Y699456I-62J-190D01*
G01X1418532Y699257D01*
G02X1418549Y699240I-133J-150D01*
G02X1418597Y699129I-151J-131D01*
G02X1418598Y699108I-199J-20D01*
G01Y697892D01*
G02X1418597Y697871I-200J-1D01*
G02X1418549Y697760I-199J20D01*
G02X1418532Y697743I-150J133D01*
G01X1418310Y697544D01*
G02X1418239Y697503I-133J149D01*
G01X1418199Y697490D01*
X1418157Y697494D01*
G03X1418000Y697502I-155J-1494D01*
G03Y694498I0J-1502D01*
G03X1418157Y694506I2J1502D01*
G01X1418199Y694510D01*
X1418239Y694497D01*
G02X1418310Y694456I-62J-190D01*
G01X1418532Y694257D01*
G02X1418549Y694240I-133J-150D01*
G02X1418597Y694129I-151J-131D01*
G02X1418598Y694108I-199J-20D01*
G01Y690892D01*
G02X1418597Y690871I-200J-1D01*
G02X1418549Y690760I-199J20D01*
G02X1418532Y690743I-150J133D01*
G01X1418310Y690544D01*
G02X1418239Y690503I-133J149D01*
G01X1418199Y690490D01*
X1418157Y690494D01*
G03X1418000Y690502I-155J-1494D01*
G03Y687498I0J-1502D01*
G03X1418157Y687506I2J1502D01*
G01X1418199Y687510D01*
X1418239Y687497D01*
G02X1418310Y687456I-62J-190D01*
G01X1418532Y687257D01*
G02X1418549Y687240I-133J-150D01*
G02X1418597Y687129I-151J-131D01*
G02X1418598Y687108I-199J-20D01*
G01Y686892D01*
G02X1418597Y686871I-200J-1D01*
G02X1418549Y686760I-199J20D01*
G02X1418532Y686743I-150J133D01*
G01X1418310Y686544D01*
G02X1418239Y686503I-133J149D01*
G01X1418199Y686490D01*
X1418157Y686494D01*
G03X1418000Y686502I-155J-1494D01*
G03Y683498I0J-1502D01*
G03X1418157Y683506I2J1502D01*
G01X1418199Y683510D01*
X1418239Y683497D01*
G02X1418310Y683456I-62J-190D01*
G01X1418532Y683257D01*
G02X1418549Y683240I-133J-150D01*
G02X1418597Y683129I-151J-131D01*
G02X1418598Y683108I-199J-20D01*
G01Y682892D01*
G02X1418597Y682871I-200J-1D01*
G02X1418549Y682760I-199J20D01*
G02X1418532Y682743I-150J133D01*
G01X1418310Y682544D01*
G02X1418239Y682503I-133J149D01*
G01X1418199Y682490D01*
X1418157Y682494D01*
G03X1418000Y682502I-155J-1494D01*
G03Y679498I0J-1502D01*
G03X1418157Y679506I2J1502D01*
G01X1418199Y679510D01*
X1418239Y679497D01*
G02X1418310Y679456I-62J-190D01*
G01X1418532Y679257D01*
G02X1418549Y679240I-133J-150D01*
G02X1418597Y679129I-151J-131D01*
G02X1418598Y679108I-199J-20D01*
G01Y668769D01*
G03X1418849Y668011I1268J-1D01*
G02X1418863Y667990I-159J-121D01*
G03X1419076Y667710I1137J644D01*
G01X1429032Y657754D01*
X1429045Y657715D01*
G03X1430481Y656651I1436J437D01*
G03X1431983Y658153I0J1502D01*
G03X1430919Y659589I-1501J0D01*
G01X1430880Y659602D01*
X1421365Y669116D01*
G02X1421306Y669258I141J142D01*
G01Y693392D01*
G02X1421430Y693577I200J0D01*
G01X1421486Y693601D01*
X1421604Y693577D01*
X1423757Y691424D01*
X1423772Y691381D01*
G03X1424471Y690557I1418J495D01*
G02X1424556Y690468I-95J-176D01*
G03X1425815Y689621I1353J652D01*
G02X1425945Y689562I-12J-200D01*
G01X1426028Y689476D01*
G02X1426086Y689336I-142J-141D01*
G01Y688410D01*
G02X1426027Y688268I-200J0D01*
G01X1425424Y687665D01*
G03X1424748Y686034I1631J-1632D01*
G01Y675530D01*
G02X1424713Y675417I-200J0D01*
G03X1424308Y674112I1900J-1305D01*
G03X1426615Y671806I2306J0D01*
G03X1428246Y672481I1J2306D01*
G01X1428686Y672921D01*
G03X1429362Y674552I-1631J1632D01*
G01Y683393D01*
G02X1429496Y683582I200J0D01*
G03X1430502Y685000I-496J1418D01*
G03X1430265Y685809I-1502J-1D01*
G02X1430271Y686033I169J108D01*
G03X1430700Y687372I-1878J1340D01*
G01Y694249D01*
G03X1430024Y695880I-2307J-1D01*
G01X1426461Y699443D01*
G02X1426402Y699585I141J142D01*
G01Y707385D01*
G02X1426439Y707501I200J0D01*
G01X1426461Y707532D01*
G02X1426550Y707602I163J-116D01*
G03Y710398I-550J1398D01*
G01X1426523Y710409D01*
X1426478Y710444D01*
X1426439Y710499D01*
G02X1426402Y710615I163J116D01*
G01Y711385D01*
G02X1426439Y711501I200J0D01*
G01X1426461Y711532D01*
G02X1426550Y711602I163J-116D01*
G03Y714398I-550J1398D01*
G01X1426523Y714409D01*
X1426478Y714444D01*
X1426439Y714499D01*
G02X1426402Y714615I163J116D01*
G01Y715513D01*
G02X1426480Y715576I161J-119D01*
G01X1426508Y715586D01*
G03Y718414I-508J1414D01*
G01X1426480Y718424D01*
G02X1426402Y718487I83J182D01*
G01Y747468D01*
G02X1426525Y747653I200J0D01*
G01X1426581Y747676D01*
X1426699Y747653D01*
X1434840Y739512D01*
G03X1435762Y739130I923J924D01*
G01X1447720D01*
G02X1447862Y739071I0J-200D01*
G01X1459367Y727565D01*
X1459380Y727526D01*
G03X1460816Y726462I1436J437D01*
G03X1462318Y727964I0J1502D01*
G03X1461254Y729400I-1501J0D01*
G01X1461215Y729413D01*
X1449268Y741360D01*
G03X1448346Y741742I-923J-924D01*
G01X1438906D01*
G02X1438849Y741808I119J161D01*
G02X1438846Y741815I182J82D01*
G01X1438690Y742140D01*
G02X1438671Y742247I180J87D01*
G01X1438674Y742276D01*
X1438695Y742328D01*
X1438713Y742350D01*
G03X1439035Y743279I-1180J929D01*
G01Y743311D01*
G03X1437533Y744782I-1502J-31D01*
G03X1436031Y743280I0J-1502D01*
G03X1436040Y743112I1502J-4D01*
G02X1436017Y742994I-199J-23D01*
G02X1435928Y742909I-176J95D01*
G01X1435588Y742746D01*
G02X1435583Y742744I-77J185D01*
G02X1435360Y742785I-82J183D01*
G01X1434067Y744078D01*
G02X1434009Y744230I142J141D01*
G01X1434025Y744528D01*
G02X1434046Y744608I200J-10D01*
G01X1434065Y744645D01*
X1434099Y744672D01*
G03X1434655Y745839I-947J1167D01*
G03X1433153Y747341I-1502J0D01*
G03X1431986Y746785I0J-1503D01*
G01X1431973Y746768D01*
X1431939Y746741D01*
X1431922Y746732D01*
G02X1431842Y746711I-90J179D01*
G01X1431544Y746695D01*
G02X1431392Y746753I-11J200D01*
G01X1424458Y753687D01*
G02X1424414Y753901I142J141D01*
G01X1424415Y753904D01*
X1424426Y753932D01*
X1424464Y753978D01*
X1424489Y753995D01*
G02X1424599Y754028I110J-167D01*
G01X1441059D01*
G03X1441201Y754087I0J200D01*
G01X1453502Y766388D01*
G03X1453561Y766530I-141J142D01*
G01Y767495D01*
G02X1453564Y767526I200J-4D01*
G01Y767528D01*
G02X1453660Y767668I198J-33D01*
G01X1453675Y767675D01*
G03X1454534Y769032I-642J1357D01*
G03X1454521Y769232I-1502J3D01*
G03X1453703Y770376I-1489J-200D01*
G01X1453673Y770391D01*
X1453619Y770445D01*
G02X1453583Y770495I142J140D01*
G02X1453561Y770586I178J91D01*
G01Y770757D01*
G02X1453633Y770910I200J-1D01*
G01X1453643Y770918D01*
X1453683Y770944D01*
X1453929Y771103D01*
G02X1454078Y771131I109J-168D01*
G01X1454123Y771121D01*
X1454141Y771113D01*
G03X1454737Y770990I595J1379D01*
G01X1454757D01*
G03X1456240Y772492I-19J1502D01*
G03X1454949Y773979I-1502J0D01*
G01X1454858Y773992D01*
G03X1454830Y773994I-28J-198D01*
G01X1454738D01*
G03X1454594Y773987I1J-1502D01*
G03X1454148Y773873I145J-1495D01*
G01X1454146D01*
X1454123Y773864D01*
X1454078Y773852D01*
G02X1453930Y773880I-39J196D01*
G01X1453929Y773881D01*
X1453646Y774064D01*
G02X1453562Y774206I115J164D01*
G01X1453561Y774217D01*
Y775753D01*
G02X1453568Y775806I200J1D01*
G02X1453582Y775842I193J-54D01*
G02X1453637Y775909I179J-91D01*
G01X1453771Y776010D01*
X1453773D01*
X1453807Y776036D01*
G02X1453990Y776064I118J-161D01*
G03X1454503Y775979I514J1511D01*
G01X1454504D01*
G03Y779171I0J1596D01*
G03X1453993Y779086I3J-1595D01*
G01X1453986Y779083D01*
G02X1453976Y779081I-44J195D01*
G01X1453962Y779078D01*
G02X1453805Y779115I-37J197D01*
G01X1453794Y779123D01*
X1453634Y779242D01*
G02X1453562Y779378I127J154D01*
G01Y779380D01*
G02X1453561Y779397I199J20D01*
G01Y782966D01*
G02X1453562Y782980I200J-7D01*
G01Y782982D01*
G02X1453640Y783125I199J-16D01*
G01X1453772Y783223D01*
X1453774D01*
X1453911Y783323D01*
G02X1453989Y783354I111J-166D01*
G01X1454019Y783359D01*
X1454064Y783352D01*
X1454068Y783351D01*
X1454080Y783347D01*
X1454082D01*
X1454085Y783346D01*
X1454086D01*
G03X1454090Y783344I90J176D01*
G03X1454509Y783278I441J1436D01*
G01X1454552D01*
G03X1456035Y784780I-19J1502D01*
G03X1454533Y786282I-1502J0D01*
G03X1454080Y786213I-3J-1502D01*
G01X1454065Y786208D01*
G02X1453986Y786206I-44J195D01*
G01X1453941Y786214D01*
X1453773Y786338D01*
X1453741Y786362D01*
X1453632Y786441D01*
G02X1453562Y786577I129J153D01*
G01Y786581D01*
G02X1453561Y786594I198J22D01*
G01Y788084D01*
G02X1453562Y788098I200J-7D01*
G01Y788100D01*
G02X1453640Y788243I199J-16D01*
G01X1453772Y788341D01*
X1453774D01*
X1453911Y788441D01*
G02X1453989Y788472I111J-166D01*
G01X1454019Y788477D01*
X1454064Y788470D01*
X1454068Y788469D01*
X1454080Y788465D01*
X1454082D01*
X1454085Y788464D01*
X1454086D01*
G03X1454090Y788462I90J176D01*
G03X1454509Y788396I441J1436D01*
G01X1454552D01*
G03X1456035Y789898I-19J1502D01*
G03X1454533Y791400I-1502J0D01*
G03X1454080Y791331I-3J-1502D01*
G01X1454065Y791326D01*
G02X1453986Y791324I-44J195D01*
G01X1453941Y791332D01*
X1453773Y791456D01*
X1453741Y791480D01*
X1453632Y791559D01*
G02X1453562Y791695I129J153D01*
G01Y791699D01*
G02X1453561Y791712I198J22D01*
G01Y819533D01*
G02X1453562Y819553I200J0D01*
G02X1453591Y819638I199J-20D01*
G01X1453592D01*
G02X1453658Y819703I169J-106D01*
G01X1453685Y819717D01*
G03X1453684Y822488I-581J1385D01*
G01X1453667Y822495D01*
G02X1453592Y822563I93J178D01*
G01X1453577Y822586D01*
X1453569Y822614D01*
G02X1453561Y822670I192J56D01*
G01Y824931D01*
G02X1453562Y824951I200J0D01*
G02X1453591Y825036I199J-20D01*
G01X1453592D01*
G02X1453658Y825101I169J-106D01*
G01X1453685Y825115D01*
G03X1453684Y827886I-581J1385D01*
G01X1453667Y827893D01*
G02X1453592Y827961I93J178D01*
G01X1453577Y827984D01*
X1453569Y828012D01*
G02X1453561Y828068I192J56D01*
G01Y829539D01*
G02X1453637Y829685I200J-11D01*
G01X1453667Y829707D01*
X1453772Y829782D01*
X1453799Y829802D01*
X1453906Y829881D01*
G02X1454060Y829914I116J-163D01*
G01X1454078Y829910D01*
X1454079D01*
X1454088Y829907D01*
X1454090Y829906D01*
X1454091D01*
G03X1454523Y829837I450J1433D01*
G01X1454541D01*
G03Y832841I0J1502D01*
G03X1454082Y832769I0J-1502D01*
G01X1454081D01*
G02X1453988Y832762I-61J190D01*
G01X1453943Y832769D01*
X1453644Y832989D01*
X1453642Y832990D01*
X1453624Y833003D01*
G02X1453583Y833060I140J144D01*
G01X1453572Y833081D01*
X1453561Y833126D01*
Y835177D01*
X1453571Y835219D01*
X1453626Y835341D01*
X1453655Y835369D01*
G03Y837545I-1036J1088D01*
G01X1453626Y837573D01*
X1453579Y837678D01*
G02X1453561Y837760I182J83D01*
G01Y853127D01*
G02X1453562Y853146I200J-1D01*
G01Y853147D01*
G02X1453601Y853245I199J-22D01*
G02X1453619Y853266I160J-119D01*
G01X1467270Y866917D01*
G02X1467292Y866936I141J-141D01*
G02X1467412Y866976I120J-160D01*
G01X1473183D01*
G03X1473674Y867082I-2J1201D01*
G01X1473676Y867083D01*
X1473697Y867092D01*
X1473725Y867098D01*
G02X1473783Y867101I39J-196D01*
G02X1473822Y867093I-20J-199D01*
G01X1473832Y867090D01*
X1473856Y867081D01*
X1473878Y867073D01*
G02X1473933Y867041I-72J-187D01*
G03X1475833I950J1165D01*
G02X1475888Y867073I127J-155D01*
G01X1475910Y867081D01*
X1475934Y867090D01*
X1475944Y867093D01*
G02X1475983Y867101I59J-191D01*
G02X1476041Y867098I19J-199D01*
G01X1476069Y867092D01*
X1476090Y867083D01*
X1476092Y867082D01*
G03X1476583Y866976I493J1095D01*
G01X1489660D01*
G03X1490509Y867328I-1J1201D01*
G01X1491892Y868712D01*
G02X1492006Y868764I136J-147D01*
G02X1492024Y868765I20J-199D01*
G01X1492698D01*
G03X1492840Y868824I0J200D01*
G01X1494109Y870093D01*
G03X1494168Y870235I-141J142D01*
G01Y882339D01*
Y882340D01*
G02X1494315Y882532I200J-1D01*
G01X1494325Y882534D01*
G03Y885466I-324J1466D01*
G01X1494315Y885468D01*
G02X1494168Y885660I53J193D01*
G01Y893402D01*
G02X1494242Y893557I200J0D01*
G01X1494482Y893752D01*
G02X1494561Y893792I128J-154D01*
G01X1494605Y893802D01*
X1494649Y893793D01*
G03X1494951Y893762I304J1471D01*
G01X1494954D01*
G03Y896766I0J1502D01*
G01X1494951D01*
G03X1494649Y896735I2J-1502D01*
G01X1494605Y896726D01*
X1494561Y896736D01*
G02X1494482Y896776I49J194D01*
G01X1494242Y896971D01*
G02X1494168Y897126I126J155D01*
G01Y901628D01*
G02X1494172Y901666I200J-2D01*
G02X1494225Y901768I196J-37D01*
G01X1495131Y902674D01*
G03X1495190Y902816I-141J142D01*
G01Y932807D01*
G02X1495290Y932969I200J-11D01*
G02X1495322Y932984I101J-173D01*
G01X1495536Y933061D01*
X1495620Y933091D01*
X1495668Y933108D01*
X1495670Y933109D01*
X1495683Y933114D01*
G02X1495799Y933116I61J-191D01*
G01X1495801D01*
X1495862Y933076D01*
G02X1495905Y933037I-112J-166D01*
G03X1497063Y932494I1158J963D01*
G03Y935506I0J1506D01*
G03X1495905Y934963I0J-1506D01*
G02X1495862Y934924I-155J127D01*
G01X1495801Y934884D01*
X1495799D01*
G02X1495682Y934886I-55J193D01*
G01X1495670Y934891D01*
X1495668Y934892D01*
X1495620Y934909D01*
X1495536Y934939D01*
X1495322Y935016D01*
G02X1495290Y935031I69J188D01*
G02X1495190Y935193I100J173D01*
G01Y938361D01*
G02X1495268Y938519I200J0D01*
G01X1495520Y938713D01*
G02X1495600Y938750I122J-158D01*
G01X1495645Y938760D01*
X1495691Y938748D01*
G03X1496071Y938699I381J1453D01*
G01X1496082D01*
G03X1497574Y940201I-10J1502D01*
G03X1496072Y941703I-1502J0D01*
G01X1496071D01*
G03X1495691Y941654I1J-1502D01*
G01X1495645Y941642D01*
X1495600Y941652D01*
G02X1495520Y941689I42J195D01*
G01X1495268Y941883D01*
G02X1495190Y942041I122J158D01*
G01Y952141D01*
G02X1495268Y952299I200J0D01*
G01X1495520Y952493D01*
G02X1495600Y952530I122J-158D01*
G01X1495645Y952540D01*
X1495691Y952528D01*
G03X1496071Y952479I381J1453D01*
G01X1496082D01*
G03X1497574Y953981I-10J1502D01*
G03X1497243Y954921I-1502J-1D01*
G02X1497257Y955187I156J125D01*
G01X1506087Y964017D01*
G02X1506207Y964075I142J-141D01*
G01X1506218Y964076D01*
X1534984D01*
G03X1535126Y964135I0J200D01*
G01X1537638Y966647D01*
G03X1537697Y966789I-141J142D01*
G01Y1013748D01*
G02X1537756Y1013890I200J0D01*
G01X1539684Y1015818D01*
G03X1539743Y1015960I-141J142D01*
G01Y1066041D01*
G02X1539802Y1066183I200J0D01*
G01X1541941Y1068322D01*
G03X1542000Y1068464I-141J142D01*
G01Y1111045D01*
G02X1542059Y1111187I200J0D01*
G01X1542129Y1111257D01*
G02X1542271Y1111316I142J-141D01*
G01X1587173D01*
X1587189Y1111313D01*
G03X1587401Y1111296I210J1285D01*
G03X1587613Y1111313I2J1302D01*
G01X1587629Y1111316D01*
X1600938D01*
G02X1600957Y1111315I-1J-200D01*
G01X1600958D01*
G02X1601056Y1111276I-22J-199D01*
G02X1601077Y1111258I-119J-160D01*
G01X1602098Y1110237D01*
G03X1602116Y1110219I858J840D01*
G01X1603788Y1108547D01*
G02X1603816Y1108300I-141J-141D01*
G01X1603768Y1108231D01*
G02X1603742Y1108203I-159J121D01*
G01X1603724Y1108188D01*
X1603695Y1108174D01*
G03X1602930Y1106987I538J-1187D01*
G03X1602952Y1106754I1303J5D01*
G01Y1106748D01*
X1602956Y1106725D01*
X1602928Y1106636D01*
X1602674Y1106370D01*
G02X1602506Y1106310I-144J139D01*
G01X1602505D01*
G03X1602362Y1106319I-147J-1193D01*
G03Y1103915I0J-1202D01*
G03X1602505Y1103924I-4J1202D01*
G01X1602506D01*
G02X1602674Y1103864I24J-199D01*
G01X1602928Y1103598D01*
X1602956Y1103509D01*
X1602952Y1103483D01*
G03X1602930Y1103247I1281J-238D01*
G01Y1103246D01*
G03X1602950Y1103020I1302J1D01*
G01Y1103018D01*
X1602956Y1102985D01*
X1602928Y1102896D01*
X1602642Y1102595D01*
X1602552Y1102563D01*
X1602506Y1102569D01*
G03X1602362Y1102578I-147J-1193D01*
G03Y1100174I0J-1202D01*
G03X1602433Y1100176I2J1202D01*
G01X1602488Y1100179D01*
X1602585Y1100128D01*
X1602799Y1099780D01*
G02X1602801Y1099574I-170J-105D01*
G03X1602734Y1099454I3307J-1925D01*
G02X1602664Y1099380I-176J96D01*
G03X1602088Y1098935I2041J-3237D01*
G02X1602006Y1098889I-136J147D01*
G03X1601110Y1097993I356J-1252D01*
G02X1601064Y1097911I-193J54D01*
G03X1600030Y1095296I2792J-2616D01*
G01Y1095141D01*
G02X1599916Y1094961I-200J0D01*
G01X1599538Y1094780D01*
X1599424Y1094794D01*
X1599379Y1094831D01*
G03X1598622Y1095099I-757J-935D01*
G03Y1092695I0J-1202D01*
G03X1599379Y1092963I0J1203D01*
G01X1599424Y1093000D01*
X1599538Y1093014D01*
X1599916Y1092833D01*
G02X1600030Y1092653I-86J-180D01*
G01Y1085896D01*
G02X1599918Y1085716I-200J0D01*
G03X1599188Y1084546I573J-1170D01*
G01Y1080806D01*
G03X1599196Y1080659I1302J-3D01*
G01X1599201Y1080614D01*
X1599172Y1080528D01*
X1598887Y1080242D01*
X1598802Y1080211D01*
X1598757Y1080216D01*
G03X1598623Y1080224I-144J-1279D01*
G01X1598621D01*
G03X1597334Y1078936I1J-1288D01*
G03X1598622Y1077648I1288J0D01*
G03X1599391Y1077904I-1J1288D01*
G01X1599437Y1077938D01*
X1599549Y1077947D01*
X1599920Y1077761D01*
G02X1600030Y1077583I-90J-179D01*
G01Y1076549D01*
G02X1599920Y1076371I-200J1D01*
G01X1599600Y1076210D01*
G02X1599391Y1076228I-90J179D01*
G03X1598622Y1076484I-770J-1032D01*
G03Y1073908I0J-1288D01*
G03X1599391Y1074164I-1J1288D01*
G01X1599437Y1074198D01*
X1599549Y1074207D01*
X1599920Y1074021D01*
G02X1600030Y1073843I-90J-179D01*
G01Y1070281D01*
G02X1600016Y1070209I-200J1D01*
G03X1599750Y1068787I3660J-1420D01*
G01Y1047862D01*
G02X1599739Y1047798I-200J1D01*
G01X1486606Y713554D01*
X1486601Y713548D01*
G03X1486285Y712671I1186J-923D01*
G01Y712669D01*
G03X1486284Y712631I1502J-59D01*
G01Y712624D01*
G03Y712615I1502J-5D01*
G01Y712603D01*
X1481460Y698350D01*
G02X1481369Y698312I-120J159D01*
G01X1481123Y698288D01*
X1480997Y698276D01*
G02X1480885Y698297I-21J199D01*
G01X1480860Y698311D01*
X1480820Y698349D01*
X1480804Y698376D01*
G03X1479500Y699132I-1304J-747D01*
G03Y696128I0J-1502D01*
G03X1480083Y696246I-1J1502D01*
G02X1480196Y696258I77J-185D01*
G01X1480224Y696253D01*
X1480274Y696228D01*
X1480564Y695959D01*
G02X1480620Y695868I-136J-146D01*
G01X1480375Y695145D01*
G02X1480351Y695130I-118J162D01*
G01X1480064Y695004D01*
G02X1479984Y694987I-81J183D01*
G01X1479943D01*
X1479933Y694991D01*
X1479905Y695004D01*
G03X1479299Y695132I-607J-1374D01*
G01X1479268D01*
G03X1477795Y693630I29J-1502D01*
G01Y693627D01*
G03X1477827Y693321I1502J2D01*
G01Y693319D01*
X1477828Y693317D01*
G02X1477821Y693214I-196J-38D01*
G01X1477813Y693190D01*
X1477784Y693146D01*
X1477501Y692899D01*
G02X1477404Y692852I-132J150D01*
G02X1477302Y692861I-34J197D01*
G01X1477301D01*
G03X1476795Y692949I-507J-1414D01*
G01X1476783D01*
G03X1475292Y691447I11J-1502D01*
G03X1476794Y689945I1502J0D01*
G03X1477430Y690087I-1J1502D01*
G01X1477432D01*
X1477433Y690088D01*
G02X1477530Y690106I84J-182D01*
G01X1477583Y690102D01*
X1477912Y689881D01*
G02X1477924Y689872I-114J-164D01*
G02X1478000Y689706I-124J-157D01*
G01Y689705D01*
G03X1477998Y689630I1500J-78D01*
G03X1478190Y688894I1502J-1D01*
G01X1478210Y688858D01*
X1478218Y688774D01*
X1477408Y686378D01*
X1477401Y686367D01*
G03X1477244Y685957I1309J-736D01*
G03X1477222Y685832I1467J-323D01*
G01X1477221Y685827D01*
X1476670Y684199D01*
X1476639Y684154D01*
X1476621Y684139D01*
G03X1476095Y682997I977J-1142D01*
G01Y682996D01*
G03X1476124Y682703I1502J1D01*
G01X1476128Y682683D01*
G02X1476121Y682579I-196J-39D01*
G01X1476106Y682533D01*
G02X1476080Y682517I-118J162D01*
G01X1476068Y682511D01*
X1475834Y682389D01*
G02X1475760Y682367I-93J177D01*
G01X1475723Y682364D01*
X1475686Y682375D01*
G03X1475267Y682435I-420J-1442D01*
G01X1475264D01*
G03X1473762Y680933I0J-1502D01*
G03X1474704Y679539I1502J0D01*
G01X1474724Y679531D01*
X1474804Y679457D01*
G02X1474850Y679394I-136J-147D01*
G01X1474950Y679179D01*
G02X1474961Y679150I-181J-85D01*
G01X1462342Y641867D01*
G03X1462193Y641284I3720J-1261D01*
G01Y641280D01*
X1459988Y630198D01*
G03X1459917Y629625I3851J-768D01*
G01X1459267Y616373D01*
G02X1459264Y616349I-200J13D01*
G01X1458249Y610535D01*
G03X1458192Y609941I3834J-668D01*
G01X1458144Y607440D01*
X1458136Y607004D01*
G02X1458111Y606918I-200J11D01*
G01X1458100Y606898D01*
X1458066Y606861D01*
X1458044Y606847D01*
G03X1457276Y605443I899J-1404D01*
G01Y605442D01*
G03X1457954Y604099I1669J0D01*
G01X1457976Y604083D01*
X1457987Y604069D01*
G02X1458007Y604040I-154J-127D01*
G01X1458014Y604028D01*
X1458034Y603991D01*
G02X1458036Y603987I-178J-91D01*
G01X1458056Y603947D01*
G02X1458075Y603859I-181J-85D01*
G01Y603858D01*
X1457943Y596969D01*
X1457704Y584556D01*
Y584550D01*
X1457598Y582388D01*
X1457578Y582349D01*
G03X1457410Y581659I1333J-690D01*
G03X1457526Y581080I1503J0D01*
G01X1457533Y581062D01*
X1457159Y573435D01*
G02X1457144Y573368I-200J10D01*
G01X1451353Y559387D01*
G02X1451187Y559265I-184J77D01*
G01X1450780Y559226D01*
X1450679Y559274D01*
X1450649Y559321D01*
G03X1450489Y559524I-1255J-825D01*
G01X1450483Y559530D01*
G02X1450446Y559595I152J130D01*
G01Y559597D01*
G02X1450435Y559661I189J65D01*
G01Y559933D01*
G02X1450446Y559997I200J-1D01*
G01Y559999D01*
G02X1450483Y560064I189J-65D01*
G01X1450489Y560070D01*
G03Y562124I-1096J1027D01*
G01X1450483Y562130D01*
G02X1450446Y562195I152J130D01*
G01Y562197D01*
G02X1450435Y562261I189J65D01*
G01Y562533D01*
G02X1450446Y562597I200J-1D01*
G01Y562599D01*
G02X1450483Y562664I189J-65D01*
G01X1450489Y562670D01*
G03X1450895Y563697I-1096J1027D01*
G03X1450882Y563897I-1502J3D01*
G03X1450263Y564922I-1489J-200D01*
G02X1450248Y564933I111J167D01*
G02X1450202Y564992I132J151D01*
G02X1450180Y565069I177J92D01*
G01Y565073D01*
G02X1450179Y565085I198J23D01*
G01Y565342D01*
G02X1450183Y565377I200J-5D01*
G01X1450189Y565403D01*
X1450200Y565449D01*
Y565450D01*
G02X1450201Y565452I179J-88D01*
G01X1450238Y565524D01*
X1450251Y565551D01*
X1450279Y565583D01*
X1450298Y565597D01*
G03X1450895Y566797I-908J1200D01*
G03X1449393Y568299I-1502J0D01*
G03X1447901Y566973I0J-1502D01*
G01X1447895Y566919D01*
G03X1448523Y565572I1498J-122D01*
G01X1448533Y565564D01*
G02X1448605Y565436I-126J-155D01*
G01Y565434D01*
G02X1448607Y565409I-198J-28D01*
G01Y565133D01*
G02X1448605Y565105I-200J0D01*
G02X1448585Y565042I-198J28D01*
G01X1448569Y565010D01*
X1448541Y564957D01*
G02X1448527Y564936I-173J100D01*
G01X1448519Y564926D01*
X1448506Y564911D01*
X1448496Y564902D01*
X1448487Y564896D01*
G03X1447891Y563697I908J-1199D01*
G03X1448297Y562670I1502J0D01*
G01X1448303Y562664D01*
G02X1448340Y562599I-152J-130D01*
G01Y562597D01*
G02X1448351Y562533I-189J-65D01*
G01Y562261D01*
G02X1448340Y562197I-200J1D01*
G01Y562195D01*
G02X1448303Y562130I-189J65D01*
G01X1448297Y562124D01*
G03Y560070I1096J-1027D01*
G01X1448303Y560064D01*
G02X1448340Y559999I-152J-130D01*
G01Y559997D01*
G02X1448351Y559933I-189J-65D01*
G01Y559661D01*
G02X1448340Y559597I-200J1D01*
G01Y559595D01*
G02X1448303Y559530I-189J65D01*
G01X1448297Y559524D01*
G03Y557470I1096J-1027D01*
G01X1448303Y557464D01*
G02X1448340Y557399I-152J-130D01*
G01Y557397D01*
G02X1448351Y557333I-189J-65D01*
G01Y557061D01*
G02X1448340Y556997I-200J1D01*
G01Y556995D01*
G02X1448303Y556930I-189J65D01*
G01X1448297Y556924D01*
G03Y554870I1096J-1027D01*
G01X1448303Y554864D01*
G02X1448340Y554799I-152J-130D01*
G01Y554797D01*
G02X1448351Y554733I-189J-65D01*
G01Y554461D01*
G02X1448340Y554397I-200J1D01*
G01Y554395D01*
G02X1448303Y554330I-189J65D01*
G01X1448297Y554324D01*
G03X1447891Y553297I1096J-1027D01*
G03X1448294Y552273I1502J0D01*
G02X1448296Y552271I-140J-142D01*
G01X1448324Y552240D01*
X1448345Y552125D01*
X1447444Y549951D01*
X1447321Y549884D01*
X1447252Y549897D01*
G03X1446988Y549920I-262J-1479D01*
G03X1446001Y549550I0J-1501D01*
G01X1446000D01*
Y549549D01*
G02X1445870Y549501I-130J152D01*
G01X1445606D01*
G02X1445476Y549549I0J200D01*
G01X1445475Y549550D01*
G03X1443501I-987J-1131D01*
G01X1443500D01*
Y549549D01*
G02X1443370Y549501I-130J152D01*
G01X1443106D01*
G02X1442976Y549549I0J200D01*
G01X1442975Y549550D01*
G03X1441001I-987J-1131D01*
G01X1441000D01*
Y549549D01*
G02X1440870Y549501I-130J152D01*
G01X1440606D01*
G02X1440476Y549549I0J200D01*
G01X1440475Y549550D01*
G03X1439488Y549920I-987J-1131D01*
G03X1437986Y548418I0J-1502D01*
G03X1438575Y547225I1503J0D01*
G02X1438654Y547064I-121J-159D01*
G01X1438651Y546744D01*
G02X1438571Y546586I-200J2D01*
G01X1438570Y546585D01*
G03X1437960Y545377I891J-1208D01*
G03X1438330Y544390I1501J0D01*
G01Y544389D01*
X1438331D01*
G02X1438379Y544259I-152J-130D01*
G01Y543995D01*
G02X1438331Y543865I-200J0D01*
G01X1438330Y543864D01*
G03Y541890I1131J-987D01*
G01Y541889D01*
X1438331D01*
G02X1438379Y541759I-152J-130D01*
G01Y541495D01*
G02X1438331Y541365I-200J0D01*
G01X1438330Y541364D01*
G03Y539390I1131J-987D01*
G01Y539389D01*
X1438331D01*
G02X1438379Y539259I-152J-130D01*
G01Y538995D01*
G02X1438331Y538865I-200J0D01*
G01X1438330Y538864D01*
G03X1437960Y537877I1131J-987D01*
G03X1440964I1502J0D01*
G03X1440594Y538864I-1501J0D01*
G01Y538865D01*
X1440593D01*
G02X1440545Y538995I152J130D01*
G01Y539259D01*
G02X1440593Y539389I200J0D01*
G01X1440594Y539390D01*
G03Y541364I-1131J987D01*
G01Y541365D01*
X1440593D01*
G02X1440545Y541495I152J130D01*
G01Y541759D01*
G02X1440593Y541889I200J0D01*
G01X1440594Y541890D01*
G03Y543864I-1131J987D01*
G01Y543865D01*
X1440593D01*
G02X1440545Y543995I152J130D01*
G01Y544259D01*
G02X1440593Y544389I200J0D01*
G01X1440594Y544390D01*
G03X1440964Y545377I-1131J987D01*
G03X1440375Y546570I-1503J0D01*
G02X1440296Y546731I121J159D01*
G01X1440299Y547051D01*
G02X1440379Y547209I200J-2D01*
G01X1440380Y547210D01*
G03X1440475Y547286I-890J1210D01*
G01X1440476Y547287D01*
G02X1440606Y547335I130J-152D01*
G01X1440870D01*
G02X1441000Y547287I0J-200D01*
G01X1441001Y547286D01*
G03X1442975I987J1131D01*
G01X1442976D01*
Y547287D01*
G02X1443106Y547335I130J-152D01*
G01X1443370D01*
G02X1443500Y547287I0J-200D01*
G01X1443501Y547286D01*
G03X1445475I987J1131D01*
G01X1445476D01*
Y547287D01*
G02X1445606Y547335I130J-152D01*
G01X1445870D01*
G02X1446000Y547287I0J-200D01*
G01X1446001Y547286D01*
G03X1446718Y546941I986J1132D01*
G01X1446790Y546928D01*
X1446882Y546817D01*
Y521183D01*
G02X1446724Y520987I-200J0D01*
G03Y518049I312J-1469D01*
G02X1446882Y517853I-42J-196D01*
G01Y514624D01*
G03X1447051Y513485I3926J0D01*
G01X1470347Y436693D01*
G03X1470476Y436330I3760J1132D01*
G01X1471017Y435026D01*
G02Y434872I-185J-77D01*
G01X1470893Y434574D01*
X1470837Y434518D01*
X1470800Y434503D01*
G03X1469873Y433115I576J-1388D01*
G03X1471199Y431623I1502J0D01*
G01X1471253Y431617D01*
G03X1471375Y431612I122J1498D01*
G03X1471974Y431737I-1J1502D01*
G02X1471980Y431739I66J-189D01*
G01X1471988Y431742D01*
X1472066D01*
X1472364Y431619D01*
G02X1472473Y431510I-76J-185D01*
G01X1478342Y417342D01*
X1478345Y417328D01*
G03X1479380Y415498I3810J947D01*
G01X1481377Y413500D01*
X1481389Y413481D01*
G03X1481411Y413446I3306J2053D01*
G01X1481412Y413445D01*
X1481442Y413397D01*
Y413396D01*
G03X1481450Y413384I3241J2152D01*
G01X1481456Y413374D01*
G03X1481470Y413353I3245J2148D01*
G01X1481471Y413352D01*
X1481487Y413327D01*
G03X1481491Y413321I168J108D01*
G01X1481542Y413248D01*
G03X1481968Y412742I3179J2244D01*
G01X1501387Y393323D01*
G03X1501389Y393321I2753J2751D01*
G03X1502040Y392799I2746J2758D01*
G03X1502120Y392749I2102J3275D01*
G01X1502124Y392747D01*
G03X1502177Y392715I2038J3315D01*
G03X1502232Y392683I1985J3348D01*
G01X1502233D01*
X1502277Y392659D01*
X1502283Y392656D01*
X1502321Y392636D01*
G03X1502647Y392483I1814J3442D01*
G01X1512106Y388566D01*
G03X1513308Y388281I1487J3595D01*
G02X1513328Y388278I-20J-199D01*
G03X1513999Y388220I672J3868D01*
G01X1516636D01*
G02X1516646Y388211I-129J-153D01*
G01X1516744Y388113D01*
G02X1516797Y388012I-143J-140D01*
G01Y388010D01*
G02X1516801Y387973I-196J-40D01*
G01Y383713D01*
G03X1516860Y383571I200J0D01*
G01X1517762Y382669D01*
G02X1517773Y382657I-142J-141D01*
G02X1517795Y382626I-152J-131D01*
G01X1517799Y382617D01*
X1517812Y382574D01*
G02X1517820Y382527I-192J-57D01*
G03X1518085Y381746I1501J74D01*
G03X1519076Y381117I1237J853D01*
G01X1519078D01*
X1519105Y381112D01*
X1519128Y381102D01*
G02X1519154Y381088I-82J-183D01*
G02X1519170Y381076I-112J-166D01*
G01X1519256Y381005D01*
G02X1519305Y380934I-136J-146D01*
G01X1519367Y380759D01*
Y380757D01*
X1519411Y380630D01*
G02X1519416Y380609I-192J-57D01*
G01X1519419Y380587D01*
G02X1519417Y380543I-199J-13D01*
G01X1518922Y380049D01*
X1518883Y380036D01*
G03X1517819Y378600I437J-1436D01*
G03X1519321Y377098I1502J0D01*
G03X1520757Y378162I0J1501D01*
G01X1520770Y378201D01*
X1526843Y384274D01*
G03X1527226Y385198I-923J924D01*
G01Y441021D01*
G03X1526843Y441945I-1306J0D01*
G01X1519099Y449689D01*
G02X1519040Y449831I141J142D01*
G01Y454316D01*
G02X1519080Y454356I160J-120D01*
G01X1519381Y454549D01*
G02X1519567Y454559I102J-172D01*
G01X1519568D01*
G03X1520114Y454421I635J1361D01*
G01X1520158Y454419D01*
X1520196Y454399D01*
G02X1520259Y454346I-95J-176D01*
G01X1520352Y454228D01*
X1520446Y454109D01*
G02X1520483Y454035I-157J-125D01*
G01X1520493Y453994D01*
X1520485Y453951D01*
G03X1520461Y453685I1478J-267D01*
G01Y453682D01*
G03X1523465I1502J0D01*
G03X1522049Y455182I-1502J0D01*
G01X1522005Y455184D01*
X1521967Y455204D01*
G02X1521904Y455257I95J176D01*
G01X1521811Y455375D01*
X1521717Y455494D01*
G02X1521680Y455568I157J125D01*
G01X1521670Y455609D01*
X1521678Y455652D01*
G03X1521702Y455918I-1478J267D01*
G01Y455921D01*
G03X1520839Y457280I-1502J0D01*
G01X1520799Y457299D01*
X1520772Y457331D01*
G02X1520731Y457408I152J130D01*
G01X1520651Y457703D01*
G02X1520669Y457853I193J53D01*
G01X1520679Y457867D01*
G03X1520938Y458710I-1243J843D01*
G01Y458711D01*
G03X1519436Y460213I-1502J0D01*
G03X1518541Y459917I0J-1501D01*
G01X1518518Y459900D01*
X1518466Y459881D01*
X1518439Y459878D01*
G02X1518333Y459899I-16J200D01*
G01X1518012Y460060D01*
G02X1517942Y460119I90J178D01*
G01Y461879D01*
G02X1517980Y461917I159J-121D01*
G01X1518231Y462111D01*
G02X1518314Y462149I122J-158D01*
G01X1518357Y462158D01*
X1518403Y462146D01*
G03X1518785Y462098I377J1454D01*
G03X1520282Y463600I-5J1502D01*
G03X1518780Y465102I-1502J0D01*
G01X1518779D01*
G03X1518403Y465054I1J-1502D01*
G01X1518357Y465042D01*
X1518314Y465051D01*
G02X1518231Y465089I39J196D01*
G01X1517980Y465283D01*
G02X1517942Y465321I121J159D01*
G01Y465753D01*
G02X1518001Y465895I200J0D01*
G01X1538394Y486287D01*
G03X1538776Y487209I-924J923D01*
G01Y574456D01*
G02X1538780Y574495I200J-1D01*
G01X1548672Y624231D01*
G03X1548698Y624486I-1281J259D01*
G01Y630967D01*
G02X1548713Y631044I200J1D01*
G01X1562475Y664268D01*
X1562497Y664287D01*
G03X1563054Y665455I-946J1168D01*
G03X1560050I-1502J0D01*
G03X1560056Y665318I1502J-3D01*
G01X1560061Y665269D01*
X1546184Y631767D01*
G03X1546084Y631267I1207J-501D01*
G01Y624635D01*
G02X1546080Y624596I-200J1D01*
G01X1536189Y574860D01*
G03X1536164Y574606I1281J-254D01*
G01Y487835D01*
G02X1536105Y487693I-200J0D01*
G01X1526907Y478495D01*
G02X1526688Y478452I-141J141D01*
G01X1526580Y478497D01*
X1526565Y478519D01*
Y494925D01*
G03X1526506Y495067I-200J0D01*
G01X1521285Y500288D01*
G03X1521143Y500347I-142J-141D01*
G01X1515242D01*
G02X1515076Y500436I0J200D01*
G01X1514128Y501853D01*
X1514121Y501895D01*
G03X1513519Y503396I-3867J-680D01*
G01X1512574Y504810D01*
G03X1511722Y505726I-3265J-2182D01*
G02X1511652Y505830I122J158D01*
G03X1511130Y506970I-3785J-1044D01*
G01X1510184Y508385D01*
G03X1509734Y508941I-3264J-2182D01*
G02X1509689Y509148I143J140D01*
G01X1509811Y509487D01*
G02X1509977Y509618I188J-68D01*
G03X1512915Y511499I-428J3903D01*
G02X1512965Y511554I170J-105D01*
G03X1513548Y512742I-919J1188D01*
G01Y512744D01*
G03X1513478Y513198I-1502J1D01*
G02X1513469Y513271I190J61D01*
G03X1513476Y513521I-3919J235D01*
G03X1513127Y515139I-3927J0D01*
G02Y515303I183J82D01*
G03X1513476Y516921I-3578J1618D01*
G03X1513469Y517170I-3926J14D01*
G02X1513477Y517243I199J15D01*
G03X1513546Y517629I-1431J455D01*
G01X1513548Y517651D01*
X1513547D01*
Y517653D01*
X1513548Y517657D01*
G02X1513748Y517852I200J-5D01*
G01X1517100D01*
G02X1517238Y517796I-1J-200D01*
G03X1519952Y516706I2715J2837D01*
G03X1523317Y518611I0J3924D01*
G02X1523367Y518666I170J-105D01*
G03X1523950Y519854I-919J1188D01*
G01Y519856D01*
G03X1523880Y520310I-1502J1D01*
G02X1523871Y520383I190J61D01*
G03X1523878Y520633I-3919J235D01*
G03X1523529Y522251I-3927J0D01*
G02Y522415I183J82D01*
G03X1523878Y524033I-3578J1618D01*
G03X1523871Y524283I-3926J15D01*
G02X1523880Y524356I199J12D01*
G03X1523950Y524810I-1432J453D01*
G01Y524811D01*
G03X1523367Y526000I-1504J0D01*
G02X1523318Y526055I122J158D01*
G03X1519952Y527960I-3366J-2021D01*
G03X1517237Y526870I0J-3926D01*
G01X1517208Y526842D01*
X1517138Y526814D01*
X1516624D01*
G02X1516533Y526836I0J200D01*
G03X1514841Y527263I-1783J-3498D01*
G01X1514804Y527264D01*
X1514179Y527523D01*
G03X1513890Y527630I-1495J-3593D01*
G03X1513807Y527656I-1205J-3700D01*
G03X1513652Y527699I-1118J-3728D01*
G01X1513620Y527707D01*
X1513593Y527724D01*
G02X1513550Y527761I108J169D01*
G01X1513525Y527792D01*
X1513515Y527804D01*
G02X1513470Y527919I155J127D01*
G03X1513127Y529312I-3920J-226D01*
G02Y529476I183J82D01*
G03X1513476Y531094I-3578J1618D01*
G03X1513469Y531344I-3926J15D01*
G02X1513478Y531417I199J12D01*
G03X1513548Y531845I-1432J454D01*
G01Y531870D01*
G03Y531875I-1502J3D01*
G01Y531895D01*
G03X1513519Y532169I-1502J-20D01*
G01X1513516Y532182D01*
G02X1513529Y532284I199J27D01*
G01X1513539Y532308D01*
X1513556Y532330D01*
G02X1513588Y532363I159J-122D01*
G01X1513744Y532477D01*
X1513746D01*
X1513900Y532588D01*
G02X1513909Y532594I115J-163D01*
G01X1514019Y532531D01*
G03X1515948Y532024I1930J3420D01*
G01X1517100D01*
G02X1517238Y531969I0J-200D01*
G03X1519951Y530880I2714J2837D01*
G01X1519952D01*
G03X1523318Y532785I0J3926D01*
G02X1523367Y532840I171J-103D01*
G03X1523950Y534028I-919J1188D01*
G01Y534029D01*
G03X1523880Y534483I-1502J1D01*
G02X1523871Y534556I190J61D01*
G03X1523878Y534806I-3919J235D01*
G03X1523529Y536424I-3927J0D01*
G02Y536588I183J82D01*
G03X1523878Y538206I-3578J1618D01*
G03X1523871Y538456I-3926J15D01*
G02X1523880Y538529I199J12D01*
G03X1523950Y538983I-1432J453D01*
G01Y538985D01*
G03X1523367Y540172I-1501J-1D01*
G02X1523318Y540227I122J158D01*
G03X1522761Y540949I-3366J-2021D01*
G02X1522704Y541089I143J140D01*
G01X1522706Y541372D01*
G02X1522764Y541512I200J-1D01*
G01X1522992Y541740D01*
G03X1523843Y543013I-2776J2777D01*
G01X1525638Y547345D01*
G03X1525862Y548084I-3627J1503D01*
G01X1526007Y548809D01*
X1526024Y548849D01*
X1526038Y548867D01*
G03X1526740Y550449I-3150J2344D01*
G01X1527110Y552314D01*
G03X1527186Y553078I-3851J769D01*
G03X1527146Y553638I-3927J1D01*
G02X1527172Y553769I198J29D01*
G03X1527648Y555012I-3376J2005D01*
G01X1528027Y556925D01*
G03X1528102Y557688I-3852J764D01*
G03X1528062Y558248I-3927J1D01*
G02X1528088Y558379I198J29D01*
G03X1528564Y559622I-3376J2005D01*
G01X1528736Y560491D01*
X1528804Y560570D01*
X1528854Y560588D01*
G03X1529852Y562002I-504J1415D01*
G01Y562003D01*
G03X1529283Y563181I-1504J0D01*
G02X1529224Y563418I124J157D01*
G03X1529480Y564232I-3596J1578D01*
G01X1529859Y566145D01*
G03X1529934Y566908I-3852J764D01*
G03X1529894Y567468I-3927J1D01*
G02X1529920Y567599I198J29D01*
G03X1530396Y568842I-3376J2005D01*
G01X1530775Y570755D01*
G03X1530850Y571518I-3852J764D01*
G03X1530810Y572078I-3927J1D01*
G02X1530836Y572209I198J29D01*
G03X1531312Y573452I-3376J2005D01*
G01X1531691Y575365D01*
G03X1531766Y576128I-3852J764D01*
G03X1531726Y576688I-3927J1D01*
G02X1531752Y576819I198J29D01*
G03X1532228Y578062I-3376J2005D01*
G01X1532607Y579975D01*
G03X1532682Y580738I-3852J764D01*
G03X1532647Y581254I-3927J-7D01*
G02X1532676Y581387I198J26D01*
G03X1533201Y582709I-3326J2086D01*
G01X1533581Y584623D01*
G03X1533656Y585388I-3851J764D01*
G03X1533508Y586456I-3926J0D01*
G01X1533495Y586502D01*
X1561662Y728343D01*
G02X1561669Y728368I196J-41D01*
G01X1636840Y950428D01*
G02X1636938Y950542I190J-64D01*
G01X1637186Y950669D01*
G02X1637334Y950683I91J-178D01*
G01X1637335D01*
G03X1637771Y950618I437J1437D01*
G03X1639273Y952120I0J1502D01*
G03X1638298Y953527I-1503J0D01*
G01X1638261Y953540D01*
X1638204Y953593D01*
X1638068Y953880D01*
G02X1638059Y954030I180J86D01*
G01X1646840Y979969D01*
X1646987Y980042D01*
X1647051Y980021D01*
G03X1647066Y980015I565J1391D01*
G03X1647072Y980013I66J189D01*
G03X1647564Y979930I492J1419D01*
G01X1647565D01*
G03X1649067Y981432I0J1502D01*
G03X1648032Y982860I-1503J0D01*
G01X1648030D01*
G02X1647904Y983114I64J190D01*
G01X1651138Y992667D01*
G02X1651288Y992799I190J-64D01*
G01X1651681Y992877D01*
X1651781Y992843D01*
X1651817Y992803D01*
G03X1652351Y992416I1127J993D01*
G01X1652400Y992395D01*
X1652463Y992314D01*
X1652520Y991925D01*
G02X1652450Y991742I-198J-29D01*
G03X1651912Y990590I964J-1152D01*
G03X1654916I1502J0D01*
G03X1654007Y991970I-1502J0D01*
G01X1653958Y991991D01*
X1653895Y992072D01*
X1653838Y992461D01*
G02X1653908Y992644I198J29D01*
G03X1654446Y993796I-964J1152D01*
G03X1652944Y995298I-1502J0D01*
G03X1652652Y995269I2J-1502D01*
G01X1652599Y995259D01*
X1652499Y995293D01*
X1652235Y995594D01*
G02X1652196Y995790I150J132D01*
G01X1652626Y997062D01*
G02X1652815Y997198I189J-64D01*
G01X1660234D01*
G02X1660383Y997132I1J-200D01*
G01X1660411Y997101D01*
X1660437Y997023D01*
X1658114Y970449D01*
G02X1658112Y970435I-199J21D01*
G01X1651292Y927619D01*
G02X1651194Y927477I-198J32D01*
G01X1650884Y927300D01*
X1650794Y927293D01*
X1650752Y927310D01*
G03X1650206Y927413I-547J-1399D01*
G01X1650205D01*
G03Y924409I0J-1502D01*
G03X1650290Y924411I7J1502D01*
G01X1650335Y924414D01*
X1650419Y924380D01*
X1650658Y924115D01*
G02X1650707Y923949I-149J-134D01*
G01X1648210Y908269D01*
G03X1648162Y907657I3843J-609D01*
G03X1648170Y907406I3891J-2D01*
G01X1649387Y888593D01*
G02X1649309Y888421I-199J-13D01*
G01X1649005Y888188D01*
X1648906Y888172D01*
X1648859Y888188D01*
G03X1648376Y888268I-484J-1422D01*
G01X1648375D01*
G03Y885264I0J-1502D01*
G01X1648376D01*
G03X1649038Y885418I-1J1502D01*
G01X1649083Y885441D01*
X1649183Y885437D01*
X1649515Y885246D01*
G02X1649614Y885085I-101J-173D01*
G01X1650051Y878330D01*
Y878300D01*
X1649158Y868099D01*
G03X1649144Y867758I3912J-331D01*
G01Y867756D01*
G03X1649158Y867415I3926J-10D01*
G01X1655303Y797178D01*
Y797174D01*
X1655311Y797060D01*
Y797056D01*
G03X1655317Y796951I3889J170D01*
G01Y796950D01*
X1656633Y776602D01*
X1656709Y775431D01*
Y775409D01*
X1656708Y775402D01*
G02X1656698Y775358I-199J22D01*
G01X1656657Y775242D01*
X1656613Y775116D01*
G02X1656519Y775013I-186J75D01*
G01X1656517D01*
G02X1656508Y775008I-102J172D01*
G01X1656500Y775005D01*
G03X1655540Y773604I542J-1401D01*
G03X1655547Y773457I1502J-2D01*
G01X1655550Y773427D01*
G03X1656160Y772388I1493J178D01*
G03X1656711Y772137I886J1215D01*
G01X1656731Y772132D01*
X1656744Y772129D01*
X1656765Y772117D01*
G02X1656799Y772092I-101J-173D01*
G02X1656813Y772078I-134J-148D01*
G01X1656891Y771991D01*
G02X1656937Y771893I-151J-131D01*
G01X1656992Y771054D01*
X1657027Y770509D01*
G02X1656960Y770362I-200J2D01*
G01X1656729Y770175D01*
X1656701Y770152D01*
G02X1656614Y770111I-126J155D01*
G01X1656581Y770104D01*
X1656534Y770112D01*
X1656522Y770115D01*
X1656521D01*
X1656518Y770116D01*
G03X1656115Y770171I-403J-1447D01*
G01X1656112D01*
G03Y767167I0J-1502D01*
G01X1656113D01*
G03X1656704Y767288I0J1502D01*
G01X1656721Y767295D01*
G02X1656798Y767304I61J-190D01*
G01X1656845Y767301D01*
X1657053Y767173D01*
X1657177Y767097D01*
G02X1657256Y766976I-117J-163D01*
G01X1657280Y766618D01*
X1657492Y763340D01*
G03X1657499Y763248I3884J249D01*
G01Y763244D01*
X1658070Y754418D01*
X1661369Y703455D01*
G03X1661528Y702575I3884J247D01*
G01X1668068Y681038D01*
G02X1668070Y681032I-189J-66D01*
G01X1670268Y672827D01*
G03X1670660Y671880I3793J1015D01*
G01X1697851Y624781D01*
X1697856Y624740D01*
G03X1698359Y623200I3903J423D01*
G01X1699335Y621510D01*
G03X1700145Y620522I3401J1962D01*
G02X1700210Y620411I-131J-151D01*
G03X1700660Y619215I3851J766D01*
G01X1701036Y618565D01*
G02X1701055Y618409I-173J-100D01*
G01X1700972Y618131D01*
G02X1700871Y618009I-192J56D01*
G03X1699290Y616533I1785J-3497D01*
G02X1699240Y616478I-170J105D01*
G03X1698657Y615299I919J-1188D01*
G01Y615286D01*
G03X1698727Y614834I1502J1D01*
G02X1698736Y614761I-190J-61D01*
G03X1698728Y614511I3919J-251D01*
G03X1699077Y612893I3927J0D01*
G02Y612729I-182J-82D01*
G03X1698728Y611111I3578J-1618D01*
G03X1698736Y610863I3927J3D01*
G02X1698727Y610790I-199J-12D01*
G03X1698724Y610779I1448J-401D01*
G01Y610778D01*
X1698716Y610751D01*
X1698715Y610748D01*
G03X1698706Y610716I1442J-423D01*
G01Y610715D01*
X1698700Y610691D01*
G03X1698688Y610639I1458J-364D01*
G01X1698684Y610623D01*
G02X1698618Y610523I-192J55D01*
G01X1698592Y610503D01*
X1698561Y610492D01*
G02X1698493Y610480I-68J188D01*
G01X1696816D01*
G03X1696075Y610408I4J-3891D01*
G01X1696073D01*
G03X1696042Y610401I841J-3799D01*
G01X1696039D01*
X1696018Y610396D01*
X1696016D01*
G03X1695975Y610387I814J-3805D01*
G03X1695355Y610195I837J-3801D01*
G01X1695342Y610190D01*
G03X1695319Y610180I1540J-3574D01*
G01X1695067D01*
X1694997Y610208D01*
X1694968Y610236D01*
G03X1692253Y611326I-2715J-2836D01*
G03X1688888Y609422I0J-3926D01*
G02X1688838Y609367I-170J105D01*
G03X1688255Y608179I920J-1188D01*
G01Y608151D01*
G03X1688259Y608063I1502J24D01*
G01Y608062D01*
X1688264Y607991D01*
G03X1688268Y607965I199J17D01*
G01X1688277Y607918D01*
X1688278Y607912D01*
G03X1688325Y607721I1479J263D01*
G02X1688334Y607648I-190J-61D01*
G03X1688326Y607399I3919J-251D01*
G03X1688675Y605781I3927J0D01*
G02Y605617I-182J-82D01*
G03X1688326Y603999I3578J-1618D01*
G03X1688334Y603749I3927J1D01*
G02X1688325Y603676I-199J-12D01*
G03X1688255Y603222I1432J-453D01*
G01Y603196D01*
G03X1688286Y602913I1502J21D01*
G01X1688291Y602892D01*
G03X1688315Y602800I1465J333D01*
G01Y602798D01*
G03X1688326Y602764I1435J445D01*
G01Y602762D01*
G03X1688330Y602750I1427J469D01*
G01X1688347Y602698D01*
G03X1688354Y602680I190J63D01*
G01X1688377Y602627D01*
X1688379Y602621D01*
X1688382Y602615D01*
G03X1688391Y602596I1362J633D01*
G03X1688393Y602593I166J108D01*
G02X1688394Y602590I-188J-64D01*
G03X1688454Y602474I1363J631D01*
G03X1688839Y602031I1304J745D01*
G02X1688888Y601976I-122J-158D01*
G03X1692253Y600072I3365J2022D01*
G03X1694967Y601162I-1J3927D01*
G02X1695105Y601218I139J-144D01*
G01X1698530D01*
X1698543Y601204D01*
G03X1698545Y601202I142J140D01*
G01X1698546Y601201D01*
G03X1698548Y601199I142J140D01*
G01X1698594Y601147D01*
X1698611Y601128D01*
G02X1698646Y601072I-150J-133D01*
G01X1698658Y601043D01*
X1698661Y601009D01*
G03X1698662Y600992I1500J80D01*
G01Y600988D01*
G03X1698670Y600913I1498J122D01*
G03X1698727Y600656I1490J196D01*
G02X1698736Y600583I-190J-61D01*
G03X1698728Y600338I3919J-251D01*
G03X1699077Y598720I3927J0D01*
G02Y598556I-182J-82D01*
G03X1698728Y596938I3578J-1618D01*
G03X1698736Y596691I3927J4D01*
G02X1698727Y596618I-199J-12D01*
G03X1698686Y596458I1433J-452D01*
G01Y596457D01*
G03X1698684Y596447I1472J-300D01*
G01Y596445D01*
X1698682Y596438D01*
G02X1698675Y596415I-195J47D01*
G02X1698608Y596329I-185J75D01*
G01X1698546Y596285D01*
X1698515Y596275D01*
X1698514D01*
G03X1698409Y596240I1178J-3709D01*
G03X1698191Y596157I1275J-3677D01*
G03X1697914Y596028I1503J-3589D01*
G02X1697823Y596006I-91J178D01*
G01X1695105D01*
G02X1694967Y596062I1J200D01*
G03X1692253Y597152I-2715J-2837D01*
G03X1688888Y595248I0J-3926D01*
G02X1688838Y595193I-170J105D01*
G03X1688255Y594005I920J-1188D01*
G01Y593977D01*
G03X1688259Y593889I1502J24D01*
G01Y593888D01*
X1688264Y593817D01*
G03X1688268Y593791I199J17D01*
G01X1688277Y593744D01*
X1688278Y593738D01*
G03X1688325Y593547I1479J263D01*
G02X1688334Y593474I-190J-61D01*
G03X1688326Y593225I3919J-251D01*
G03X1688675Y591607I3927J0D01*
G02Y591443I-182J-82D01*
G03X1688326Y589825I3578J-1618D01*
G03X1688334Y589575I3927J1D01*
G02X1688325Y589502I-199J-12D01*
G03X1688255Y589048I1432J-453D01*
G01Y589022D01*
G03X1688286Y588739I1502J21D01*
G01X1688291Y588718D01*
G03X1688315Y588626I1465J333D01*
G01Y588624D01*
G03X1688326Y588590I1435J445D01*
G01Y588588D01*
G03X1688330Y588576I1427J469D01*
G01X1688347Y588524D01*
G03X1688354Y588506I190J63D01*
G01X1688377Y588453D01*
X1688379Y588447D01*
X1688382Y588441D01*
G03X1688391Y588422I1362J633D01*
G03X1688393Y588419I166J108D01*
G02X1688394Y588416I-188J-64D01*
G03X1688454Y588300I1363J631D01*
G03X1688839Y587857I1304J745D01*
G02X1688888Y587802I-122J-158D01*
G03X1692253Y585898I3365J2022D01*
G03X1694967Y586988I-1J3927D01*
G02X1695105Y587044I139J-144D01*
G01X1698529D01*
G02X1698547Y587026I-132J-150D01*
G01X1698590Y586977D01*
X1698612Y586952D01*
X1698636Y586895D01*
X1698638Y586890D01*
Y586888D01*
X1698660Y586837D01*
X1698663Y586806D01*
G03X1698727Y586485I1497J132D01*
G02X1698736Y586412I-190J-61D01*
G03X1698728Y586165I3919J-251D01*
G03X1699077Y584547I3927J0D01*
G02Y584383I-182J-82D01*
G03X1698728Y582765I3578J-1618D01*
G03X1698730Y582649I3927J10D01*
G01X1698733Y582571D01*
G02X1698707Y582538I-169J107D01*
G01X1698589Y582417D01*
X1698500Y582326D01*
G02X1698382Y582275I-134J148D01*
G01X1698378D01*
G02X1698365Y582274I-22J198D01*
G01X1696995D01*
G03X1696242Y582200I2J-3891D01*
G03X1696193Y582190I754J-3817D01*
G03X1695281Y581875I805J-3807D01*
G03X1695240Y581855I1685J-3507D01*
G02X1695238Y581853I-142J140D01*
G01X1695198Y581834D01*
X1695106D01*
G02X1694968Y581889I0J200D01*
G03X1692255Y582978I-2714J-2837D01*
G01X1692253D01*
G03X1688887Y581074I0J-3927D01*
G02X1688838Y581019I-171J103D01*
G03X1688255Y579846I919J-1188D01*
G01Y579810D01*
G03X1688295Y579481I1503J16D01*
G03X1688325Y579371I1464J340D01*
G02X1688334Y579298I-190J-61D01*
G03X1688326Y579052I3919J-251D01*
G03X1688675Y577434I3927J0D01*
G02Y577270I-182J-82D01*
G03X1688326Y575652I3578J-1618D01*
G03X1688334Y575403I3927J2D01*
G02X1688325Y575330I-199J-12D01*
G03X1688270Y575089I1432J-454D01*
G01Y575087D01*
G03X1688267Y575065I1487J-214D01*
G01X1688260Y575013D01*
G03X1688258Y574991I198J-29D01*
G01X1688255Y574914D01*
Y574865D01*
G03X1688839Y573684I1504J9D01*
G02X1688888Y573629I-122J-158D01*
G03X1692253Y571726I3365J2024D01*
G01X1692254D01*
G03X1694967Y572815I-1J3926D01*
G02X1695105Y572870I138J-145D01*
G01X1698530D01*
G02X1698551Y572849I-130J-151D01*
G01X1698593Y572800D01*
G02X1698622Y572754I-153J-129D01*
G01X1698660Y572661D01*
X1698663Y572631D01*
Y572630D01*
G03X1698666Y572601I1496J140D01*
G03X1698727Y572309I1494J160D01*
G02X1698736Y572236I-190J-61D01*
G03X1698728Y571991I3919J-251D01*
G03X1699077Y570373I3927J0D01*
G02Y570209I-182J-82D01*
G03X1698728Y568591I3578J-1618D01*
G03X1698736Y568344I3927J4D01*
G02X1698727Y568271I-199J-12D01*
G03X1698657Y567816I1433J-453D01*
G01Y567807D01*
G03X1698724Y567366I1502J3D01*
G02X1698730Y567272I-191J-59D01*
G01X1698713Y567173D01*
G02X1698679Y567092I-197J35D01*
G01X1698515Y566861D01*
G02X1698477Y566826I-154J129D01*
G01X1698104D01*
G02X1698027Y566841I-1J200D01*
G01X1696771Y567362D01*
G03X1695272Y567660I-1500J-3628D01*
G01X1695067D01*
X1694997Y567688D01*
X1694968Y567716D01*
G03X1692253Y568806I-2715J-2836D01*
G03X1688888Y566902I0J-3926D01*
G02X1688838Y566847I-170J105D01*
G03X1688255Y565659I920J-1188D01*
G01Y565631D01*
G03X1688259Y565543I1502J24D01*
G01Y565542D01*
X1688264Y565471D01*
G03X1688268Y565445I199J17D01*
G01X1688277Y565398D01*
X1688278Y565392D01*
G03X1688325Y565201I1479J263D01*
G02X1688334Y565128I-190J-61D01*
G03X1688326Y564879I3919J-251D01*
G03X1688675Y563261I3927J0D01*
G02Y563097I-182J-82D01*
G03X1688326Y561479I3578J-1618D01*
G03X1688334Y561233I3927J5D01*
G02X1688325Y561160I-199J-12D01*
G03X1688255Y560705I1433J-453D01*
G01Y560676D01*
G03X1688286Y560393I1502J21D01*
G01X1688291Y560372D01*
G03X1688315Y560280I1465J333D01*
G01Y560278D01*
G03X1688326Y560244I1435J445D01*
G01Y560242D01*
G03X1688330Y560230I1427J469D01*
G01X1688347Y560178D01*
G03X1688354Y560160I190J63D01*
G01X1688377Y560107D01*
X1688379Y560101D01*
X1688382Y560095D01*
G03X1688391Y560076I1362J633D01*
G03X1688393Y560073I166J108D01*
G02X1688394Y560070I-188J-64D01*
G03X1688454Y559954I1363J631D01*
G03X1688839Y559511I1304J745D01*
G02X1688888Y559456I-122J-158D01*
G03X1692253Y557552I3365J2022D01*
G03X1694699Y558407I0J3926D01*
G01X1694742Y558442D01*
X1694849Y558457D01*
X1695561Y558162D01*
G03X1697060Y557864I1500J3628D01*
G01X1700568D01*
G03X1702066Y558162I-2J3927D01*
G01X1705515Y559592D01*
G02X1705531Y559597I68J-188D01*
G01X1707249Y560151D01*
G03X1707419Y560210I-1191J3705D01*
G03X1707598Y560282I-1362J3645D01*
G01X1707602Y560284D01*
X1707618Y560290D01*
G02X1707701Y560300I65J-189D01*
G01X1707748Y560296D01*
X1708033Y560110D01*
G02X1708035Y560108I-140J-142D01*
G01X1708071Y560084D01*
G02X1708161Y559917I-110J-167D01*
G01Y550461D01*
G02X1708156Y550417I-200J0D01*
G01X1708148Y550385D01*
X1708146Y550379D01*
G03X1708140Y550367I3474J-1744D01*
G01X1708139Y550364D01*
G03X1708116Y550310I3569J-1552D01*
G01Y550309D01*
G03X1708107Y550288I3572J-1543D01*
G01X1707443Y548703D01*
X1707442Y548701D01*
G03X1707429Y548671I3564J-1562D01*
G01Y548670D01*
X1707414Y548633D01*
G03X1707406Y548613I3609J-1455D01*
G03X1707381Y548548I3620J-1429D01*
G01Y548547D01*
X1707375Y548532D01*
Y548531D01*
X1707353Y548471D01*
G03X1707351Y548466I185J-77D01*
G01Y548465D01*
X1707322Y548376D01*
G03X1707171Y547688I3710J-1175D01*
G03X1707153Y547519I3860J-497D01*
G03X1707148Y547450I3879J-316D01*
G01X1707146Y547417D01*
X1707109Y547329D01*
X1707090Y547307D01*
G03X1706910Y547077I3000J-2533D01*
G02X1706906Y547071I-168J108D01*
G03X1706832Y546973I3068J-2394D01*
G03X1706384Y546179I3142J-2296D01*
G01X1706376Y546161D01*
X1705880Y544977D01*
X1705711Y544574D01*
Y544572D01*
G03X1705687Y544516I3565J-1561D01*
G01Y544515D01*
X1705671Y544477D01*
X1705670Y544474D01*
Y544472D01*
G03X1705659Y544442I3648J-1355D01*
G01X1705657Y544438D01*
G03X1705648Y544412I3672J-1286D01*
G02X1705646Y544408I-179J87D01*
G03X1705635Y544379I3633J-1395D01*
G01Y544377D01*
G03X1705629Y544361I3641J-1374D01*
G03X1705627Y544357I177J-91D01*
G03X1705616Y544325I3674J-1281D01*
G01Y544323D01*
G03X1705416Y543320I3684J-1256D01*
G01Y543319D01*
X1705414Y543285D01*
X1705378Y543199D01*
X1705374Y543190D01*
G02X1705368Y543179I-178J90D01*
G01X1705347Y543149D01*
G02X1705332Y543129I-167J110D01*
G03X1705156Y542917I2904J-2590D01*
G03X1705088Y542826I3083J-2375D01*
G03X1705086Y542823I3237J-2160D01*
G01X1705076Y542809D01*
G03X1704964Y542644I3163J-2267D01*
G03X1704652Y542049I3278J-2098D01*
G01X1703979Y540444D01*
G03X1703868Y540147I3587J-1510D01*
G01X1703856Y540110D01*
X1703786Y540025D01*
G02X1703736Y539982I-154J128D01*
G01X1703651Y539935D01*
G02X1703634Y539928I-84J181D01*
G01X1703562Y539945D01*
G03X1702655Y540052I-910J-3820D01*
G03X1699290Y538148I0J-3926D01*
G02X1699240Y538093I-170J105D01*
G03X1698657Y536905I920J-1188D01*
G01Y536877D01*
G03X1698661Y536789I1502J24D01*
G01Y536788D01*
X1698666Y536717D01*
G03X1698670Y536691I199J17D01*
G01X1698679Y536644D01*
X1698680Y536638D01*
G03X1698727Y536447I1479J263D01*
G02X1698736Y536374I-190J-61D01*
G03X1698728Y536125I3919J-251D01*
G03X1699077Y534507I3927J0D01*
G02Y534343I-182J-82D01*
G03X1698728Y532726I3578J-1618D01*
G01Y532724D01*
G03X1698730Y532620I3927J23D01*
G01Y532618D01*
X1698732Y532540D01*
G02X1698712Y532515I-166J112D01*
G01X1698615Y532414D01*
X1698614Y532413D01*
X1698501Y532298D01*
G02X1698381Y532245I-136J146D01*
G01X1698377D01*
G02X1698364Y532244I-22J198D01*
G01X1697329D01*
G03X1696848Y532214I1J-3892D01*
G01X1696846D01*
G03X1695080Y531794I1J-3926D01*
G01X1695024D01*
G03X1692253Y532940I-2772J-2780D01*
G03X1688888Y531036I0J-3926D01*
G02X1688838Y530981I-170J105D01*
G03X1688255Y529793I920J-1188D01*
G01Y529765D01*
G03X1688259Y529677I1502J24D01*
G01Y529676D01*
X1688264Y529605D01*
G03X1688268Y529579I199J17D01*
G01X1688277Y529532D01*
X1688278Y529526D01*
G03X1688325Y529335I1479J263D01*
G02X1688334Y529262I-190J-61D01*
G03X1688326Y529013I3919J-251D01*
G03X1688675Y527395I3927J0D01*
G02Y527231I-182J-82D01*
G03X1688326Y525613I3578J-1618D01*
G03X1688334Y525364I3927J2D01*
G02X1688325Y525291I-199J-12D01*
G03X1688270Y525050I1432J-454D01*
G01Y525048D01*
G03X1688267Y525026I1487J-214D01*
G01X1688260Y524974D01*
G03X1688258Y524952I198J-29D01*
G01X1688255Y524875D01*
Y524826D01*
G03X1688839Y523645I1504J9D01*
G02X1688888Y523590I-122J-158D01*
G03X1692253Y521686I3365J2022D01*
G03X1694967Y522776I-1J3927D01*
G02X1695105Y522832I139J-144D01*
G01X1698530D01*
X1698543Y522818D01*
G03X1698545Y522816I142J140D01*
G01X1698546Y522815D01*
G03X1698548Y522813I142J140D01*
G01X1698594Y522761D01*
X1698611Y522742D01*
G02X1698646Y522686I-150J-133D01*
G01X1698658Y522657D01*
X1698661Y522623D01*
G03X1698662Y522606I1500J80D01*
G01Y522602D01*
G03X1698670Y522527I1497J122D01*
G03X1698727Y522270I1490J196D01*
G02X1698736Y522197I-190J-61D01*
G03X1698728Y521952I3919J-251D01*
G03X1699077Y520334I3927J0D01*
G02Y520170I-182J-82D01*
G03X1698728Y518553I3578J-1618D01*
G01Y518551D01*
G03X1698730Y518446I3927J22D01*
G01Y518444D01*
X1698732Y518366D01*
G02X1698712Y518340I-168J109D01*
G01X1698615Y518240D01*
X1698614Y518239D01*
X1698501Y518124D01*
G02X1698381Y518071I-136J146D01*
G01X1698377D01*
G02X1698364Y518070I-22J198D01*
G01X1697348D01*
G03X1695575Y517642I1J-3892D01*
G02X1695484Y517620I-91J178D01*
G01X1695067D01*
X1694997Y517648D01*
X1694968Y517676D01*
G03X1692253Y518766I-2715J-2836D01*
G03X1688888Y516862I0J-3926D01*
G02X1688839Y516807I-171J103D01*
G03X1688255Y515628I920J-1190D01*
G01Y515614D01*
G03X1688325Y515162I1502J1D01*
G02X1688334Y515089I-190J-61D01*
G03X1688326Y514839I3919J-251D01*
G03X1688675Y513221I3927J0D01*
G02Y513057I-182J-82D01*
G03X1688326Y511439I3578J-1618D01*
G03X1688334Y511190I3927J2D01*
G02X1688325Y511117I-199J-12D01*
G03X1688270Y510876I1432J-454D01*
G01Y510874D01*
G03X1688267Y510852I1487J-214D01*
G01X1688260Y510800D01*
G03X1688258Y510778I198J-29D01*
G01X1688255Y510701D01*
Y510652D01*
G03X1688839Y509471I1504J9D01*
G02X1688888Y509416I-122J-158D01*
G03X1692253Y507512I3365J2022D01*
G03X1694967Y508602I-1J3927D01*
G02X1695105Y508658I139J-144D01*
G01X1702993D01*
G03X1704496Y508957I0J3927D01*
G01X1707824Y510336D01*
G02X1708040Y510294I76J-185D01*
G02X1708161Y510008I-279J-287D01*
G01Y508690D01*
G02X1708129Y508581I-200J0D01*
G01X1708128Y508580D01*
G03X1707778Y507930I3267J-2178D01*
G01X1707079Y506270D01*
G03X1706784Y505055I3619J-1522D01*
G02X1706735Y504939I-200J16D01*
G03X1706068Y503875I2950J-2591D01*
G01X1705369Y502215D01*
G03X1705094Y501191I3620J-1521D01*
G02X1705084Y501152I-198J30D01*
G03X1704881Y500093I3684J-1255D01*
G03X1704879Y500055I3885J-224D01*
G02X1704865Y499988I-200J7D01*
G03X1704651Y499275I3637J-1480D01*
G01X1703990Y495949D01*
X1703989Y495948D01*
X1703750Y495797D01*
G02X1703702Y495776I-103J171D01*
G01X1703629Y495795D01*
G03X1702655Y495918I-975J-3804D01*
G03X1699290Y494014I0J-3926D01*
G02X1699241Y493959I-171J103D01*
G03X1699146Y493879I919J-1188D01*
G03X1698891Y493575I1014J-1109D01*
G01X1698877Y493553D01*
X1698861Y493538D01*
G02X1698838Y493519I-138J144D01*
G01X1698738Y493460D01*
G02X1698706Y493446I-96J176D01*
G02X1698667Y493437I-64J190D01*
G02X1698650Y493436I-20J199D01*
G01X1639883D01*
G03X1639741Y493377I0J-200D01*
G01X1621692Y475328D01*
G03X1621685Y475320I147J-135D01*
G01X1620403Y473905D01*
G02X1620339Y473862I-141J141D01*
G01X1620230Y473904D01*
G02X1620102Y474090I72J187D01*
G01Y544540D01*
G03X1619720Y545462I-1306J-1D01*
G01X1618071Y547111D01*
X1618058Y547150D01*
G03X1616622Y548214I-1436J-437D01*
G03X1615120Y546712I0J-1502D01*
G03X1616184Y545276I1501J0D01*
G01X1616223Y545263D01*
X1616719Y544767D01*
G02X1616710Y544675I-198J-27D01*
G01X1616613Y544390D01*
G02X1616550Y544300I-189J65D01*
G01X1616431Y544203D01*
X1616407Y544199D01*
G03X1615120Y542712I216J-1487D01*
G03X1616622Y541210I1502J0D01*
G03X1617023Y541264I2J1502D01*
G01X1617025D01*
G02X1617116Y541268I54J-192D01*
G01X1617158Y541260D01*
X1617263Y541181D01*
X1617451Y541038D01*
G02X1617490Y540999I-121J-160D01*
G01Y470687D01*
G02X1617478Y470672I-162J117D01*
G01X1617068Y470218D01*
G02X1617027Y470183I-149J133D01*
G01X1617004Y470169D01*
X1616978Y470161D01*
G03X1616479Y469861I351J-1149D01*
G01X1615234Y468615D01*
G02X1615135Y468561I-141J142D01*
G02X1615113Y468558I-38J197D01*
G01X1614972Y468544D01*
G03X1614850Y468486I20J-199D01*
G01X1608793Y462429D01*
X1608791Y462428D01*
G02X1608720Y462384I-139J144D01*
G01X1608617Y462427D01*
G02X1608494Y462611I77J185D01*
G01Y520573D01*
G03X1607818Y522204I-2307J-1D01*
G01X1598391Y531631D01*
G03X1596761Y532306I-1630J-1631D01*
G01X1596760D01*
G03X1594454Y530000I0J-2306D01*
G01Y529999D01*
G03X1595129Y528369I2306J0D01*
G01X1603821Y519677D01*
G02X1603880Y519535I-141J-142D01*
G01Y457908D01*
G03X1603896Y457641I2307J4D01*
G01Y457639D01*
X1603906Y457551D01*
G02X1603876Y457512I-172J101D01*
G01X1588150Y441786D01*
G03X1588091Y441644I141J-142D01*
G01Y441555D01*
G02X1588069Y441464I-200J0D01*
G37*
G36*
G01X1392102Y899787D02*
X1394728D01*
G02X1394870Y899728I0J-200D01*
G01X1395830Y898768D01*
G02X1395889Y898626I-141J-142D01*
G01Y878105D01*
G02X1395833Y877966I-200J0D01*
G01X1395613Y877738D01*
X1395543Y877706D01*
X1395504Y877705D01*
G03Y874703I57J-1501D01*
G01X1395543Y874702D01*
X1395613Y874670D01*
X1395833Y874442D01*
G02X1395889Y874303I-144J-139D01*
G01Y871854D01*
G02X1395830Y871712I-200J0D01*
G01X1394008Y869890D01*
X1393980Y869861D01*
X1393906Y869831D01*
X1384751D01*
G02X1384588Y869915I0J200D01*
G01X1384371Y870219D01*
X1384357Y870314D01*
X1384373Y870360D01*
G03X1384448Y870811I-1327J452D01*
G01Y870814D01*
G03X1383727Y872039I-1401J0D01*
G02X1383624Y872213I97J175D01*
G01Y872214D01*
Y872564D01*
Y872565D01*
G02X1383727Y872739I200J-1D01*
G03Y875189I-680J1225D01*
G02X1383624Y875363I97J175D01*
G01Y875364D01*
Y875714D01*
Y875715D01*
G02X1383727Y875889I200J-1D01*
G03X1384448Y877114I-680J1225D01*
G03X1383728Y878339I-1402J0D01*
G02X1383625Y878514I97J175D01*
G01Y878863D01*
G02X1383728Y879038I200J0D01*
G03X1384448Y880263I-682J1225D01*
G03X1383727Y881488I-1401J0D01*
G02X1383624Y881662I97J175D01*
G01Y881663D01*
Y882013D01*
Y882014D01*
G02X1383727Y882188I200J-1D01*
G03X1384448Y883413I-680J1225D01*
G03X1383728Y884638I-1402J0D01*
G02X1383625Y884813I97J175D01*
G01Y885162D01*
G02X1383728Y885337I200J0D01*
G03X1384448Y886562I-682J1225D01*
G03X1383727Y887787I-1401J0D01*
G02X1383624Y887961I97J175D01*
G01Y887962D01*
Y888312D01*
Y888313D01*
G02X1383727Y888487I200J-1D01*
G03Y890937I-680J1225D01*
G02X1383624Y891111I97J175D01*
G01Y891112D01*
Y891462D01*
Y891463D01*
G02X1383727Y891637I200J-1D01*
G03X1384156Y892005I-680J1226D01*
G01Y892006D01*
X1384157Y892007D01*
G02X1384314Y892084I158J-123D01*
G01X1384632D01*
G02X1384789Y892007I-1J-200D01*
G01X1384790Y892006D01*
Y892005D01*
G03X1385979Y891421I1188J917D01*
G03X1386965Y891790I0J1502D01*
G02X1386967Y891792I142J-140D01*
G02X1387097Y891840I130J-152D01*
G01X1387361D01*
G02X1387491Y891792I0J-200D01*
G01X1387492Y891791D01*
G03X1389465Y891790I987J1131D01*
G02X1389467Y891792I142J-140D01*
G02X1389597Y891840I130J-152D01*
G01X1389861D01*
G02X1389991Y891792I0J-200D01*
G01X1389992Y891791D01*
G03X1391965Y891790I987J1131D01*
G02X1391967Y891792I142J-140D01*
G02X1392097Y891840I130J-152D01*
G01X1392361D01*
G02X1392491Y891792I0J-200D01*
G01X1392492Y891791D01*
G03X1393479Y891421I987J1131D01*
G03Y894425I0J1502D01*
G03X1392493Y894056I0J-1502D01*
G02X1392491Y894054I-142J140D01*
G02X1392361Y894006I-130J152D01*
G01X1392097D01*
G02X1391967Y894054I0J200D01*
G01X1391966Y894055D01*
G03X1389993Y894056I-987J-1131D01*
G02X1389991Y894054I-142J140D01*
G02X1389861Y894006I-130J152D01*
G01X1389597D01*
G02X1389467Y894054I0J200D01*
G01X1389466Y894055D01*
G03X1387493Y894056I-987J-1131D01*
G02X1387491Y894054I-142J140D01*
G02X1387361Y894006I-130J152D01*
G01X1387097D01*
G02X1386967Y894054I0J200D01*
G01X1386966Y894055D01*
G03X1385979Y894425I-987J-1131D01*
G03X1384752Y893790I0J-1503D01*
G01X1384725Y893752D01*
X1384645Y893708D01*
X1384235Y893690D01*
X1384151Y893727D01*
X1384121Y893763D01*
G03X1383047Y894264I-1074J-901D01*
G01X1383046D01*
G03X1381821Y893543I0J-1401D01*
G02X1381647Y893440I-175J97D01*
G01X1381646D01*
X1381296D01*
X1381295D01*
G02X1381121Y893543I1J200D01*
G03X1379896Y894264I-1225J-680D01*
G03X1378671Y893544I0J-1402D01*
G02X1378496Y893441I-175J97D01*
G01X1378147D01*
G02X1377972Y893544I0J200D01*
G03X1376747Y894264I-1225J-682D01*
G03X1375522Y893543I0J-1401D01*
G02X1375348Y893440I-175J97D01*
G01X1375347D01*
X1374997D01*
X1374996D01*
G02X1374822Y893543I1J200D01*
G03X1372372I-1225J-680D01*
G02X1372198Y893440I-175J97D01*
G01X1372197D01*
X1371847D01*
X1371846D01*
G02X1371672Y893543I1J200D01*
G03X1370447Y894264I-1225J-680D01*
G03X1369222Y893544I0J-1402D01*
G02X1369047Y893441I-175J97D01*
G01X1368698D01*
G02X1368523Y893544I0J200D01*
G03X1367298Y894264I-1225J-682D01*
G03X1366073Y893543I0J-1401D01*
G02X1365899Y893440I-175J97D01*
G01X1365898D01*
X1365548D01*
X1365547D01*
G02X1365373Y893543I1J200D01*
G03X1364830Y894087I-1226J-680D01*
G02X1364727Y894262I97J175D01*
G01Y894611D01*
G02X1364830Y894786I200J0D01*
G03X1365550Y896011I-682J1225D01*
G03X1362746I-1402J0D01*
G03X1363466Y894786I1402J0D01*
G02X1363569Y894611I-97J-175D01*
G01Y894262D01*
G02X1363466Y894087I-200J0D01*
G03X1362923Y893544I682J-1225D01*
G02X1362748Y893441I-175J97D01*
G01X1362399D01*
G02X1362224Y893544I0J200D01*
G03X1360999Y894264I-1225J-682D01*
G03X1359774Y893543I0J-1401D01*
G02X1359600Y893440I-175J97D01*
G01X1359599D01*
X1359249D01*
X1359248D01*
G02X1359074Y893543I1J200D01*
G03X1356624I-1225J-680D01*
G02X1356450Y893440I-175J97D01*
G01X1356449D01*
X1356099D01*
X1356098D01*
G02X1355924Y893543I1J200D01*
G03X1354699Y894264I-1225J-680D01*
G03X1353474Y893544I0J-1402D01*
G02X1353299Y893441I-175J97D01*
G01X1352950D01*
G02X1352775Y893544I0J200D01*
G03X1351550Y894264I-1225J-682D01*
G03X1350148Y892862I0J-1402D01*
G03X1350869Y891637I1401J0D01*
G02X1350972Y891463I-97J-175D01*
G01Y891462D01*
Y891112D01*
Y891111D01*
G02X1350869Y890937I-200J1D01*
G03Y888487I680J-1225D01*
G02X1350972Y888313I-97J-175D01*
G01Y888312D01*
Y887962D01*
Y887961D01*
G02X1350869Y887787I-200J1D01*
G03X1350148Y886562I680J-1225D01*
G03X1350868Y885337I1402J0D01*
G02X1350971Y885162I-97J-175D01*
G01Y884813D01*
G02X1350868Y884638I-200J0D01*
G03X1350148Y883413I682J-1225D01*
G03X1350869Y882188I1401J0D01*
G02X1350972Y882014I-97J-175D01*
G01Y882013D01*
Y881663D01*
Y881662D01*
G02X1350869Y881488I-200J1D01*
G03X1350148Y880263I680J-1225D01*
G03X1350868Y879038I1402J0D01*
G02X1350971Y878863I-97J-175D01*
G01Y878514D01*
G02X1350868Y878339I-200J0D01*
G03X1350148Y877114I682J-1225D01*
G03X1350869Y875889I1401J0D01*
G02X1350972Y875715I-97J-175D01*
G01Y875714D01*
Y875364D01*
Y875363D01*
G02X1350869Y875189I-200J1D01*
G03X1350148Y873964I680J-1225D01*
G03X1351550Y872562I1402J0D01*
G03X1352775Y873282I0J1402D01*
G02X1352950Y873385I175J-97D01*
G01X1353299D01*
G02X1353474Y873282I0J-200D01*
G03X1354699Y872562I1225J682D01*
G03X1355925Y873284I0J1402D01*
G01X1355926Y873285D01*
G02X1356100Y873387I174J-98D01*
G01X1356449D01*
G02X1356624Y873284I0J-200D01*
G03X1357169Y872739I1226J681D01*
G02X1357272Y872564I-97J-175D01*
G01Y872215D01*
G02X1357170Y872041I-200J0D01*
G01X1357169Y872040D01*
G03X1356447Y870814I680J-1226D01*
G03X1357167Y869589I1402J0D01*
G02X1357270Y869414I-97J-175D01*
G01Y869065D01*
G02X1357167Y868890I-200J0D01*
G03X1356624Y868346I683J-1224D01*
G02X1356450Y868243I-175J97D01*
G01X1356449D01*
X1356099D01*
X1356098D01*
G02X1355924Y868346I1J200D01*
G03X1354699Y869067I-1225J-680D01*
G03Y866263I0J-1402D01*
G03X1355924Y866984I0J1401D01*
G02X1356098Y867087I175J-97D01*
G01X1356099D01*
X1356449D01*
X1356450D01*
G02X1356624Y866984I-1J-200D01*
G03X1359074I1225J680D01*
G02X1359248Y867087I175J-97D01*
G01X1359249D01*
X1359599D01*
X1359600D01*
G02X1359774Y866984I-1J-200D01*
G03X1360427Y866386I1225J682D01*
G01X1360428Y866385D01*
X1360430Y866384D01*
G02X1360513Y866312I-84J-181D01*
G02X1360546Y866202I-167J-110D01*
G01Y862830D01*
G02X1360513Y862720I-200J0D01*
G02X1360430Y862648I-167J109D01*
G01X1360428Y862647D01*
X1360427Y862646D01*
G03X1359774Y862048I572J-1280D01*
G02X1359600Y861945I-175J97D01*
G01X1359599D01*
X1359249D01*
X1359248D01*
G02X1359074Y862048I1J200D01*
G03X1356624I-1225J-680D01*
G02X1356450Y861945I-175J97D01*
G01X1356449D01*
X1356099D01*
X1356098D01*
G02X1355924Y862048I1J200D01*
G03X1354699Y862769I-1225J-680D01*
G03Y859965I0J-1402D01*
G03X1355924Y860686I0J1401D01*
G02X1356098Y860789I175J-97D01*
G01X1356099D01*
X1356449D01*
X1356450D01*
G02X1356624Y860686I-1J-200D01*
G03X1357167Y860142I1226J680D01*
G02X1357270Y859967I-97J-175D01*
G01Y859618D01*
G02X1357167Y859443I-200J0D01*
G03X1356447Y858218I682J-1225D01*
G03X1357169Y856992I1402J0D01*
G01X1357170D01*
Y856991D01*
G02X1357272Y856817I-98J-174D01*
G01Y856468D01*
G02X1357169Y856293I-200J0D01*
G03X1356661Y855809I682J-1225D01*
G02X1356652Y855796I-169J107D01*
G02X1356503Y855715I-161J119D01*
G02X1356491I-6J200D01*
G01X1356059D01*
G02X1355889Y855809I0J200D01*
G03X1353509I-1190J-741D01*
G02X1353339Y855715I-170J106D01*
G01X1352910D01*
G02X1352740Y855809I0J200D01*
G03X1350360I-1190J-741D01*
G02X1350190Y855715I-170J106D01*
G01X1346612D01*
G02X1346442Y855809I0J200D01*
G03X1344062I-1190J-741D01*
G02X1343892Y855715I-170J106D01*
G01X1343463D01*
G02X1343293Y855809I0J200D01*
G03X1340913I-1190J-741D01*
G02X1340743Y855715I-170J106D01*
G01X1340311D01*
G02X1340299I-6J200D01*
G02X1340150Y855796I12J200D01*
G02X1340141Y855809I160J120D01*
G03X1339633Y856293I-1190J-741D01*
G02X1339530Y856468I97J175D01*
G01Y856817D01*
G02X1339632Y856991I200J0D01*
G01X1339633Y856992D01*
G03X1340355Y858218I-680J1226D01*
G03X1339635Y859443I-1402J0D01*
G02X1339532Y859618I97J175D01*
G01Y859967D01*
G02X1339635Y860142I200J0D01*
G03X1340178Y860686I-683J1224D01*
G02X1340352Y860789I175J-97D01*
G01X1340353D01*
X1340703D01*
X1340704D01*
G02X1340878Y860686I-1J-200D01*
G03X1342103Y859965I1225J680D01*
G03Y862769I0J1402D01*
G03X1340878Y862048I0J-1401D01*
G02X1340704Y861945I-175J97D01*
G01X1340703D01*
X1340353D01*
X1340352D01*
G02X1340178Y862048I1J200D01*
G03X1337728I-1225J-680D01*
G02X1337554Y861945I-175J97D01*
G01X1337553D01*
X1337203D01*
X1337202D01*
G02X1337028Y862048I1J200D01*
G03X1335803Y862769I-1225J-680D01*
G03X1334578Y862049I0J-1402D01*
G02X1334403Y861946I-175J97D01*
G01X1334054D01*
G02X1333879Y862049I0J200D01*
G03X1333098Y862697I-1225J-682D01*
G01X1333097D01*
G02X1332961Y862887I64J190D01*
G01Y866145D01*
G02X1333097Y866335I200J0D01*
G01X1333098D01*
G03X1333879Y866983I-444J1330D01*
G02X1334054Y867086I175J-97D01*
G01X1334403D01*
G02X1334578Y866983I0J-200D01*
G03X1335803Y866263I1225J682D01*
G03X1337028Y866984I0J1401D01*
G02X1337202Y867087I175J-97D01*
G01X1337203D01*
X1337553D01*
X1337554D01*
G02X1337728Y866984I-1J-200D01*
G03X1340178I1225J680D01*
G02X1340352Y867087I175J-97D01*
G01X1340353D01*
X1340703D01*
X1340704D01*
G02X1340878Y866984I-1J-200D01*
G03X1342103Y866263I1225J680D01*
G03Y869067I0J1402D01*
G03X1340878Y868346I0J-1401D01*
G02X1340704Y868243I-175J97D01*
G01X1340703D01*
X1340353D01*
X1340352D01*
G02X1340178Y868346I1J200D01*
G03X1339635Y868890I-1226J-680D01*
G02X1339532Y869065I97J175D01*
G01Y869414D01*
G02X1339635Y869589I200J0D01*
G03X1340355Y870814I-682J1225D01*
G03X1339633Y872040I-1402J0D01*
G01X1339632D01*
Y872041D01*
G02X1339530Y872215I98J174D01*
G01Y872564D01*
G02X1339633Y872739I200J0D01*
G03X1340178Y873284I-681J1226D01*
G02X1340353Y873387I175J-97D01*
G01X1340702D01*
G02X1340876Y873285I0J-200D01*
G01X1340877Y873284D01*
G03X1342103Y872562I1226J680D01*
G03X1343328Y873282I0J1402D01*
G02X1343503Y873385I175J-97D01*
G01X1343852D01*
G02X1344027Y873282I0J-200D01*
G03X1345252Y872562I1225J682D01*
G03X1346654Y873964I0J1402D01*
G03X1345933Y875189I-1401J0D01*
G02X1345830Y875363I97J175D01*
G01Y875364D01*
Y875714D01*
Y875715D01*
G02X1345933Y875889I200J-1D01*
G03X1346654Y877114I-680J1225D01*
G03X1345934Y878339I-1402J0D01*
G02X1345831Y878514I97J175D01*
G01Y878863D01*
G02X1345934Y879038I200J0D01*
G03X1346654Y880263I-682J1225D01*
G03X1345933Y881488I-1401J0D01*
G02X1345830Y881662I97J175D01*
G01Y881663D01*
Y882013D01*
Y882014D01*
G02X1345933Y882188I200J-1D01*
G03X1346654Y883413I-680J1225D01*
G03X1345934Y884638I-1402J0D01*
G02X1345831Y884813I97J175D01*
G01Y885162D01*
G02X1345934Y885337I200J0D01*
G03X1346654Y886562I-682J1225D01*
G03X1345933Y887787I-1401J0D01*
G02X1345830Y887961I97J175D01*
G01Y887962D01*
Y888312D01*
Y888313D01*
G02X1345933Y888487I200J-1D01*
G03Y890937I-680J1225D01*
G02X1345830Y891111I97J175D01*
G01Y891112D01*
Y891462D01*
Y891463D01*
G02X1345933Y891637I200J-1D01*
G03X1346654Y892862I-680J1225D01*
G03X1345252Y894264I-1402J0D01*
G03X1344027Y893544I0J-1402D01*
G02X1343852Y893441I-175J97D01*
G01X1343503D01*
G02X1343328Y893544I0J200D01*
G03X1342103Y894264I-1225J-682D01*
G03X1340878Y893543I0J-1401D01*
G02X1340704Y893440I-175J97D01*
G01X1340703D01*
X1340353D01*
X1340352D01*
G02X1340178Y893543I1J200D01*
G03X1337728I-1225J-680D01*
G02X1337554Y893440I-175J97D01*
G01X1337553D01*
X1337203D01*
X1337202D01*
G02X1337028Y893543I1J200D01*
G03X1336485Y894086I-1225J-682D01*
G02X1336483Y894088I140J142D01*
G02X1336410Y894159I98J174D01*
G01Y894160D01*
G02X1336382Y894262I172J102D01*
G01Y894612D01*
G02X1336485Y894786I200J-1D01*
G03X1337204Y896011I-684J1225D01*
G03X1334400I-1402J0D01*
G03X1335120Y894787I1400J0D01*
G02X1335195Y894714I-97J-175D01*
G01Y894713D01*
G02X1335223Y894611I-172J-102D01*
G01Y894261D01*
G02X1335120Y894087I-200J1D01*
G03X1334578Y893544I684J-1224D01*
G02X1334403Y893441I-175J97D01*
G01X1334054D01*
G02X1333879Y893544I0J200D01*
G03X1333144Y894176I-1225J-682D01*
G01X1333085Y894198D01*
X1333014Y894301D01*
Y897279D01*
G02X1333073Y897421I200J0D01*
G01X1334892Y899240D01*
G02X1335148Y899264I142J-141D01*
G03X1336000Y898998I853J1234D01*
G03X1337243Y899655I0J1504D01*
G01X1337256Y899675D01*
X1337290Y899706D01*
X1337391Y899762D01*
G02X1337488Y899787I97J-175D01*
G01X1338418D01*
X1338526Y899703D01*
X1338543Y899636D01*
G03X1341457I1457J364D01*
G01X1341474Y899703D01*
X1341582Y899787D01*
X1349929D01*
X1350037Y899703D01*
X1350054Y899636D01*
G03X1352968I1457J364D01*
G01X1352985Y899703D01*
X1353093Y899787D01*
X1361512D01*
G02X1361609Y899762I0J-200D01*
G01X1361710Y899706D01*
X1361744Y899675D01*
X1361757Y899655D01*
G03X1364243I1243J846D01*
G01X1364256Y899675D01*
X1364290Y899706D01*
X1364391Y899762D01*
G02X1364488Y899787I97J-175D01*
G01X1365512D01*
G02X1365609Y899762I0J-200D01*
G01X1365710Y899706D01*
X1365744Y899675D01*
X1365757Y899655D01*
G03X1368243I1243J846D01*
G01X1368256Y899675D01*
X1368290Y899706D01*
X1368391Y899762D01*
G02X1368488Y899787I97J-175D01*
G01X1375759D01*
G02X1375871Y899753I0J-200D01*
G03X1377545I837J1246D01*
G02X1377657Y899787I112J-166D01*
G01X1381258D01*
G02X1381408Y899719I0J-200D01*
G01X1381635Y899462D01*
X1381660Y899380D01*
X1381655Y899337D01*
G03X1381644Y899162I1391J-175D01*
G01Y899161D01*
G03X1384448I1402J0D01*
G01Y899162D01*
G03X1384437Y899337I-1402J0D01*
G01X1384432Y899380D01*
X1384457Y899462D01*
X1384684Y899719D01*
G02X1384834Y899787I150J-132D01*
G01X1385908D01*
X1386017Y899698D01*
X1386032Y899627D01*
G03X1387504Y898428I1472J304D01*
G03X1388749Y899090I0J1502D01*
G02X1389388Y899122I332J-224D01*
G03X1390541Y898583I1153J964D01*
G03X1391978Y899646I0J1503D01*
G01X1391998Y899710D01*
X1392102Y899787D01*
G37*
G36*
G01X1416281Y122912D02*
G02X1416282Y122910I-178J-90D01*
G01X1416283Y122906D01*
X1416306Y122845D01*
G02X1416316Y122786I-190J-62D01*
G01Y117486D01*
G02X1416279Y117370I-200J0D01*
G03Y115622I1220J-874D01*
G02X1416316Y115506I-163J-116D01*
G01Y110681D01*
G03X1416329Y110610I200J0D01*
G02X1416341Y110527I-188J-70D01*
G01X1416333Y110411D01*
G02X1416294Y110305I-199J13D01*
G03X1415998Y109410I1206J-895D01*
G03X1417500Y107908I1502J0D01*
G03X1418432Y108232I0J1502D01*
G02X1418697Y108217I124J-157D01*
G01X1419246Y107668D01*
G03X1419388Y107609I142J141D01*
G01X1419965D01*
X1419982Y107606D01*
G03X1420054Y107596I201J1185D01*
G01X1420056D01*
G03X1420187Y107588I139J1194D01*
G01X1436114D01*
G02X1436314Y107388I0J-200D01*
G01Y104246D01*
G03X1436344Y103919I1802J0D01*
G01X1436345Y103912D01*
X1436348Y103877D01*
G02X1436334Y103803I-200J-1D01*
G01X1436323Y103776D01*
X1436305Y103754D01*
G02X1436263Y103714I-157J123D01*
G01X1436231Y103692D01*
G02X1436116Y103656I-114J164D01*
G01X1436075Y103664D01*
X1436034Y103677D01*
G02X1436007Y103688I62J190D01*
G03X1435340Y103845I-668J-1344D01*
G01X1435338D01*
G03X1433836Y102343I0J-1502D01*
G03X1434283Y101274I1502J0D01*
G02X1434285Y101272I-140J-142D01*
G03X1435358Y100821I1073J1051D01*
G03X1436858Y102242I0J1502D01*
G01X1436861Y102293D01*
X1436884Y102332D01*
G02X1436931Y102386I172J-102D01*
G02X1436951Y102401I130J-152D01*
G01X1437018Y102443D01*
X1437235Y102579D01*
G02X1437320Y102605I100J-174D01*
G01X1437368Y102608D01*
X1437402Y102594D01*
G03X1438116Y102446I715J1655D01*
G03X1439918Y104247I0J1802D01*
G01Y107388D01*
G02X1440118Y107588I200J0D01*
G01X1476361D01*
G02X1476399Y107584I-2J-200D01*
G02X1476501Y107531I-37J-196D01*
G01X1477918Y106114D01*
G02X1477971Y106013I-143J-140D01*
G01Y106011D01*
G02X1477975Y105974I-196J-40D01*
G01Y94811D01*
X1477964Y94779D01*
G03X1477878Y94279I1416J-501D01*
G03X1477964Y93779I1502J1D01*
G01X1477975Y93747D01*
Y87617D01*
G02X1477972Y87580I-200J-2D01*
G02X1477941Y87505I-197J37D01*
G01X1477925Y87482D01*
X1477879Y87444D01*
X1477852Y87433D01*
G03Y84659I576J-1387D01*
G01X1477879Y84648D01*
X1477925Y84610D01*
X1477941Y84587D01*
G02X1477972Y84512I-166J-112D01*
G02X1477975Y84475I-197J-35D01*
G01Y62340D01*
G02X1477974Y62323I-200J3D01*
G01Y62321D01*
G02X1477924Y62206I-199J18D01*
G01X1477887Y62168D01*
X1477886Y62167D01*
X1477719Y61999D01*
G02X1477656Y61956I-142J140D01*
G01X1477622Y61941D01*
X1477582Y61940D01*
X1477580D01*
G03X1476503Y61457I27J-1502D01*
G01X1476502Y61456D01*
G02X1476361Y61393I-146J137D01*
G01X1476159Y61398D01*
X1476049Y61401D01*
G02X1475967Y61421I5J200D01*
G01X1475929Y61439D01*
X1475901Y61473D01*
G03X1474746Y62015I-1155J-960D01*
G03Y59011I0J-1502D01*
G03X1475849Y59494I0J1501D01*
G01X1475850Y59495D01*
G02X1475991Y59558I146J-137D01*
G01X1476193Y59553D01*
X1476303Y59550D01*
G02X1476385Y59530I-5J-200D01*
G01X1476423Y59512D01*
X1476451Y59478D01*
G03X1477581Y58936I1155J960D01*
G01X1477622Y58935D01*
X1477656Y58920D01*
G02X1477712Y58883I-80J-183D01*
G01X1477886Y58709D01*
G02X1477888Y58707I-140J-142D01*
G01X1477924Y58670D01*
G02X1477974Y58555I-149J-133D01*
G01Y58553D01*
G02X1477975Y58536I-199J-20D01*
G01Y54060D01*
G02X1477953Y53969I-200J0D01*
G02X1477917Y53919I-178J90D01*
G01X1476713Y52715D01*
G02X1476663Y52679I-140J142D01*
G02X1476572Y52657I-91J178D01*
G01X1458042D01*
G02X1457951Y52679I0J200D01*
G02X1457901Y52715I90J178D01*
G01X1452700Y57916D01*
X1452699D01*
G02X1452534Y58004I1J200D01*
G01X1452320Y58322D01*
X1452316Y58365D01*
G03X1452969Y61590I-7749J3248D01*
G01Y61628D01*
G03X1450666Y67392I-8402J-15D01*
G03X1444547Y70036I-6119J-5759D01*
G03X1436145Y61634I0J-8402D01*
G03X1436765Y58467I8402J1D01*
G01Y58466D01*
G02X1436779Y58371I-185J-76D01*
G01X1436774Y58322D01*
X1436560Y58004D01*
G02X1436395Y57916I-166J112D01*
G01X1429249D01*
G02X1429225Y57917I-4J200D01*
G02X1429126Y57958I24J199D01*
G02X1429075Y58018I124J157D01*
G01X1429043Y58081D01*
Y58083D01*
X1428910Y58343D01*
G02X1428889Y58449I178J90D01*
G01Y58453D01*
X1428941Y58524D01*
G03X1429654Y60709I-2988J2184D01*
G03X1429211Y62466I-3701J1D01*
G01X1429204Y62479D01*
G02X1429182Y62573I178J91D01*
G01Y62603D01*
X1429263Y62752D01*
Y62754D01*
X1429375Y62956D01*
G02X1429430Y63013I168J-107D01*
G01X1429433Y63015D01*
X1429511Y63022D01*
X1429513D01*
G03X1429987Y63092I-317J3790D01*
G03X1432469Y64880I-794J3719D01*
G01X1432471Y64884D01*
G03X1431866Y69516I-3278J1927D01*
G03X1430623Y70346I-2692J-2685D01*
G03X1425829Y65021I-1450J-3515D01*
G01X1425832Y65016D01*
X1425833Y65013D01*
X1425837Y65004D01*
G02X1425853Y64921I-184J-79D01*
G01X1425852Y64869D01*
X1425722Y64651D01*
Y64649D01*
X1425643Y64519D01*
G02X1425605Y64477I-166J112D01*
G01X1425593Y64467D01*
G02X1425477Y64430I-116J163D01*
G01X1418633D01*
G03X1414932Y60729I0J-3701D01*
G01Y60727D01*
G03X1415640Y58551I3701J1D01*
G01X1415656Y58529D01*
X1415675Y58478D01*
X1415678Y58449D01*
G02X1415656Y58343I-200J-14D01*
G01X1415583Y58199D01*
X1415490Y58016D01*
G02X1415453Y57969I-174J99D01*
G02X1415420Y57944I-137J146D01*
G01X1415404Y57936D01*
G02X1415365Y57922I-87J180D01*
G02X1415317Y57916I-49J194D01*
G01X1378620D01*
G02X1378529Y57938I0J200D01*
G02X1378479Y57974I90J178D01*
G01X1376892Y59561D01*
G02X1376856Y59611I142J140D01*
G02X1376834Y59702I178J91D01*
G01Y95781D01*
X1376833Y95782D01*
G02X1376797Y95832I142J140D01*
G02X1376775Y95923I178J91D01*
G01Y108878D01*
G02X1376806Y108985I200J0D01*
G01X1376821Y109008D01*
X1376862Y109045D01*
X1376889Y109058D01*
G03X1377443Y109512I-648J1355D01*
G01X1377468Y109545D01*
X1377500Y109564D01*
G02X1377563Y109588I102J-172D01*
G01X1377866Y109633D01*
G02X1377932Y109627I15J-200D01*
G01X1377961Y109619D01*
X1377976Y109608D01*
G03X1378144Y109492I936J1175D01*
G03X1378892Y109282I766J1292D01*
G01X1378935D01*
G03X1380223Y110052I-24J1502D01*
G02X1380342Y110147I175J-97D01*
G01X1380365Y110153D01*
X1380714D01*
G02X1380741Y110151I-1J-200D01*
G02X1380879Y110061I-31J-198D01*
G03X1381004Y109875I1306J743D01*
G03X1381135Y109730I1178J933D01*
G02X1381137Y109728I-140J-142D01*
G03X1382205Y109282I1068J1056D01*
G03X1383707Y110784I0J1502D01*
G03X1383256Y111857I-1502J0D01*
G02X1383254Y111859I140J142D01*
G03X1382185Y112306I-1069J-1055D01*
G03X1380881Y111549I0J-1502D01*
G02X1380721Y111455I-170J106D01*
G01X1380404D01*
G02X1380356Y111461I1J200D01*
G02X1380328Y111470I47J194D01*
G01X1380316Y111475D01*
X1380287Y111487D01*
G02X1380234Y111520I78J184D01*
G01X1380210Y111540D01*
X1380193Y111568D01*
G03X1379969Y111851I-1282J-784D01*
G02X1379967Y111853I140J142D01*
G03X1378892Y112306I-1075J-1050D01*
G01X1378891D01*
G03X1377690Y111706I0J-1502D01*
G01X1377665Y111673D01*
X1377633Y111654D01*
G02X1377569Y111630I-101J172D01*
G01X1377477Y111616D01*
X1377269Y111585D01*
G02X1377201Y111591I-17J199D01*
G01X1377165Y111600D01*
X1377157Y111606D01*
X1377132Y111624D01*
G03X1377084Y111658I-892J-1208D01*
G01X1377064Y111672D01*
X1377050Y111687D01*
G02X1377020Y111729I146J136D01*
G01X1376975Y111812D01*
G02X1376952Y111903I177J93D01*
G01Y111927D01*
G02X1376974Y112017I200J-1D01*
G01X1376988Y112042D01*
X1376992Y112049D01*
G02X1377021Y112089I175J-96D01*
G01X1377040Y112109D01*
X1377061Y112122D01*
G03X1377764Y113394I-799J1272D01*
G03X1377325Y114455I-1502J0D01*
G02X1377323Y114457I140J142D01*
G03X1376889Y114770I-1082J-1043D01*
G01X1376888Y114771D01*
G02X1376805Y114844I85J181D01*
G01X1376790Y114867D01*
X1376782Y114895D01*
G02X1376775Y114947I193J52D01*
G01Y115079D01*
G02X1376783Y115135I200J0D01*
G03X1377811Y116594I-521J1459D01*
G03X1377096Y117899I-1548J0D01*
G02X1377090Y117927I192J56D01*
G02X1377088Y117954I198J28D01*
G01Y118272D01*
G02X1377105Y118351I200J-2D01*
G03X1377764Y119594I-843J1243D01*
G03X1377325Y120655I-1502J0D01*
G02X1377323Y120657I140J142D01*
G03X1376889Y120970I-1082J-1043D01*
G01X1376888Y120971D01*
G02X1376805Y121044I85J181D01*
G01X1376790Y121067D01*
X1376782Y121095D01*
G02X1376775Y121147I193J52D01*
G01Y122628D01*
G02X1376822Y122757I200J0D01*
G01X1376845Y122785D01*
X1376942Y122801D01*
G03X1378198Y124283I-246J1482D01*
G01Y124298D01*
G03X1377753Y125350I-1502J-15D01*
G02X1377751Y125352I140J142D01*
G03X1376940Y125782I-1076J-1049D01*
G01X1376926Y125785D01*
G02X1376822Y125850I49J194D01*
G01X1376799Y125877D01*
X1376787Y125908D01*
G02X1376778Y125940I188J70D01*
G02X1376775Y125976I197J35D01*
G01Y131940D01*
G02X1376776Y131958I200J-2D01*
G02X1376798Y132032I199J-19D01*
G02X1376896Y132123I177J-92D01*
G01X1376935Y132140D01*
X1377246Y132273D01*
G02X1377349Y132281I66J-189D01*
G01X1377376Y132276D01*
X1377428Y132250D01*
X1377442Y132236D01*
X1377452Y132227D01*
X1377453Y132226D01*
G03X1378505Y131796I1052J1072D01*
G03X1379943Y132865I0J1502D01*
G01Y132866D01*
X1379965Y132937D01*
X1379969Y132942D01*
X1380258Y133115D01*
X1380291Y133121D01*
G03X1380652Y133077I361J1459D01*
G03X1382154Y134579I0J1502D01*
G03X1381703Y135652I-1502J0D01*
G02X1381701Y135654I140J142D01*
G03X1380632Y136101I-1069J-1055D01*
G03X1379204Y135066I0J-1503D01*
G01X1379192Y135029D01*
X1379170Y135002D01*
G02X1379126Y134962I-155J126D01*
G01X1379086Y134938D01*
G02X1379084Y134936I-142J140D01*
G01X1378876Y134813D01*
G02X1378824Y134795I-91J178D01*
G01X1378792Y134789D01*
X1378753Y134796D01*
G03X1378486Y134820I-267J-1478D01*
G01X1378485D01*
G03X1377450Y134407I0J-1503D01*
G01X1377444Y134401D01*
G02X1377347Y134354I-133J150D01*
G01X1377320Y134349D01*
X1377290Y134353D01*
G02X1377236Y134367I23J199D01*
G01X1376983Y134476D01*
X1376890Y134516D01*
X1376868Y134533D01*
G03X1376859Y134540I-127J-154D01*
G01X1376828Y134562D01*
G02X1376776Y134680I147J135D01*
G01Y134682D01*
G02X1376775Y134697I199J21D01*
G01Y241469D01*
G02X1376779Y241506I200J-3D01*
G01Y241508D01*
G02X1376832Y241609I196J-39D01*
G01X1377594Y242371D01*
G02X1377620Y242393I142J-141D01*
G02X1377677Y242421I116J-163D01*
G01X1377679D01*
G02X1377692Y242425I65J-189D01*
G01X1377711Y242424D01*
G03X1377809Y242420I98J1206D01*
G01X1387731D01*
G03X1387845Y242425I4J1210D01*
G01X1387849D01*
G03X1387871Y242427I-99J1207D01*
G01X1387872D01*
G03X1387890Y242429I-125J1204D01*
G01X1391039D01*
G02X1391056Y242428I-3J-200D01*
G03X1391195Y242420I139J1202D01*
G01X1395664D01*
G02X1395693Y242417I-5J-191D01*
G01X1395756Y242406D01*
G02X1395803Y242372I-92J-177D01*
G01X1396012Y242171D01*
X1396026Y242157D01*
X1396031Y242153D01*
X1396032Y242152D01*
X1396062Y242084D01*
X1396064Y242043D01*
Y242042D01*
G03X1396230Y241409I1501J55D01*
G03X1396510Y241029I1334J690D01*
G02X1396512Y241027I-140J-142D01*
G03X1397585Y240576I1073J1051D01*
G03X1399086Y242125I0J1502D01*
G01X1399098Y242152D01*
X1399327Y242372D01*
G02X1399374Y242406I139J-143D01*
G01X1399437Y242417D01*
G02X1399466Y242420I34J-188D01*
G01X1403319D01*
G03X1403453Y242427I4J1210D01*
G02X1403471Y242428I20J-199D01*
G01X1406854D01*
G02X1406872Y242427I-2J-200D01*
G03X1407001Y242420I130J1203D01*
G01X1413603D01*
G02X1413612Y242419I-17J-190D01*
G03X1413645Y242414I198J1195D01*
G01X1413691Y242406D01*
G02X1413693Y242405I-88J-179D01*
G01X1416242Y239856D01*
G02X1416266Y239762I-176J-95D01*
G01Y153169D01*
G02X1416264Y153146I-200J6D01*
G01X1416262Y153135D01*
X1416252Y153081D01*
X1416250Y153075D01*
G02X1416219Y153025I-184J79D01*
G01X1416198Y153004D01*
G03X1415979Y147637I2435J-2787D01*
G03X1416090Y147526I2672J2561D01*
G03X1416163Y147458I2559J2674D01*
G03X1416223Y147405I2480J2748D01*
G02X1416266Y147286I-157J-124D01*
G01Y122986D01*
G03X1416281Y122912I200J2D01*
G37*
G36*
G01X1395897Y276294D02*
X1451883D01*
G02X1452023Y276237I0J-200D01*
G01X1452024Y276236D01*
X1453309Y274951D01*
G02X1453311Y274949I-140J-142D01*
G02X1453368Y274809I-143J-140D01*
G01Y267385D01*
G02X1453255Y267205I-200J0D01*
G01X1452878Y267023D01*
X1452765Y267036D01*
X1452719Y267072D01*
G03X1451785Y267398I-934J-1175D01*
G03Y264394I0J-1502D01*
G03X1452719Y264720I0J1501D01*
G01X1452765Y264756D01*
X1452878Y264769D01*
X1453255Y264587D01*
G02X1453368Y264407I-87J-180D01*
G01Y257955D01*
Y257945D01*
G02X1453295Y257800I-200J10D01*
G02X1453268Y257782I-124J157D01*
G01X1452978Y257614D01*
G02X1452827Y257593I-101J173D01*
G01X1452771Y257608D01*
X1452749Y257620D01*
G03X1452027Y257805I-723J-1319D01*
G01X1452026D01*
G03Y254801I0J-1502D01*
G01X1452027D01*
G03X1452749Y254986I-1J1504D01*
G01X1452771Y254998D01*
X1452827Y255013D01*
G02X1452979Y254992I51J-194D01*
G01X1453249Y254835D01*
X1453273Y254821D01*
X1453278Y254818D01*
G02X1453368Y254651I-110J-167D01*
G01Y207178D01*
X1453361Y207153D01*
G03X1453310Y206764I1451J-388D01*
G01Y206755D01*
G03X1453361Y206372I1502J5D01*
G01X1453368Y206346D01*
Y202582D01*
G03X1453427Y202440I200J0D01*
G01X1453848Y202019D01*
G03X1453990Y201960I142J141D01*
G01X1456708D01*
G02X1456848Y201903I0J-200D01*
G01X1456849Y201902D01*
X1457163Y201588D01*
G03X1457162Y201569I1198J-73D01*
G01Y193724D01*
G02X1457076Y193560I-200J0D01*
G01X1456952Y193474D01*
X1456809Y193374D01*
G02X1456659Y193341I-115J164D01*
G01X1456640Y193344D01*
X1456624Y193350D01*
G03X1456104Y193443I-520J-1409D01*
G01X1456088D01*
G03Y190439I16J-1502D01*
G01X1456105D01*
G03X1456608Y190526I-1J1502D01*
G01X1456625Y190532D01*
X1456662Y190539D01*
G02X1456809Y190508I35J-197D01*
G02X1456812Y190506I-109J-167D01*
G01X1456952Y190408D01*
X1457076Y190322D01*
G02X1457162Y190158I-114J-164D01*
G01Y165175D01*
G02X1457103Y165033I-200J0D01*
G01X1453637Y161567D01*
X1453609Y161538D01*
X1453535Y161508D01*
X1446521D01*
G02X1446350Y161604I0J200D01*
G01X1446173Y161896D01*
G02X1446168Y162094I171J103D01*
G01X1446171Y162100D01*
X1446188Y162135D01*
G03X1446340Y162781I-1350J659D01*
G01Y162787D01*
Y162793D01*
Y162815D01*
G03X1445934Y163820I-1502J-22D01*
G01X1445907Y163849D01*
X1445880Y163918D01*
Y164268D01*
X1445907Y164338D01*
X1445934Y164366D01*
G03Y166420I-1096J1027D01*
G01X1445907Y166448D01*
X1445880Y166518D01*
Y166868D01*
X1445907Y166938D01*
X1445934Y166966D01*
G03X1446340Y167993I-1096J1027D01*
G03X1445970Y168980I-1501J0D01*
G01X1445946Y169008D01*
X1445921Y169074D01*
Y169412D01*
X1445946Y169478D01*
X1445970Y169506D01*
G03X1446340Y170493I-1131J987D01*
G03X1443336I-1502J0D01*
G03X1443706Y169506I1501J0D01*
G01X1443730Y169478D01*
X1443755Y169412D01*
Y169074D01*
X1443730Y169008D01*
X1443706Y168980D01*
G03X1443336Y167993I1131J-987D01*
G03X1443742Y166966I1502J0D01*
G01X1443769Y166938D01*
X1443796Y166868D01*
Y166518D01*
X1443769Y166448D01*
X1443742Y166420D01*
G03Y164366I1096J-1027D01*
G01X1443769Y164338D01*
X1443796Y164268D01*
Y163918D01*
X1443769Y163849D01*
X1443742Y163820D01*
G03X1443336Y162821I1096J-1027D01*
G01Y162810D01*
Y162792D01*
G03X1443497Y162116I1502J1D01*
G01X1443498Y162114D01*
X1443508Y162094D01*
X1443521Y162042D01*
G02X1443498Y161890I-194J-48D01*
G01X1443466Y161837D01*
Y161835D01*
X1443324Y161603D01*
G02X1443153Y161508I-170J105D01*
G01X1439584D01*
G02X1439426Y161585I0J200D01*
G01X1439203Y161870D01*
X1439184Y161959D01*
X1439195Y162005D01*
G03X1439240Y162368I-1457J365D01*
G03X1437738Y163870I-1502J0D01*
G03X1436711Y163464I0J-1502D01*
G01X1436683Y163437D01*
X1436613Y163410D01*
X1436263D01*
X1436193Y163437D01*
X1436165Y163464D01*
G03X1435138Y163870I-1027J-1096D01*
G03X1433636Y162368I0J-1502D01*
G03X1433681Y162005I1502J2D01*
G01X1433692Y161959D01*
X1433673Y161870D01*
X1433450Y161585D01*
G02X1433292Y161508I-158J123D01*
G01X1418144D01*
G02X1418002Y161567I0J200D01*
G01X1417346Y162223D01*
G02X1417288Y162364I142J141D01*
G01Y240157D01*
G03X1417229Y240298I-200J-1D01*
G01X1414447Y243080D01*
G03X1414434Y243093I-856J-843D01*
G01X1414175Y243352D01*
G03X1414035Y243410I-141J-142D01*
G01X1413817D01*
X1413800Y243413D01*
G03X1413786Y243415I-177J-1188D01*
G01X1413770Y243417D01*
X1413759Y243420D01*
X1413755D01*
X1413744Y243421D01*
G03X1413604Y243430I-147J-1193D01*
G01X1413600D01*
G03X1413597I-1J-1202D01*
G01X1407006D01*
G02X1406848Y243507I0J200D01*
G01X1406625Y243793D01*
X1406606Y243882D01*
X1406618Y243928D01*
G03X1406664Y244297I-1457J369D01*
G03X1405162Y245799I-1502J0D01*
G03X1404795Y245753I2J-1502D01*
G01X1404739Y245739D01*
X1404632Y245773D01*
X1404324Y246131D01*
X1404306Y246242D01*
X1404328Y246295D01*
G03X1404444Y246874I-1387J579D01*
G03X1402942Y248376I-1502J0D01*
G03X1401913Y247968I0J-1502D01*
G01X1401879Y247936D01*
X1401793Y247909D01*
X1401448Y247958D01*
G02X1401335Y248014I28J198D01*
G01X1401296Y248053D01*
X1401284Y248073D01*
G03X1400000Y248794I-1284J-783D01*
G03Y245790I0J-1502D01*
G03X1401029Y246198I0J1502D01*
G01X1401063Y246230D01*
X1401149Y246257D01*
X1401504Y246207D01*
G02X1401647Y246112I-28J-198D01*
G01X1401648Y246111D01*
Y246110D01*
G03X1402942Y245371I1294J763D01*
G03X1403083Y245378I-4J1503D01*
G01X1403118Y245382D01*
G03X1403181Y245391I-181J1491D01*
G03X1403210Y245396I-241J1483D01*
G01X1403211D01*
G03X1403309Y245418I-280J1476D01*
G01X1403365Y245432D01*
X1403472Y245398D01*
X1403742Y245084D01*
G02X1403776Y244878I-151J-131D01*
G01X1403775Y244876D01*
Y244875D01*
G03X1403669Y244474I1386J-581D01*
G01X1403664Y244419D01*
G03X1403659Y244297I1498J-122D01*
G01Y244295D01*
G03X1403705Y243927I1503J1D01*
G01X1403716Y243882D01*
X1403698Y243793D01*
X1403478Y243508D01*
G02X1403455Y243483I-158J122D01*
G02X1403326Y243430I-136J147D01*
G01X1399465D01*
G03X1399266Y243413I2J-1201D01*
G01X1399249Y243410D01*
X1398303D01*
X1398257Y243422D01*
X1398238Y243431D01*
X1398236Y243432D01*
G03X1397742Y243572I-651J-1354D01*
G03X1397696Y243576I-153J-1494D01*
G03X1397344Y243561I-112J-1498D01*
G03X1396933Y243432I240J-1483D01*
G01X1396914Y243422D01*
X1396867Y243410D01*
X1395881D01*
X1395864Y243413D01*
G03X1395665Y243430I-201J-1184D01*
G01X1391197D01*
G02X1391029Y243522I0J200D01*
G01X1391012Y243548D01*
X1390860Y243780D01*
G02X1390830Y243926I167J110D01*
G01X1390835Y243952D01*
X1390844Y243974D01*
G03X1390968Y244571I-1378J598D01*
G01Y244590D01*
G03X1387964I-1502J-19D01*
G01Y244571D01*
G03X1388089Y243971I1503J0D01*
G01X1388104Y243936D01*
X1388106Y243886D01*
X1388105Y243874D01*
G02X1388074Y243782I-199J16D01*
G01X1388060Y243760D01*
X1387901Y243520D01*
G02X1387734Y243430I-167J110D01*
G01X1377805D01*
G02X1377663Y243489I0J200D01*
G01X1376074Y245078D01*
X1376045Y245106D01*
X1376015Y245180D01*
Y265149D01*
G02X1376078Y265295I200J0D01*
G01X1376319Y265522D01*
X1376395Y265550D01*
X1376437Y265548D01*
G03X1377559Y265518I1114J20672D01*
G01Y265517D01*
G03X1395648Y276150I0J20703D01*
G01Y276151D01*
G02X1395726Y276228I174J-99D01*
G01X1395800Y276269D01*
G02X1395897Y276294I97J-175D01*
G37*
G36*
G01X1390106Y624893D02*
Y629863D01*
G02X1390230Y630048I200J0D01*
G01X1390287Y630071D01*
X1390404Y630048D01*
X1392135Y628317D01*
G02X1392194Y628176I-141J-142D01*
G01Y625344D01*
G02X1391994Y625144I-200J0D01*
G01X1391969D01*
X1391946Y625150D01*
G03X1391762Y625184I-364J-1457D01*
G01X1391720Y625189D01*
G03X1391586Y625195I-134J-1497D01*
G03X1390528Y624759I0J-1502D01*
G01X1390501Y624732D01*
X1390416Y624696D01*
G02X1390263Y624694I-79J184D01*
G01X1390232Y624707D01*
G02X1390106Y624893I74J186D01*
G37*
G36*
G01X1471773Y202336D02*
X1475285D01*
G02X1475426Y202278I0J-200D01*
G01X1477466Y200238D01*
X1477481Y200207D01*
G03X1477520Y200132I1352J655D01*
G01X1477521Y200131D01*
G03X1477536Y200105I1308J738D01*
G01X1477549Y200083D01*
X1477565Y200027D01*
X1477578Y199981D01*
Y197600D01*
G02X1477545Y197490I-200J0D01*
G03Y195840I1254J-825D01*
G02X1477578Y195730I-167J-110D01*
G01Y193600D01*
G02X1477545Y193490I-200J0D01*
G03Y191840I1254J-825D01*
G02X1477578Y191730I-167J-110D01*
G01Y187518D01*
X1477568Y187475D01*
X1477557Y187453D01*
G03Y186103I1355J-675D01*
G01X1477568Y186081D01*
X1477578Y186038D01*
Y181600D01*
G02X1477545Y181490I-200J0D01*
G03Y179840I1254J-825D01*
G02X1477578Y179730I-167J-110D01*
G01Y177600D01*
G02X1477545Y177490I-200J0D01*
G03Y175840I1254J-825D01*
G02X1477578Y175730I-167J-110D01*
G01Y173600D01*
G02X1477545Y173490I-200J0D01*
G03Y171840I1254J-825D01*
G02X1477578Y171730I-167J-110D01*
G01Y169600D01*
G02X1477545Y169490I-200J0D01*
G03Y167840I1254J-825D01*
G02X1477578Y167730I-167J-110D01*
G01Y163086D01*
G02X1477523Y162947I-200J-1D01*
G01X1477441Y162862D01*
X1477408Y162846D01*
X1477316Y162801D01*
X1477283Y162797D01*
G03Y159815I182J-1491D01*
G01X1477316Y159811D01*
X1477409Y159766D01*
G02X1477466Y159724I-88J-180D01*
G01X1477523Y159665D01*
G02X1477578Y159526I-145J-138D01*
G01Y151308D01*
G02X1477378Y151108I-200J0D01*
G01X1470804D01*
G02X1470628Y151213I0J200D01*
G01X1470462Y151523D01*
G02X1470438Y151625I176J95D01*
G01X1470440Y151682D01*
X1470471Y151729D01*
G03X1470723Y152562I-1251J833D01*
G03X1469221Y154064I-1502J0D01*
G03X1467927Y153325I0J-1502D01*
G01X1467901Y153281D01*
X1467816Y153229D01*
X1467638Y153219D01*
X1467385Y153204D01*
X1467295Y153245D01*
X1467265Y153285D01*
G03X1466071Y153875I-1194J-913D01*
G03X1464569Y152373I0J-1502D01*
G03X1464734Y151689I1502J0D01*
G01X1464758Y151642D01*
X1464754Y151539D01*
X1464548Y151203D01*
G02X1464378Y151108I-170J105D01*
G01X1455060D01*
G02X1454932Y151155I1J200D01*
G01X1454099Y151988D01*
X1453794Y152292D01*
G03X1452379Y152878I-1415J-1415D01*
G01X1446019D01*
G03X1444604Y152292I0J-2001D01*
G01X1441267Y148955D01*
G03X1440744Y148042I1414J-1416D01*
G03X1440680Y147540I1938J-502D01*
G03X1442678Y145538I2002J0D01*
G01X1442682D01*
G03X1443184Y145602I0J2002D01*
G03X1444097Y146125I-503J1937D01*
G01X1446789Y148817D01*
G02X1446931Y148876I142J-141D01*
G01X1449409D01*
G02X1449558Y148809I0J-200D01*
G01X1449757Y148588D01*
G02X1449807Y148437I-149J-133D01*
G01Y148434D01*
G03X1449799Y148277I1494J-155D01*
G03X1451301Y146775I1502J0D01*
G03X1452490Y147359I0J1502D01*
G01X1452514Y147390D01*
X1452547Y147410D01*
G02X1452617Y147435I101J-173D01*
G01X1452886Y147479D01*
G02X1453030Y147447I32J-198D01*
G01X1453031Y147446D01*
G03X1453495Y147214I1120J1659D01*
G03X1454150Y147104I654J1892D01*
G01X1477378D01*
G02X1477578Y146904I0J-200D01*
G01Y124540D01*
X1477575Y124524D01*
G03X1477556Y124283I1483J-238D01*
G03X1477575Y124042I1502J-3D01*
G01X1477578Y124026D01*
Y120792D01*
G02X1477564Y120718I-200J0D01*
G01X1477526Y120621D01*
X1477502Y120594D01*
G03Y118594I1122J-1000D01*
G01X1477526Y118567D01*
X1477564Y118470D01*
G02X1477578Y118396I-186J-74D01*
G01Y117752D01*
X1477524Y117618D01*
X1477501Y117592D01*
G03X1477122Y116594I1124J-998D01*
G01Y116592D01*
G03X1477426Y115687I1503J1D01*
G02X1477466Y115567I-160J-120D01*
G01Y114421D01*
G02X1477426Y114301I-200J0D01*
G03Y112487I1199J-907D01*
G02X1477466Y112367I-160J-120D01*
G01Y111688D01*
G03X1477496Y111583I200J0D01*
G01X1477547Y111504D01*
G02X1477578Y111396I-169J-107D01*
G01Y109734D01*
G02X1477519Y109592I-200J0D01*
G01X1476576Y108649D01*
G02X1476434Y108590I-142J141D01*
G01X1439762D01*
G02X1439598Y108676I0J200D01*
G03X1436634I-1482J-1027D01*
G02X1436470Y108590I-164J114D01*
G01X1420189D01*
G02X1420047Y108649I0J200D01*
G01X1418988Y109708D01*
X1418963Y109753D01*
X1418956Y109780D01*
G03X1417870Y110866I-1456J-370D01*
G01X1417843Y110873D01*
X1417798Y110898D01*
X1417736Y110960D01*
G02X1417677Y111102I141J142D01*
G01Y114907D01*
X1417764Y115016D01*
X1417833Y115031D01*
G03Y117961I-333J1465D01*
G01X1417764Y117976D01*
X1417677Y118085D01*
Y159263D01*
G02X1417736Y159405I200J0D01*
G01X1418599Y160268D01*
G02X1418741Y160327I142J-141D01*
G01X1454258D01*
G03X1454400Y160386I0J200D01*
G01X1458105Y164091D01*
G03X1458164Y164233I-141J142D01*
G01Y201546D01*
G02X1458165Y201564I200J-2D01*
G01X1458167Y201587D01*
G02X1458225Y201711I199J-18D01*
G01X1458791Y202277D01*
G02X1458933Y202336I142J-141D01*
G01X1468633D01*
G02X1468810Y202229I0J-200D01*
G01X1468974Y201916D01*
G02X1468963Y201711I-177J-93D01*
G01X1468962Y201710D01*
G03X1468701Y200873I1241J-846D01*
G01Y200845D01*
G03X1471705I1502J19D01*
G01Y200865D01*
G03X1471444Y201711I-1502J0D01*
G01X1471412Y201757D01*
X1471406Y201867D01*
X1471596Y202229D01*
G02X1471773Y202336I177J-93D01*
G37*
G36*
G01X1447808Y811767D02*
G03X1447001Y812002I-807J-1267D01*
G01X1446998D01*
G03X1446835Y811994I-8J-1502D01*
G01X1446763Y811983D01*
G03X1445498Y810500I237J-1483D01*
G03X1446824Y809008I1502J0D01*
G01X1446879Y809002D01*
G03X1446912Y809000I107J1499D01*
G01X1446920D01*
G03X1446999Y808997I97J1500D01*
G01X1447001D01*
G03X1447837Y809252I-2J1503D01*
G01X1447883Y809283D01*
X1447993Y809289D01*
X1448338Y809105D01*
G02X1448448Y808983I-81J-183D01*
G01X1448459Y808951D01*
Y778201D01*
G02X1448368Y778033I-200J0D01*
G01X1448227Y777941D01*
X1448225D01*
X1448090Y777852D01*
G02X1447907Y777832I-111J166D01*
G01X1447861Y777850D01*
X1447859Y777851D01*
G03X1447290Y777963I-569J-1390D01*
G01X1447260D01*
G03Y774959I29J-1502D01*
G01X1447291D01*
G03X1447897Y775087I-1J1503D01*
G01X1447944Y775108D01*
X1448044Y775100D01*
X1448225Y774982D01*
G03X1448227Y774981I90J178D01*
G01X1448366Y774891D01*
G02X1448427Y774830I-107J-168D01*
G02X1448452Y774774I-168J-109D01*
G01X1448459Y774747D01*
Y768271D01*
G02X1448400Y768129I-200J0D01*
G01X1437930Y757659D01*
G02X1437788Y757600I-142J141D01*
G01X1435479D01*
G02X1435305Y757701I0J200D01*
G03X1432695I-1305J-743D01*
G02X1432521Y757600I-174J99D01*
G01X1427653D01*
X1427585Y757626D01*
X1427557Y757651D01*
G03X1427550Y757658I-144J-137D01*
G01X1427544Y757662D01*
X1427487Y757716D01*
X1427437Y757713D01*
X1427310Y757784D01*
G02X1427275Y757808I95J176D01*
G01X1427254Y757826D01*
X1427232Y757860D01*
G03X1426000Y758502I-1232J-861D01*
G03X1425733Y758478I0J-1502D01*
G01X1425684Y758469D01*
X1425591Y758498D01*
X1424431Y759658D01*
G02X1424372Y759800I141J142D01*
G01Y898720D01*
X1424455Y898827D01*
X1424521Y898845D01*
G03X1424538Y898849I-336J1465D01*
G01X1424579Y898861D01*
G03X1425630Y900295I-453J1434D01*
G03X1424520Y901746I-1503J0D01*
G01X1424454Y901764D01*
X1424372Y901871D01*
Y904269D01*
G02X1424382Y904331I200J0D01*
G01X1424411Y904419D01*
X1424427Y904442D01*
G03X1424590Y904749I-1237J853D01*
G03X1424679Y905494I-1400J545D01*
G03X1424661Y905601I-1489J-196D01*
G03X1424434Y906138I-1471J-305D01*
G01Y906139D01*
X1424426Y906151D01*
X1424407Y906191D01*
G02X1424397Y906214I178J91D01*
G01X1424383Y906256D01*
G02X1424372Y906321I189J65D01*
G01Y908905D01*
Y908913D01*
G02X1424468Y909076I200J-8D01*
G02X1424494Y909089I102J-172D01*
G01X1424831Y909233D01*
G02X1424974Y909239I79J-184D01*
G01X1425017Y909224D01*
G03X1426085Y908779I1068J1059D01*
G03Y911783I0J1502D01*
G03X1425048Y911368I0J-1503D01*
G02X1424974Y911323I-138J144D01*
G02X1424831Y911329I-64J190D01*
G01X1424494Y911473D01*
G02X1424468Y911486I76J185D01*
G02X1424372Y911649I104J171D01*
G01Y934878D01*
G02X1424435Y935024I200J0D01*
G01X1424649Y935224D01*
G02X1424785Y935278I137J-146D01*
G01X1424814D01*
G03X1424897Y935275I96J1499D01*
G03Y938279I0J1502D01*
G03X1424800Y938276I-2J-1502D01*
G01X1424797D01*
G02X1424651Y938329I-10J200D01*
G01X1424436Y938529D01*
G02X1424372Y938675I136J147D01*
G01Y976428D01*
G02X1424431Y976570I200J0D01*
G01X1447750Y999889D01*
G02X1447752Y999891I142J-140D01*
G02X1447892Y999948I140J-143D01*
G01X1460174D01*
G02X1460314Y999891I0J-200D01*
G01X1460315Y999890D01*
X1467728Y992477D01*
G03X1467870Y992418I142J141D01*
G01X1531920D01*
G02X1532060Y992361I0J-200D01*
G01X1532061Y992360D01*
X1536003Y988418D01*
G02X1536005Y988416I-140J-142D01*
G02X1536062Y988276I-143J-140D01*
G01Y967056D01*
G02X1536003Y966914I-200J0D01*
G01X1534268Y965179D01*
G02X1534126Y965120I-142J141D01*
G01X1507737D01*
G02X1507580Y965196I0J200D01*
G01X1507387Y965440D01*
G02X1507362Y965480I156J125D01*
G02X1507348Y965522I182J84D01*
G01X1507338Y965567D01*
X1507349Y965612D01*
G03X1507391Y965964I-1461J353D01*
G03X1505888Y967467I-1503J0D01*
G03X1504390Y966093I0J-1504D01*
G01Y966089D01*
X1504386Y966056D01*
G03X1504385Y966036I199J-20D01*
G01Y966035D01*
Y965983D01*
G03Y965967I1503J-8D01*
G01Y965963D01*
G03X1504764Y964966I1503J1D01*
G01X1504788Y964939D01*
X1504840Y964809D01*
Y964771D01*
X1504841Y964691D01*
G02X1504820Y964599I-200J-3D01*
G01X1504802Y964564D01*
X1495685Y955447D01*
X1495645Y955422D01*
X1495621Y955415D01*
G03X1494638Y954432I451J-1434D01*
G01X1494631Y954408D01*
X1494606Y954368D01*
X1492447Y952209D01*
G03X1492388Y952067I141J-142D01*
G01Y896753D01*
X1492387Y896743D01*
X1492385Y896709D01*
X1492357Y896646D01*
X1492145Y896422D01*
G02X1492083Y896377I-146J136D01*
G01X1492049Y896362D01*
X1492011Y896359D01*
G03Y893361I90J-1499D01*
G01X1492049Y893358D01*
X1492083Y893343D01*
G02X1492144Y893299I-85J-181D01*
G01X1492355Y893078D01*
X1492383Y893017D01*
X1492386Y892983D01*
X1492388Y892967D01*
Y877196D01*
G02X1492306Y877035I-200J0D01*
G01X1492006Y876816D01*
X1491913Y876800D01*
X1491867Y876815D01*
G03X1491414Y876885I-453J-1431D01*
G03Y873881I0J-1502D01*
G03X1491867Y873951I0J1501D01*
G01X1491913Y873966D01*
X1492007Y873950D01*
X1492306Y873731D01*
G02X1492388Y873570I-118J-161D01*
G01Y871964D01*
X1492358Y871890D01*
X1492329Y871862D01*
X1488508Y868041D01*
G02X1488366Y867982I-142J141D01*
G01X1476588D01*
G02X1476507Y867999I0J200D01*
G01X1476505Y868000D01*
G02X1476386Y868183I81J183D01*
G01Y868185D01*
G03Y868202I-1503J8D01*
G01Y868207D01*
G03X1473380I-1503J-1D01*
G01Y868202D01*
G03Y868185I1503J-9D01*
G01Y868182D01*
G02X1473180Y867982I-200J0D01*
G01X1467411D01*
G03X1467302Y867978I-10J-1206D01*
G01X1467293Y867977D01*
X1462793D01*
G02X1462611Y868094I0J200D01*
G01Y868095D01*
G03X1461241Y868978I-1370J-621D01*
G03X1459754Y867692I0J-1503D01*
G01X1459749Y867660D01*
X1459720Y867602D01*
X1448518Y856400D01*
G03X1448459Y856258I141J-142D01*
G01Y846048D01*
G02X1448400Y845906I-200J0D01*
G01X1448347Y845853D01*
X1448319Y845839D01*
G03Y843161I681J-1339D01*
G01X1448347Y843147D01*
X1448439Y843055D01*
G02X1448459Y842968I-180J-87D01*
G01Y836401D01*
G02X1448398Y836257I-200J0D01*
G01X1448296Y836158D01*
X1448191Y836057D01*
G02X1448052Y836001I-139J144D01*
G01X1448044D01*
G03X1448000Y836002I-56J-1501D01*
G01X1447999D01*
G03Y832998I1J-1502D01*
G01X1448001D01*
G03X1448043Y832999I-15J1502D01*
G01X1448050D01*
G02X1448191Y832943I2J-200D01*
G01X1448395Y832746D01*
G02X1448426Y832707I-140J-143D01*
G01X1448429Y832702D01*
G02X1448459Y832597I-170J-105D01*
G01Y820080D01*
G02X1448353Y819903I-200J0D01*
G01X1448067Y819752D01*
G02X1447973Y819729I-93J177D01*
G01X1447930D01*
G02X1447874Y819737I0J200D01*
G01X1447836Y819748D01*
X1447808Y819767D01*
G03X1447001Y820002I-807J-1267D01*
G01X1446998D01*
G03X1446835Y819994I-8J-1502D01*
G01X1446763Y819983D01*
G03X1445498Y818500I237J-1483D01*
G03X1446824Y817008I1502J0D01*
G01X1446879Y817002D01*
G03X1446912Y817000I107J1499D01*
G01X1446920D01*
G03X1446999Y816997I97J1500D01*
G01X1447001D01*
G03X1447837Y817252I-2J1503D01*
G01X1447883Y817283D01*
X1447993Y817289D01*
X1448338Y817105D01*
G02X1448448Y816983I-81J-183D01*
G01X1448459Y816951D01*
Y812080D01*
G02X1448353Y811903I-200J0D01*
G01X1448067Y811752D01*
G02X1447973Y811729I-93J177D01*
G01X1447930D01*
G02X1447874Y811737I0J200D01*
G01X1447836Y811748D01*
X1447808Y811767D01*
G37*
G36*
G01X1508917Y54588D02*
X1537184D01*
X1537398Y54374D01*
Y52805D01*
X1537184Y52591D01*
X1508917D01*
G03X1502980Y46654I0J-5937D01*
G01Y7874D01*
G02X1497106Y2000I-5874J0D01*
G01X1449862D01*
G02X1443988Y7874I0J5874D01*
G01Y46654D01*
G03X1442424Y50670I-5938J0D01*
G01Y50786D01*
X1442657Y51019D01*
X1444546D01*
X1444895Y50670D01*
G02X1445986Y46656I-6843J-4015D01*
G01Y7874D01*
G03X1449862Y3998I3876J0D01*
G01X1497106D01*
G03X1500982Y7874I0J3876D01*
G01Y46654D01*
G02X1508917Y54588I7935J-1D01*
G37*
G36*
G01X1444195Y1313026D02*
X1445730Y1314561D01*
G02X1445948Y1314605I142J-141D01*
G01X1446005Y1314581D01*
X1446072Y1314482D01*
Y1308775D01*
G02X1446013Y1308634I-200J1D01*
G01X1444711Y1307332D01*
G02X1444570Y1307274I-141J142D01*
G01X1438925D01*
G02X1438740Y1307397I0J200D01*
G01X1438717Y1307454D01*
X1438740Y1307571D01*
X1440040Y1308871D01*
X1440118Y1308901D01*
X1440161Y1308898D01*
G03X1440260Y1308896I86J1800D01*
G01X1443660D01*
G03X1445462Y1310698I0J1802D01*
G03X1444329Y1312372I-1803J0D01*
G01X1444282Y1312390D01*
X1444218Y1312467D01*
X1444140Y1312844D01*
G02X1444195Y1313026I196J40D01*
G37*
G36*
G01X1454570Y275932D02*
X1476505D01*
X1476579Y275902D01*
X1476607Y275873D01*
X1477218Y275262D01*
G02X1477277Y275120I-141J-142D01*
G01Y205020D01*
X1477247Y204946D01*
X1477218Y204918D01*
X1475697Y203397D01*
G02X1475555Y203338I-142J141D01*
G01X1454688D01*
X1454614Y203368D01*
X1454586Y203397D01*
X1454428Y203555D01*
G02X1454370Y203696I142J141D01*
G01Y204858D01*
G02X1454430Y205001I200J0D01*
G01X1454664Y205230D01*
X1454738Y205259D01*
X1454778Y205258D01*
X1454812D01*
G03Y208262I0J1502D01*
G01X1454778D01*
X1454738Y208261D01*
X1454664Y208290D01*
X1454430Y208519D01*
G02X1454370Y208661I140J143D01*
G01Y255107D01*
G02X1454488Y255289I200J0D01*
G01X1454812Y255436D01*
G02X1454983Y255432I81J-183D01*
G01X1455033Y255407D01*
X1455052Y255392D01*
G03X1456026Y255033I975J1143D01*
G03Y258037I0J1502D01*
G03X1455052Y257678I1J-1502D01*
G01X1455033Y257663D01*
X1454983Y257638D01*
G02X1454812Y257634I-90J179D01*
G01X1454488Y257781D01*
G02X1454370Y257963I82J182D01*
G01Y275732D01*
G02X1454570Y275932I200J0D01*
G37*
G36*
G01X1468803Y993479D02*
X1466593Y995688D01*
G02X1466578Y995704I138J145D01*
G01X1466542Y995750D01*
X1466529Y995864D01*
X1466719Y996256D01*
G02X1466910Y996369I180J-87D01*
G01X1466922Y996368D01*
X1466927Y996367D01*
G03X1467094Y996358I164J1493D01*
G01X1467096D01*
G03X1465594Y997860I0J1502D01*
G01Y997858D01*
G03X1465603Y997691I1502J-3D01*
G01X1465604Y997686D01*
X1465605Y997674D01*
G02X1465492Y997483I-200J-11D01*
G01X1465153Y997318D01*
G02X1464924Y997357I-87J180D01*
G01X1463782Y998499D01*
G02X1463723Y998641I141J142D01*
G01Y1005801D01*
G02X1463728Y1005846I200J1D01*
G01X1463743Y1005911D01*
X1463752Y1005930D01*
G03X1463817Y1006096I-1364J630D01*
G01X1463826Y1006124D01*
X1463876Y1006196D01*
G02X1464008Y1006281I166J-112D01*
G01X1464048Y1006287D01*
X1464125Y1006269D01*
X1464174Y1006232D01*
G02X1464217Y1006189I-118J-161D01*
G01X1464235Y1006165D01*
X1464245Y1006137D01*
G03X1465658Y1005146I1413J512D01*
G03Y1008150I0J1502D01*
G03X1464221Y1007085I0J-1502D01*
G01Y1007083D01*
G02X1464152Y1006984I-191J60D01*
G01X1464130Y1006967D01*
G02X1463890Y1006964I-122J158D01*
G01X1463889D01*
X1463847Y1006994D01*
X1463811Y1007041D01*
X1463801Y1007070D01*
G03X1463752Y1007191I-1416J-503D01*
G01X1463743Y1007210D01*
X1463728Y1007274D01*
G02X1463723Y1007319I195J44D01*
G01Y1016861D01*
G02X1463817Y1017031I200J0D01*
G03X1464527Y1018307I-792J1276D01*
G03X1464503Y1018573I-1502J-1D01*
G02X1464558Y1018750I197J36D01*
G01X1468267Y1022459D01*
G03X1468326Y1022601I-141J142D01*
G01Y1028929D01*
G02X1468378Y1029063I200J-1D01*
G01X1468456Y1029149D01*
G02X1468577Y1029213I148J-134D01*
G03X1469873Y1030701I-206J1488D01*
G03X1469096Y1032017I-1503J0D01*
G01X1469094D01*
Y1032018D01*
G02X1469028Y1032077I97J175D01*
G01X1469027Y1032078D01*
G02X1468993Y1032164I164J115D01*
G01X1468948Y1032481D01*
G02X1469001Y1032647I198J28D01*
G01X1469003Y1032649D01*
X1469307Y1032953D01*
G02X1469309Y1032955I142J-140D01*
G02X1469449Y1033012I140J-143D01*
G01X1477154D01*
G02X1477294Y1032955I0J-200D01*
G01X1477295Y1032954D01*
X1477871Y1032378D01*
G02X1477873Y1032376I-140J-142D01*
G02X1477930Y1032236I-143J-140D01*
G01Y1022920D01*
G02X1477871Y1022778I-200J0D01*
G01X1471638Y1016545D01*
Y1016532D01*
X1471614Y1016501D01*
G02X1471596Y1016480I-160J119D01*
G01X1471556Y1016440D01*
Y1016274D01*
X1471596Y1016234D01*
G02X1471614Y1016213I-142J-140D01*
G01X1471638Y1016182D01*
Y1002759D01*
G03X1471697Y1002617I200J0D01*
G01X1471794Y1002521D01*
Y1002518D01*
X1474489Y999823D01*
G02X1474545Y999652I-142J-141D01*
G01X1474490Y999286D01*
X1474435Y999209D01*
X1474393Y999187D01*
G03X1473594Y997860I702J-1327D01*
G03X1476598I1502J0D01*
G01Y997862D01*
G03X1476378Y998644I-1504J-1D01*
G01X1476350Y998689D01*
X1476348Y998798D01*
X1476545Y999149D01*
G02X1476719Y999251I174J-98D01*
G01X1477451D01*
G03X1477593Y999310I0J200D01*
G01X1480440Y1002157D01*
G02X1480629Y1002210I142J-141D01*
G01X1481013Y1002116D01*
X1481088Y1002046D01*
X1481104Y1001996D01*
G03X1482535Y1000951I1431J457D01*
G03X1484037Y1002453I0J1502D01*
G03X1482804Y1003931I-1502J0D01*
G01X1482803D01*
G02X1482648Y1004069I36J197D01*
G01X1482543Y1004407D01*
G02X1482592Y1004607I191J59D01*
G01X1483712Y1005727D01*
G02X1483714Y1005729I142J-140D01*
G02X1483854Y1005786I140J-143D01*
G01X1488421D01*
G02X1488582Y1005704I0J-200D01*
G01X1488772Y1005445D01*
G02X1488802Y1005268I-161J-118D01*
G01Y1005267D01*
X1488794Y1005239D01*
G03X1488733Y1004816I1441J-424D01*
G03X1491737I1502J0D01*
G03X1491676Y1005239I-1502J-1D01*
G01X1491668Y1005267D01*
Y1005268D01*
G02X1491698Y1005445I191J59D01*
G01X1491888Y1005704D01*
G02X1492049Y1005786I161J-118D01*
G01X1516558D01*
G03X1516700Y1005845I0J200D01*
G01X1528117Y1017262D01*
G03X1528176Y1017404I-141J142D01*
G01Y1024464D01*
X1528192Y1024502D01*
G03Y1025678I-1381J588D01*
G01X1528176Y1025716D01*
Y1071970D01*
G02X1528280Y1072145I200J0D01*
G01X1528577Y1072309D01*
G02X1528730Y1072325I96J-176D01*
G01X1528789Y1072308D01*
X1528811Y1072295D01*
G03X1529429Y1072124I618J1031D01*
G03Y1074528I0J1202D01*
G03X1528811Y1074357I0J-1202D01*
G01X1528789Y1074344D01*
X1528730Y1074327D01*
G02X1528577Y1074343I-57J192D01*
G01X1528280Y1074507D01*
G02X1528176Y1074682I96J175D01*
G01Y1075710D01*
G02X1528280Y1075885I200J0D01*
G01X1528577Y1076049D01*
G02X1528730Y1076065I96J-176D01*
G01X1528789Y1076048D01*
X1528811Y1076035D01*
G03X1529429Y1075864I618J1031D01*
G03Y1078268I0J1202D01*
G03X1528811Y1078097I0J-1202D01*
G01X1528789Y1078084D01*
X1528730Y1078067D01*
G02X1528577Y1078083I-57J192D01*
G01X1528280Y1078247D01*
G02X1528176Y1078422I96J175D01*
G01Y1079451D01*
G02X1528280Y1079626I200J0D01*
G01X1528577Y1079790D01*
G02X1528730Y1079806I96J-176D01*
G01X1528789Y1079789D01*
X1528811Y1079776D01*
G03X1529429Y1079605I618J1031D01*
G03Y1082009I0J1202D01*
G03X1528811Y1081838I0J-1202D01*
G01X1528789Y1081825D01*
X1528730Y1081808D01*
G02X1528577Y1081824I-57J192D01*
G01X1528280Y1081988D01*
G02X1528176Y1082163I96J175D01*
G01Y1083191D01*
G02X1528280Y1083366I200J0D01*
G01X1528577Y1083530D01*
G02X1528730Y1083546I96J-176D01*
G01X1528789Y1083529D01*
X1528811Y1083516D01*
G03X1529429Y1083345I618J1031D01*
G03Y1085749I0J1202D01*
G03X1528811Y1085578I0J-1202D01*
G01X1528789Y1085565D01*
X1528730Y1085548D01*
G02X1528577Y1085564I-57J192D01*
G01X1528280Y1085728D01*
G02X1528176Y1085903I96J175D01*
G01Y1086931D01*
G02X1528280Y1087106I200J0D01*
G01X1528577Y1087270D01*
G02X1528730Y1087286I96J-176D01*
G01X1528789Y1087269D01*
X1528811Y1087256D01*
G03X1529429Y1087085I618J1031D01*
G03Y1089489I0J1202D01*
G03X1528811Y1089318I0J-1202D01*
G01X1528789Y1089305D01*
X1528730Y1089288D01*
G02X1528577Y1089304I-57J192D01*
G01X1528280Y1089468D01*
G02X1528176Y1089643I96J175D01*
G01Y1090671D01*
G02X1528280Y1090846I200J0D01*
G01X1528577Y1091010D01*
G02X1528730Y1091026I96J-176D01*
G01X1528789Y1091009D01*
X1528811Y1090996D01*
G03X1529429Y1090825I618J1031D01*
G03Y1093229I0J1202D01*
G03X1528811Y1093058I0J-1202D01*
G01X1528789Y1093045D01*
X1528730Y1093028D01*
G02X1528577Y1093044I-57J192D01*
G01X1528280Y1093208D01*
G02X1528176Y1093383I96J175D01*
G01Y1094411D01*
G02X1528280Y1094586I200J0D01*
G01X1528577Y1094750D01*
G02X1528730Y1094766I96J-176D01*
G01X1528789Y1094749D01*
X1528811Y1094736D01*
G03X1529429Y1094565I618J1031D01*
G03Y1096969I0J1202D01*
G03X1528811Y1096798I0J-1202D01*
G01X1528789Y1096785D01*
X1528730Y1096768D01*
G02X1528577Y1096784I-57J192D01*
G01X1528280Y1096948D01*
G02X1528176Y1097123I96J175D01*
G01Y1098151D01*
G02X1528280Y1098326I200J0D01*
G01X1528577Y1098490D01*
G02X1528730Y1098506I96J-176D01*
G01X1528789Y1098489D01*
X1528811Y1098476D01*
G03X1529429Y1098305I618J1031D01*
G03Y1100709I0J1202D01*
G03X1528811Y1100538I0J-1202D01*
G01X1528789Y1100525D01*
X1528730Y1100508D01*
G02X1528577Y1100524I-57J192D01*
G01X1528280Y1100688D01*
G02X1528176Y1100863I96J175D01*
G01Y1101891D01*
G02X1528280Y1102066I200J0D01*
G01X1528577Y1102230D01*
G02X1528730Y1102246I96J-176D01*
G01X1528789Y1102229D01*
X1528811Y1102216D01*
G03X1529429Y1102045I618J1031D01*
G03Y1104449I0J1202D01*
G01X1529428D01*
G03X1528635Y1104150I1J-1203D01*
G01X1528609Y1104127D01*
X1528528Y1104095D01*
G02X1528384Y1104094I-73J186D01*
G01X1528305Y1104124D01*
G02X1528176Y1104311I71J187D01*
G01Y1104341D01*
G03X1528117Y1104483I-200J0D01*
G01X1526690Y1105910D01*
G02X1526677Y1105925I144J138D01*
G01X1526676D01*
G02X1526632Y1106041I156J125D01*
G01X1526626Y1106157D01*
G02Y1106177I200J10D01*
G02X1526664Y1106285I200J-10D01*
G03X1526891Y1106988I-975J703D01*
G03X1525689Y1108190I-1202J0D01*
G03X1524986Y1107963I0J-1202D01*
G02X1524893Y1107926I-118J162D01*
G02X1524858Y1107925I-23J199D01*
G01X1524742Y1107931D01*
G02X1524611Y1107989I10J200D01*
G01X1522950Y1109650D01*
G02X1522937Y1109665I144J138D01*
G01X1522936D01*
G02X1522892Y1109781I156J125D01*
G01X1522886Y1109897D01*
G02Y1109917I200J10D01*
G02X1522924Y1110025I200J-10D01*
G03X1523151Y1110728I-975J703D01*
G03X1521949Y1111930I-1202J0D01*
G03X1521246Y1111703I0J-1202D01*
G02X1521119Y1111666I-116J163D01*
G01X1521001Y1111672D01*
G02X1520870Y1111730I10J200D01*
G01X1519210Y1113390D01*
G02X1519152Y1113521I142J141D01*
G01X1519146Y1113638D01*
G02X1519183Y1113765I200J11D01*
G03X1519410Y1114468I-975J703D01*
G03X1518208Y1115670I-1202J0D01*
G03X1517505Y1115443I0J-1202D01*
G01X1517477Y1115423D01*
X1517412Y1115404D01*
X1517261Y1115412D01*
G02X1517130Y1115470I10J200D01*
G01X1515470Y1117130D01*
G02X1515412Y1117261I142J141D01*
G01X1515404Y1117412D01*
X1515423Y1117477D01*
X1515443Y1117505D01*
G03X1515670Y1118208I-975J703D01*
G03X1514468Y1119410I-1202J0D01*
G03X1513765Y1119183I0J-1202D01*
G01X1513737Y1119163D01*
X1513672Y1119144D01*
X1513521Y1119152D01*
G02X1513390Y1119210I10J200D01*
G01X1512859Y1119741D01*
G02X1512800Y1119883I141J142D01*
G01Y1169589D01*
G02X1512855Y1169726I200J-1D01*
G03X1512876Y1169749I-893J837D01*
G02X1512944Y1169798I148J-134D01*
G01X1512962Y1169806D01*
G02X1513048Y1169823I81J-183D01*
G01X1513268Y1169817D01*
G02X1513350Y1169798I-3J-200D01*
G01X1513459Y1169745D01*
X1513485Y1169714D01*
G03X1514467Y1169268I982J858D01*
G01X1518207D01*
G03Y1171872I0J1302D01*
G01X1514445D01*
X1514443D01*
X1514383Y1171871D01*
X1514282Y1171937D01*
X1514113Y1172336D01*
G02X1514155Y1172555I184J78D01*
G01X1514718Y1173118D01*
X1514761Y1173143D01*
X1514787Y1173150D01*
G03X1515627Y1173990I-319J1159D01*
G01X1515634Y1174016D01*
X1515659Y1174059D01*
X1518333Y1176733D01*
X1518389Y1176761D01*
X1518419Y1176766D01*
G03X1519492Y1177838I-212J1285D01*
G01Y1177840D01*
G02X1519548Y1177948I197J-34D01*
G01X1522871Y1181271D01*
G02X1522873Y1181273I142J-140D01*
G02X1523013Y1181330I140J-143D01*
G01X1523108D01*
G02X1523308Y1181138I0J-200D01*
G02X1523209Y1180957I-200J-8D01*
G03X1522617Y1179921I610J-1036D01*
G03X1522635Y1179716I1202J2D01*
G01X1522638Y1179699D01*
Y1179698D01*
X1522647Y1179649D01*
X1522618Y1179556D01*
X1522352Y1179290D01*
G02X1522210Y1179232I-141J142D01*
G01X1522171D01*
X1522154Y1179235D01*
G03X1521948Y1179253I-207J-1184D01*
G03X1523150Y1178051I0J-1202D01*
G03X1523132Y1178256I-1202J-2D01*
G01X1523129Y1178273D01*
Y1178274D01*
X1523120Y1178323D01*
X1523149Y1178416D01*
X1523415Y1178682D01*
G02X1523557Y1178740I141J-142D01*
G01X1523596D01*
X1523613Y1178737D01*
G03X1523819Y1178719I207J1184D01*
G03X1525021Y1179921I0J1202D01*
G03X1524753Y1180678I-1203J0D01*
G01X1524752Y1180679D01*
G02X1524727Y1180891I156J126D01*
G01X1524883Y1181216D01*
G02X1525063Y1181330I180J-86D01*
G01X1525124D01*
G03X1527828Y1182450I-1J3826D01*
G01X1527839Y1182461D01*
G03X1528759Y1183381I-280J1200D01*
G01X1528788Y1183410D01*
G03X1529207Y1183907I-2706J2706D01*
G01X1529221Y1183927D01*
X1529294Y1183990D01*
X1529314Y1184001D01*
G03X1529475Y1184089I-1754J3401D01*
G01X1529497Y1184102D01*
X1529554Y1184117D01*
G02X1529710Y1184095I52J-193D01*
G01X1530003Y1183917D01*
G02X1530099Y1183734I-104J-171D01*
G01Y1183728D01*
G03X1530097Y1183661I1200J-69D01*
G03X1531299Y1184863I1202J0D01*
G03X1531237Y1184861I8J-1202D01*
G01X1531214D01*
G02X1531044Y1184957I1J200D01*
G01X1530865Y1185250D01*
G02X1530843Y1185406I171J104D01*
G01X1530858Y1185463D01*
X1530871Y1185485D01*
G03X1531146Y1186069I-3312J1916D01*
G02X1531328Y1186200I188J-69D01*
G03X1532501Y1187400I-29J1201D01*
G01Y1187402D01*
G03X1532500Y1187434I-1202J-22D01*
G01Y1191108D01*
G03X1532501Y1191138I-1201J55D01*
G03Y1191144I-200J3D01*
G03X1532500Y1191174I-1202J-25D01*
G01Y1194848D01*
G03X1532501Y1194878I-1201J55D01*
G03Y1194884I-200J3D01*
G03X1532500Y1194914I-1202J-25D01*
G01Y1198588D01*
G03X1532501Y1198618I-1201J55D01*
G03Y1198624I-200J3D01*
G03X1532500Y1198654I-1202J-25D01*
G01Y1202329D01*
G03X1532501Y1202359I-1201J55D01*
G03Y1202365I-200J3D01*
G03X1532500Y1202395I-1202J-25D01*
G01Y1206069D01*
G03X1532501Y1206099I-1201J55D01*
G03Y1206105I-200J3D01*
G03X1532500Y1206135I-1202J-25D01*
G01Y1209809D01*
G03X1532501Y1209839I-1201J55D01*
G03Y1209845I-200J3D01*
G03X1532500Y1209875I-1202J-25D01*
G01Y1213549D01*
G03X1532501Y1213579I-1201J55D01*
G03Y1213585I-200J3D01*
G03X1532500Y1213615I-1202J-25D01*
G01Y1217289D01*
G03X1532501Y1217319I-1201J55D01*
G03Y1217325I-200J3D01*
G03X1532500Y1217355I-1202J-25D01*
G01Y1221029D01*
G03X1532501Y1221059I-1201J55D01*
G03Y1221065I-200J3D01*
G03X1532500Y1221095I-1202J-25D01*
G01Y1224770D01*
G03X1532501Y1224800I-1201J55D01*
G03Y1224806I-200J3D01*
G03X1532500Y1224836I-1202J-25D01*
G01Y1225217D01*
G02X1532557Y1225357I200J0D01*
G01X1532558Y1225358D01*
X1534041Y1226841D01*
G02X1534043Y1226843I142J-140D01*
G02X1534183Y1226900I140J-143D01*
G01X1668917D01*
G02X1669057Y1226843I0J-200D01*
G01X1669058Y1226842D01*
X1669276Y1226624D01*
G02X1669331Y1226447I-142J-141D01*
G01X1669262Y1226074D01*
X1669202Y1225997D01*
X1669157Y1225977D01*
G03X1668398Y1224803I528J-1174D01*
G03X1669685Y1223516I1287J0D01*
G03X1670859Y1224275I0J1287D01*
G01X1670879Y1224320D01*
X1670956Y1224380D01*
X1671329Y1224449D01*
G02X1671506Y1224394I36J-197D01*
G01X1673081Y1222819D01*
G02X1673135Y1222639I-142J-141D01*
G01X1673071Y1222313D01*
G02X1672955Y1222168I-196J38D01*
G01X1672954D01*
G03X1672223Y1221062I471J-1106D01*
G03X1673268Y1219870I1202J0D01*
G02X1673442Y1219672I-26J-198D01*
G01Y1218960D01*
G02X1673496Y1218854I-143J-140D01*
G01Y1218852D01*
G02X1673499Y1218820I-197J-35D01*
G01Y1218804D01*
X1673389Y1218685D01*
G02X1673335Y1218644I-146J136D01*
G01X1673248Y1218598D01*
X1673216Y1218592D01*
G03Y1216052I210J-1270D01*
G01X1673248Y1216046D01*
X1673335Y1216000D01*
G02X1673390Y1215958I-92J-178D01*
G01X1673446Y1215896D01*
G02X1673499Y1215761I-147J-136D01*
G01Y1215055D01*
G02X1673446Y1214920I-200J1D01*
G01X1673342Y1214807D01*
X1673282Y1214776D01*
X1673248Y1214771D01*
G03Y1212393I177J-1189D01*
G01X1673282Y1212388D01*
X1673342Y1212357D01*
X1673446Y1212244D01*
G02X1673499Y1212109I-147J-136D01*
G01Y1211403D01*
G02X1673446Y1211268I-200J1D01*
G01X1673390Y1211206D01*
G02X1673335Y1211164I-147J136D01*
G01X1673248Y1211118D01*
X1673216Y1211112D01*
G03Y1208572I210J-1270D01*
G01X1673248Y1208566D01*
X1673335Y1208520D01*
G02X1673390Y1208478I-92J-178D01*
G01X1673446Y1208416D01*
G02X1673499Y1208281I-147J-136D01*
G01Y1207575D01*
G02X1673446Y1207440I-200J1D01*
G01X1673342Y1207327D01*
X1673282Y1207296D01*
X1673248Y1207291D01*
G03Y1204913I177J-1189D01*
G01X1673282Y1204908D01*
X1673342Y1204877D01*
X1673446Y1204764D01*
G02X1673499Y1204629I-147J-136D01*
G01Y1203923D01*
G02X1673446Y1203788I-200J1D01*
G01X1673390Y1203726D01*
G02X1673335Y1203684I-147J136D01*
G01X1673248Y1203638D01*
X1673216Y1203632D01*
G03Y1201092I210J-1270D01*
G01X1673248Y1201086D01*
X1673335Y1201040D01*
G02X1673390Y1200998I-92J-178D01*
G01X1673446Y1200936D01*
G02X1673499Y1200801I-147J-136D01*
G01Y1200094D01*
G02X1673446Y1199959I-200J1D01*
G01X1673342Y1199846D01*
X1673282Y1199815D01*
X1673248Y1199810D01*
G03Y1197432I177J-1189D01*
G01X1673282Y1197427D01*
X1673342Y1197396D01*
X1673446Y1197283D01*
G02X1673499Y1197148I-147J-136D01*
G01Y1143137D01*
G02X1673477Y1143046I-200J0D01*
G02X1673441Y1142996I-178J90D01*
G01X1672322Y1141877D01*
X1672309Y1141868D01*
X1672288Y1141849D01*
G02X1672118Y1141825I-110J167D01*
G01X1672078Y1141843D01*
X1672043Y1141857D01*
G03X1671557Y1141951I-486J-1208D01*
G01X1671555D01*
G03X1670253Y1140649I0J-1302D01*
G01Y1140647D01*
G03X1670358Y1140135I1302J0D01*
G01X1670362Y1140126D01*
X1670374Y1140089D01*
X1670382Y1140047D01*
G02X1670346Y1139905I-198J-25D01*
G02X1670325Y1139880I-163J116D01*
G01X1668582Y1138137D01*
X1668569Y1138128D01*
X1668548Y1138109D01*
G02X1668378Y1138085I-110J167D01*
G01X1668338Y1138103D01*
X1668303Y1138117D01*
G03X1667817Y1138211I-486J-1208D01*
G01X1667815D01*
G03X1666542Y1137184I0J-1302D01*
G01X1666540Y1137174D01*
X1666539Y1137171D01*
Y1137167D01*
X1666534Y1137144D01*
X1666520Y1137119D01*
G02X1666483Y1137071I-175J97D01*
G01X1666472Y1137061D01*
X1666391Y1136984D01*
G02X1666336Y1136954I-122J158D01*
G01X1666285Y1136939D01*
X1666284D01*
X1666279Y1136938D01*
X1666268Y1136937D01*
G03X1666174Y1136924I473J-3767D01*
G03X1666055Y1136904I570J-3753D01*
G03X1665970Y1136887I702J-3731D01*
G02X1665917Y1136888I-23J199D01*
G03X1665866Y1136898I-756J-3721D01*
G01X1665863D01*
G03X1665795Y1136911I-747J-3722D01*
G01X1665793D01*
X1665777Y1136914D01*
G03X1665602Y1136939I-624J-3745D01*
G01X1665599D01*
X1665580Y1136943D01*
X1665560Y1136947D01*
X1665540Y1136956D01*
G02X1665500Y1136980I82J183D01*
G01X1665469Y1137010D01*
G03X1665467Y1137012I-142J-140D01*
G01X1665407Y1137069D01*
X1665402Y1137075D01*
G03X1665392Y1137086I-153J-129D01*
G02X1665369Y1137118I150J132D01*
G01X1665357Y1137141D01*
X1665352Y1137162D01*
G03X1664074Y1138211I-1278J-254D01*
G03X1663860Y1138194I-4J-1302D01*
G01X1663813Y1138186D01*
X1663723Y1138214D01*
X1663458Y1138467D01*
G02X1663396Y1138623I138J145D01*
G01X1663397Y1138636D01*
X1663398Y1138642D01*
G03X1663406Y1138778I-1194J138D01*
G01Y1138780D01*
G03X1663388Y1138984I-1202J-3D01*
G01X1663385Y1139001D01*
Y1139002D01*
X1663376Y1139051D01*
X1663405Y1139144D01*
X1663671Y1139410D01*
G02X1663813Y1139468I141J-142D01*
G01X1663852D01*
X1663869Y1139465D01*
G03X1664075Y1139447I207J1184D01*
G03X1662873Y1140649I0J1202D01*
G03X1662891Y1140444I1202J2D01*
G01X1662894Y1140427D01*
Y1140426D01*
X1662903Y1140377D01*
X1662874Y1140284D01*
X1662608Y1140018D01*
G02X1662466Y1139960I-141J142D01*
G01X1662427D01*
X1662410Y1139963D01*
G03X1662204Y1139981I-207J-1184D01*
G03X1661984Y1139960I4J-1202D01*
G01X1661935Y1139951D01*
X1661840Y1139980D01*
X1661570Y1140250D01*
G02X1661515Y1140427I142J141D01*
G01Y1140428D01*
X1661518Y1140445D01*
G03X1661536Y1140649I-1184J207D01*
G03X1660334Y1139447I-1202J0D01*
G03X1660554Y1139468I-4J1202D01*
G01X1660603Y1139477D01*
X1660698Y1139448D01*
X1660968Y1139178D01*
G02X1661023Y1139001I-142J-141D01*
G01Y1139000D01*
X1661020Y1138983D01*
G03X1661002Y1138780I1184J-207D01*
G01Y1138778D01*
G03X1661010Y1138642I1202J2D01*
G01X1661011Y1138636D01*
X1661012Y1138623D01*
G02X1660950Y1138467I-200J-11D01*
G01X1660685Y1138214D01*
X1660595Y1138186D01*
X1660548Y1138194D01*
G03X1660334Y1138211I-210J-1285D01*
G03X1659032Y1136909I0J-1302D01*
G03X1660333Y1135607I1302J0D01*
G01X1660335D01*
G03X1660365Y1135608I-28J1301D01*
G01X1660398D01*
G02X1660535Y1135553I-1J-200D01*
G01X1660562Y1135525D01*
X1660752Y1135218D01*
G02X1660756Y1135015I-170J-105D01*
G01X1660732Y1134971D01*
Y1134969D01*
G03X1660722Y1134951I3314J-1853D01*
G01X1660707Y1134924D01*
G03X1660688Y1134888I3348J-1790D01*
G01X1660667Y1134846D01*
G03X1660577Y1134649I3407J-1676D01*
G01X1660565Y1134620D01*
X1660550Y1134602D01*
G02X1660512Y1134566I-156J126D01*
G03X1660508Y1134564I86J-177D01*
G02X1660506Y1134562I-141J139D01*
G01X1660458Y1134530D01*
X1660425Y1134509D01*
G02X1660405Y1134500I-92J178D01*
G02X1660401Y1134498I-91J177D01*
G01X1660314Y1134471D01*
X1660287Y1134470D01*
G03Y1131868I47J-1301D01*
G01X1660314Y1131867D01*
X1660403Y1131839D01*
G02X1660405Y1131838I-88J-178D01*
G02X1660443Y1131818I-74J-186D01*
G01X1660506Y1131776D01*
G02X1660508Y1131775I-87J-177D01*
G03X1660512Y1131771I142J138D01*
G02X1660527Y1131760I-111J-167D01*
G01X1660535Y1131752D01*
G02X1660550Y1131736I-138J-145D01*
G01X1660551Y1131735D01*
G02X1660576Y1131696I-155J-127D01*
G01X1660579Y1131686D01*
G03X1660608Y1131619I3498J1474D01*
G01X1660614Y1131605D01*
Y1131604D01*
G03X1660637Y1131556I3435J1617D01*
G01Y1131554D01*
G03X1660645Y1131539I3353J1779D01*
G01Y1131537D01*
G03X1660647Y1131534I166J109D01*
G01X1660649Y1131531D01*
Y1131529D01*
G03X1660650Y1131527I180J89D01*
G02X1660652Y1131524I-164J-111D01*
G03X1660718Y1131393I3423J1642D01*
G02X1660720Y1131389I-178J-91D01*
G03X1660724Y1131381I3395J1693D01*
G01X1660727Y1131376D01*
X1660744Y1131341D01*
X1660749Y1131323D01*
G02X1660756Y1131271I-193J-52D01*
G01Y1131184D01*
Y1131180D01*
G02X1660728Y1131082I-200J4D01*
G01X1660647Y1130953D01*
Y1130951D01*
X1660567Y1130823D01*
G02X1660405Y1130730I-169J107D01*
G01X1660365D01*
G03X1660335Y1130731I-58J-1300D01*
G01X1660333D01*
G03Y1128127I1J-1302D01*
G01X1660335D01*
G03X1660381Y1128128I-5J1302D01*
G01X1660403D01*
G02X1660566Y1128037I-5J-200D01*
G01X1660727Y1127777D01*
X1660740Y1127751D01*
G02X1660757Y1127672I-183J-81D01*
G01Y1127595D01*
G02X1660756Y1127576I-200J1D01*
G01X1660754Y1127558D01*
G02X1660731Y1127489I-198J28D01*
G03X1660613Y1127250I3344J-1799D01*
G01Y1127249D01*
G03X1660578Y1127168I3467J-1546D01*
G01X1660570Y1127151D01*
X1660568Y1127146D01*
X1660564Y1127138D01*
X1660548Y1127119D01*
G02X1660509Y1127083I-154J128D01*
G01X1660445Y1127040D01*
X1660420Y1127023D01*
X1660314Y1126990D01*
X1660287Y1126989D01*
G03Y1124387I47J-1301D01*
G01X1660314Y1124386D01*
X1660403Y1124358D01*
G02X1660405Y1124357I-88J-178D01*
G02X1660443Y1124337I-74J-186D01*
G01X1660506Y1124295D01*
G02X1660508Y1124294I-87J-177D01*
G03X1660512Y1124290I142J138D01*
G02X1660527Y1124279I-111J-167D01*
G01X1660535Y1124271D01*
G02X1660550Y1124255I-138J-145D01*
G01X1660551Y1124254D01*
G02X1660576Y1124215I-155J-127D01*
G01X1660579Y1124205D01*
G03X1660608Y1124138I3498J1474D01*
G01X1660614Y1124124D01*
Y1124123D01*
G03X1660637Y1124075I3435J1617D01*
G01Y1124073D01*
G03X1660645Y1124058I3353J1779D01*
G01Y1124056D01*
G03X1660647Y1124053I166J109D01*
G01X1660649Y1124050D01*
Y1124048D01*
G03X1660650Y1124046I180J89D01*
G02X1660652Y1124043I-164J-111D01*
G03X1660718Y1123912I3423J1642D01*
G02X1660720Y1123908I-178J-91D01*
G03X1660724Y1123900I3395J1693D01*
G01X1660727Y1123895D01*
X1660744Y1123860D01*
X1660749Y1123842D01*
G02X1660756Y1123790I-193J-52D01*
G01Y1123703D01*
Y1123699D01*
G02X1660728Y1123601I-200J4D01*
G01X1660647Y1123472D01*
Y1123470D01*
X1660567Y1123342D01*
G02X1660405Y1123249I-169J107D01*
G01X1660365D01*
G03X1660335Y1123250I-58J-1300D01*
G01X1660333D01*
G03Y1120646I1J-1302D01*
G01X1660335D01*
G03X1660365Y1120647I-28J1301D01*
G01X1660398D01*
G02X1660535Y1120592I-1J-200D01*
G01X1660562Y1120564D01*
X1660752Y1120257D01*
G02X1660756Y1120054I-170J-105D01*
G01X1660732Y1120010D01*
Y1120008D01*
G03X1660722Y1119990I3314J-1853D01*
G01X1660707Y1119963D01*
G03X1660688Y1119927I3348J-1790D01*
G01X1660667Y1119885D01*
G03X1660577Y1119688I3407J-1676D01*
G01X1660565Y1119659D01*
X1660550Y1119641D01*
G02X1660512Y1119605I-156J126D01*
G03X1660508Y1119603I86J-177D01*
G02X1660506Y1119601I-141J139D01*
G01X1660458Y1119569D01*
X1660425Y1119548D01*
G02X1660405Y1119539I-92J178D01*
G02X1660401Y1119537I-91J177D01*
G01X1660314Y1119510D01*
X1660287Y1119509D01*
G03X1660313Y1116906I47J-1301D01*
G01X1660319D01*
G02X1660391Y1116889I-9J-200D01*
G02X1660421Y1116872I-83J-182D01*
G01X1660510Y1116813D01*
Y1116812D01*
G02X1660571Y1116744I-114J-164D01*
G01X1660572Y1116741D01*
X1660578Y1116727D01*
G03X1660793Y1116296I3498J1476D01*
G01Y1116294D01*
G03X1660820Y1116250I3249J1964D01*
G01X1660834Y1116226D01*
G02X1660846Y1116113I-184J-77D01*
G01X1660831Y1116061D01*
X1660816Y1116029D01*
X1660610Y1115823D01*
G02X1660486Y1115765I-142J141D01*
G01X1660467D01*
X1660454Y1115766D01*
G03X1660349Y1115770I-102J-1299D01*
G01X1660333D01*
G03X1659032Y1114468I1J-1302D01*
G03X1659037Y1114347I1302J-7D01*
G02X1658979Y1114192I-199J-14D01*
G01X1656869Y1112082D01*
G02X1656745Y1112024I-142J141D01*
G01X1656726D01*
X1656713Y1112025D01*
G03X1656608Y1112029I-102J-1299D01*
G01X1656592D01*
G03X1655334Y1111056I1J-1301D01*
G01X1655328Y1111033D01*
X1655283Y1110951D01*
X1655282Y1110950D01*
G02X1655135Y1110885I-148J135D01*
G01X1654310D01*
G02X1654275Y1110888I0J200D01*
G02X1654184Y1110930I36J197D01*
G02X1654121Y1111021I127J155D01*
G01X1654117Y1111037D01*
G03X1651589Y1111039I-1264J-309D01*
G01Y1111038D01*
G03X1651586Y1111027I1254J-348D01*
G01X1651584Y1111018D01*
G02X1651406Y1110885I-189J67D01*
G01X1650570D01*
G02X1650535Y1110888I0J200D01*
G02X1650444Y1110930I36J197D01*
G02X1650381Y1111021I127J155D01*
G01X1650377Y1111037D01*
G03X1647849Y1111039I-1264J-309D01*
G01Y1111038D01*
G03X1647846Y1111027I1254J-348D01*
G01X1647844Y1111018D01*
G02X1647666Y1110885I-189J67D01*
G01X1646830D01*
G02X1646795Y1110888I0J200D01*
G02X1646704Y1110930I36J197D01*
G02X1646641Y1111021I127J155D01*
G01X1646637Y1111037D01*
G03X1644109Y1111039I-1264J-309D01*
G01Y1111038D01*
G03X1644106Y1111027I1254J-348D01*
G01X1644104Y1111018D01*
G02X1643926Y1110885I-189J67D01*
G01X1643090D01*
G02X1643055Y1110888I0J200D01*
G02X1642964Y1110930I36J197D01*
G02X1642901Y1111021I127J155D01*
G01X1642897Y1111037D01*
G03X1640369Y1111039I-1264J-309D01*
G01Y1111038D01*
G03X1640366Y1111027I1254J-348D01*
G01X1640364Y1111018D01*
G02X1640186Y1110885I-189J67D01*
G01X1639351D01*
G02X1639316Y1110888I0J200D01*
G02X1639225Y1110930I36J197D01*
G02X1639162Y1111021I127J155D01*
G01X1639158Y1111037D01*
G03X1636628Y1111039I-1265J-309D01*
G01Y1111038D01*
G03X1636625Y1111026I1262J-322D01*
G01X1636623Y1111018D01*
G02X1636445Y1110885I-189J67D01*
G01X1635611D01*
G02X1635576Y1110888I0J200D01*
G02X1635485Y1110930I36J197D01*
G02X1635422Y1111021I127J155D01*
G01X1635418Y1111037D01*
G03X1632888Y1111039I-1265J-309D01*
G01Y1111038D01*
G03X1632885Y1111026I1262J-322D01*
G01X1632883Y1111018D01*
G02X1632705Y1110885I-189J67D01*
G01X1631871D01*
G02X1631836Y1110888I0J200D01*
G02X1631745Y1110930I36J197D01*
G02X1631682Y1111021I127J155D01*
G01X1631678Y1111037D01*
G03X1629148Y1111039I-1265J-309D01*
G01Y1111038D01*
G03X1629145Y1111026I1262J-322D01*
G01X1629143Y1111018D01*
G02X1628965Y1110885I-189J67D01*
G01X1628131D01*
G02X1628096Y1110888I0J200D01*
G02X1628005Y1110930I36J197D01*
G02X1627942Y1111021I127J155D01*
G01X1627938Y1111037D01*
G03X1625408Y1111039I-1265J-309D01*
G01Y1111038D01*
G03X1625405Y1111026I1262J-322D01*
G01X1625403Y1111018D01*
G02X1625225Y1110885I-189J67D01*
G01X1624391D01*
G02X1624356Y1110888I0J200D01*
G02X1624265Y1110930I36J197D01*
G02X1624202Y1111021I127J155D01*
G01X1624198Y1111037D01*
G03X1621668Y1111039I-1265J-309D01*
G01Y1111038D01*
G03X1621665Y1111026I1262J-322D01*
G01X1621663Y1111018D01*
G02X1621485Y1110885I-189J67D01*
G01X1620651D01*
G02X1620616Y1110888I0J200D01*
G02X1620525Y1110930I36J197D01*
G02X1620462Y1111021I127J155D01*
G01X1620458Y1111037D01*
G03X1617928Y1111039I-1265J-309D01*
G01Y1111038D01*
G03X1617925Y1111026I1262J-322D01*
G01X1617923Y1111018D01*
G02X1617745Y1110885I-189J67D01*
G01X1616910D01*
G02X1616875Y1110888I0J200D01*
G02X1616784Y1110930I36J197D01*
G02X1616721Y1111021I127J155D01*
G01X1616717Y1111037D01*
G03X1614187Y1111039I-1265J-309D01*
G01Y1111038D01*
G03X1614184Y1111026I1262J-322D01*
G01X1614182Y1111018D01*
G02X1614004Y1110885I-189J67D01*
G01X1613170D01*
G02X1613135Y1110888I0J200D01*
G02X1613044Y1110930I36J197D01*
G02X1612981Y1111021I127J155D01*
G01X1612977Y1111037D01*
G03X1610447Y1111039I-1265J-309D01*
G01Y1111038D01*
G03X1610444Y1111026I1262J-322D01*
G01X1610442Y1111018D01*
G02X1610264Y1110885I-189J67D01*
G01X1609430D01*
G02X1609395Y1110888I0J200D01*
G02X1609304Y1110930I36J197D01*
G02X1609241Y1111021I127J155D01*
G01X1609237Y1111037D01*
G03X1606707Y1111039I-1265J-309D01*
G01Y1111038D01*
G03X1606704Y1111026I1262J-322D01*
G01X1606702Y1111018D01*
G02X1606524Y1110885I-189J67D01*
G01X1602949D01*
G02X1602927Y1110886I-2J200D01*
G02X1602920Y1110887I25J199D01*
G02X1602807Y1110944I29J198D01*
G01X1601493Y1112259D01*
G03X1601351Y1112318I-142J-141D01*
G01X1588999D01*
G02X1588862Y1112372I0J200D01*
G01X1588691Y1112531D01*
G02X1588647Y1112591I136J146D01*
G01X1588601Y1112687D01*
X1588597Y1112721D01*
G03X1588582Y1112816I-1194J-140D01*
G01Y1112818D01*
G02X1588637Y1112997I196J38D01*
G01X1588868Y1113228D01*
G02X1589010Y1113287I142J-141D01*
G01X1589049D01*
X1589066Y1113284D01*
G03X1589271Y1113266I207J1184D01*
G03X1588069Y1114468I0J1202D01*
G03X1588090Y1114248I1202J4D01*
G01X1588099Y1114199D01*
X1588070Y1114104D01*
X1587804Y1113838D01*
G02X1587662Y1113779I-142J141D01*
G01X1587623D01*
X1587606Y1113782D01*
G03X1587402Y1113800I-207J-1184D01*
G01X1587400D01*
G03X1587181Y1113779I5J-1202D01*
G01X1587132Y1113770D01*
X1587037Y1113799D01*
X1586767Y1114069D01*
G02X1586712Y1114246I142J141D01*
G01Y1114247D01*
X1586715Y1114264D01*
G03X1586733Y1114468I-1184J207D01*
G03X1585531Y1113266I-1202J0D01*
G03X1585751Y1113287I-4J1202D01*
G01X1585800Y1113296D01*
X1585895Y1113267D01*
X1586161Y1113001D01*
G02X1586220Y1112859I-141J-142D01*
G01Y1112818D01*
X1586217Y1112800D01*
G03X1586205Y1112721I1182J-220D01*
G01X1586201Y1112687D01*
X1586155Y1112591D01*
G02X1586111Y1112531I-180J86D01*
G01X1585940Y1112372D01*
G02X1585803Y1112318I-137J146D01*
G01X1540753D01*
G03X1540553Y1112118I0J-200D01*
G01Y1112099D01*
G02X1540395Y1111903I-200J0D01*
G03Y1109553I254J-1175D01*
G02X1540553Y1109358I-42J-195D01*
G01Y1108359D01*
G02X1540395Y1108163I-200J0D01*
G03Y1105813I254J-1175D01*
G02X1540553Y1105618I-42J-195D01*
G01Y1104618D01*
G02X1540395Y1104422I-200J0D01*
G03Y1102072I254J-1175D01*
G02X1540553Y1101877I-42J-195D01*
G01Y1100878D01*
G02X1540395Y1100682I-200J0D01*
G03Y1098332I254J-1175D01*
G02X1540553Y1098137I-42J-195D01*
G01Y1097138D01*
G02X1540395Y1096942I-200J0D01*
G03Y1094592I254J-1175D01*
G02X1540553Y1094397I-42J-195D01*
G01Y1093398D01*
G02X1540395Y1093202I-200J0D01*
G03Y1090852I254J-1175D01*
G02X1540553Y1090657I-42J-195D01*
G01Y1089658D01*
G02X1540395Y1089462I-200J0D01*
G03Y1087112I254J-1175D01*
G02X1540553Y1086917I-42J-195D01*
G01Y1085918D01*
G02X1540395Y1085722I-200J0D01*
G03Y1083372I254J-1175D01*
G02X1540553Y1083177I-42J-195D01*
G01Y1082178D01*
G02X1540395Y1081982I-200J0D01*
G03Y1079632I254J-1175D01*
G02X1540553Y1079437I-42J-195D01*
G01Y1078437D01*
G02X1540395Y1078241I-200J0D01*
G03Y1075891I254J-1175D01*
G02X1540553Y1075696I-42J-195D01*
G01Y1074697D01*
G02X1540395Y1074501I-200J0D01*
G03Y1072151I254J-1175D01*
G02X1540553Y1071956I-42J-195D01*
G01Y1070322D01*
G02X1540494Y1070180I-200J0D01*
G01X1536850Y1066536D01*
G03X1536791Y1066394I141J-142D01*
G01Y1017254D01*
G02X1536732Y1017112I-200J0D01*
G01X1534078Y1014458D01*
G03X1534019Y1014316I141J-142D01*
G01Y996661D01*
G02X1533960Y996519I-200J0D01*
G01X1530919Y993479D01*
G02X1530777Y993420I-142J141D01*
G01X1468945D01*
G02X1468803Y993479I0J200D01*
G37*
G36*
G01X1480164Y242420D02*
X1490097D01*
G03X1490231Y242427I4J1210D01*
G02X1490249Y242428I20J-199D01*
G01X1493395D01*
G02X1493412Y242427I-3J-200D01*
G03X1493559Y242418I147J1201D01*
G01X1498032D01*
G02X1498054Y242416I-6J-191D01*
G01X1498121Y242403D01*
G02X1498153Y242382I-93J-177D01*
G01X1498373Y242171D01*
G02X1498409Y242116I-147J-136D01*
G01X1498424Y242083D01*
X1498426Y242042D01*
Y242041D01*
G03X1498476Y241710I1501J57D01*
G03X1498901Y241000I1451J387D01*
G01X1498904Y240997D01*
G03X1499947Y240576I1043J1081D01*
G03X1501449Y242057I0J1502D01*
G01Y242063D01*
X1501450Y242129D01*
X1501460Y242150D01*
X1501643Y242326D01*
X1501701Y242382D01*
G02X1501733Y242403I125J-156D01*
G01X1501800Y242416D01*
G02X1501822Y242418I28J-189D01*
G01X1505682D01*
G03X1505820Y242426I-1J1210D01*
G02X1505837Y242427I20J-199D01*
G01X1509211D01*
G02X1509228Y242426I-3J-200D01*
G03X1509366Y242418I139J1202D01*
G01X1515979D01*
G02X1515991Y242417I-10J-191D01*
G01X1516053Y242405D01*
G02X1516057Y242403I-87J-180D01*
G01X1518603Y239857D01*
G02X1518628Y239761I-175J-97D01*
G01Y153168D01*
G02X1518626Y153148I-200J10D01*
G01X1518614Y153082D01*
G02X1518607Y153062I-192J56D01*
G01X1518599Y153043D01*
X1518553Y152997D01*
X1518548Y152993D01*
G03X1518398Y147579I2447J-2777D01*
G01X1518399Y147578D01*
G03X1518517Y147465I2619J2616D01*
G03X1518546Y147439I2485J2743D01*
G01X1518568Y147418D01*
X1518593Y147360D01*
Y147358D01*
X1518612Y147316D01*
G02X1518627Y147256I-184J-78D01*
G02X1518628Y147237I-199J-20D01*
G01Y125105D01*
X1518617Y125073D01*
G03X1518532Y124576I1417J-498D01*
G03X1518617Y124079I1502J1D01*
G01X1518628Y124047D01*
Y122985D01*
G03X1518643Y122909I200J0D01*
G01X1518663Y122861D01*
G02X1518678Y122785I-185J-76D01*
G01Y117486D01*
G02X1518647Y117378I-200J-1D01*
G03Y115614I1214J-882D01*
G02X1518678Y115506I-169J-107D01*
G01Y110681D01*
Y110679D01*
G03X1518690Y110609I200J-2D01*
G01X1518694Y110599D01*
G02X1518702Y110526I-191J-58D01*
G01X1518696Y110439D01*
G02X1518684Y110383I-200J13D01*
G01X1518655Y110305D01*
G03X1518640Y110284I1215J-884D01*
G01X1518639Y110283D01*
G03X1518360Y109412I1223J-872D01*
G01Y109410D01*
G03X1519862Y107908I1502J0D01*
G03X1520793Y108232I-1J1502D01*
G01X1520794Y108233D01*
G02X1521034Y108237I123J-158D01*
G02X1521058Y108217I-116J-163D01*
G01X1521608Y107667D01*
G03X1521750Y107608I142J141D01*
G01X1522333D01*
X1522350Y107605D01*
G03X1522549Y107588I201J1185D01*
G01X1538476D01*
G02X1538676Y107388I0J-200D01*
G01Y104249D01*
G03X1538707Y103914I1802J-2D01*
G01X1538712Y103885D01*
X1538707Y103831D01*
X1538691Y103792D01*
G02X1538636Y103721I-182J84D01*
G01X1538583Y103684D01*
G02X1538405Y103669I-104J171D01*
G01X1538388Y103678D01*
G03X1537702Y103844I-686J-1335D01*
G01X1537700D01*
G03X1536198Y102342I0J-1502D01*
G03X1536674Y101245I1502J0D01*
G01X1536677Y101242D01*
G03X1537720Y100821I1043J1081D01*
G03X1539220Y102242I0J1502D01*
G01X1539223Y102293D01*
X1539246Y102332D01*
G02X1539290Y102384I172J-101D01*
G02X1539295Y102388I127J-154D01*
G01X1539307Y102397D01*
X1539422Y102469D01*
X1539591Y102575D01*
X1539592D01*
G02X1539682Y102605I106J-169D01*
G01X1539730Y102608D01*
X1539774Y102589D01*
G03X1540476Y102446I704J1660D01*
G01X1540547D01*
X1540579Y102449D01*
G03X1542280Y104247I-101J1799D01*
G01Y107388D01*
G02X1542480Y107588I200J0D01*
G01X1578722D01*
G02X1578759Y107584I-3J-200D01*
G01X1578761D01*
G02X1578862Y107531I-39J-196D01*
G01X1580280Y106113D01*
G02X1580333Y106012I-143J-140D01*
G01Y106010D01*
G02X1580337Y105973I-196J-40D01*
G01Y94811D01*
X1580326Y94779D01*
G03X1580240Y94279I1416J-501D01*
G03X1580326Y93779I1502J1D01*
G01X1580337Y93747D01*
Y87617D01*
G02X1580303Y87506I-200J0D01*
G01X1580288Y87482D01*
X1580243Y87445D01*
X1580240Y87444D01*
G03X1579288Y86046I550J-1398D01*
G03X1580214Y84659I1502J0D01*
G01X1580216Y84658D01*
G02X1580304Y84585I-78J-184D01*
G01X1580320Y84561D01*
X1580328Y84535D01*
G02X1580337Y84476I-191J-59D01*
G01Y62332D01*
X1580336Y62321D01*
G02X1580286Y62205I-199J17D01*
G01X1580230Y62148D01*
X1580082Y61998D01*
G02X1580020Y61956I-141J142D01*
G01X1579985Y61941D01*
X1579942Y61940D01*
X1579941D01*
G03X1579859Y61936I32J-1502D01*
G03X1578865Y61458I109J-1498D01*
G02X1578864Y61456I-172J85D01*
G02X1578795Y61408I-146J137D01*
G01X1578757Y61392D01*
X1578613Y61396D01*
X1578411Y61401D01*
G02X1578329Y61421I5J200D01*
G01X1578291Y61439D01*
X1578263Y61473D01*
G03X1577108Y62015I-1155J-960D01*
G03Y59011I0J-1502D01*
G01X1577110D01*
G03X1578211Y59493I-1J1501D01*
G02X1578212Y59495I172J-85D01*
G02X1578281Y59543I146J-137D01*
G01X1578319Y59559D01*
X1578463Y59555D01*
X1578665Y59550D01*
G02X1578747Y59530I-5J-200D01*
G01X1578785Y59512D01*
X1578813Y59478D01*
G03X1579219Y59135I1157J958D01*
G01X1579221D01*
X1579238Y59124D01*
X1579289Y59046D01*
X1579332Y58685D01*
G02X1579274Y58519I-198J-24D01*
G03X1578825Y57448I1053J-1071D01*
G03X1580159Y55955I1502J0D01*
G02X1580337Y55756I-22J-199D01*
G01Y54059D01*
G02X1580315Y53968I-200J0D01*
G02X1580279Y53918I-178J90D01*
G01X1579075Y52714D01*
G02X1579025Y52678I-140J142D01*
G02X1578934Y52656I-91J178D01*
G01X1560404D01*
G02X1560313Y52678I0J200D01*
G02X1560263Y52714I90J178D01*
G01X1555121Y57856D01*
G03X1555024Y57910I-142J-141D01*
G01X1555011Y57913D01*
G02X1554909Y57985I59J191D01*
G01X1554784Y58171D01*
X1554682Y58323D01*
X1554678Y58363D01*
X1554704Y58427D01*
G03X1555330Y61458I-7775J3186D01*
G03X1555331Y61609I-8401J131D01*
G01Y61614D01*
G03X1552683Y67737I-8403J0D01*
G03X1546909Y70035I-5774J-6105D01*
G03X1538507Y61633I0J-8402D01*
G03X1539120Y58484I8402J1D01*
G02X1539131Y58447I-185J-75D01*
G01X1539142Y58390D01*
G02X1539122Y58305I-200J2D01*
G01Y58303D01*
G02X1539110Y58282I-179J89D01*
G01X1539065Y58215D01*
X1538922Y58003D01*
G02X1538780Y57916I-166J112D01*
G02X1538763Y57915I-20J199D01*
G01X1531610D01*
G02X1531576Y57918I1J200D01*
G02X1531515Y57939I34J197D01*
G01Y57940D01*
G02X1531433Y58024I96J175D01*
G01X1531272Y58342D01*
G02X1531271Y58344I178J90D01*
G02X1531250Y58448I178J90D01*
G01X1531251Y58453D01*
X1531303Y58524D01*
G03X1532016Y60709I-2988J2184D01*
G03X1531573Y62466I-3701J1D01*
G01Y62467D01*
G02X1531549Y62561I176J95D01*
G01Y62611D01*
X1531715Y62918D01*
G02X1531781Y62991I177J-94D01*
G01X1531823Y63018D01*
X1531874Y63022D01*
G03X1534153Y69588I-319J3789D01*
G01X1534152Y69589D01*
G03X1528187Y65028I-2617J-2759D01*
G01X1528193Y65016D01*
X1528201Y64997D01*
G02X1528188Y64823I-186J-74D01*
G01X1528181Y64812D01*
X1528011Y64527D01*
G02X1527961Y64471I-171J103D01*
G02X1527839Y64429I-123J158D01*
G01X1520995D01*
G03X1517294Y60728I0J-3701D01*
G01Y60726D01*
G03X1518002Y58550I3701J1D01*
G01X1518019Y58527D01*
X1518037Y58477D01*
X1518040Y58448D01*
G02X1518018Y58342I-199J-14D01*
G01X1517996Y58299D01*
X1517850Y58011D01*
G02X1517788Y57949I-169J107D01*
G01X1517765Y57936D01*
G02X1517677Y57915I-89J179D01*
G01X1480982D01*
G02X1480891Y57937I0J200D01*
G02X1480841Y57973I90J178D01*
G01X1480074Y58740D01*
G02X1480030Y58955I142J141D01*
G01X1480099Y59110D01*
X1480190Y59313D01*
G02X1480250Y59384I178J-90D01*
G01X1480265Y59393D01*
G02X1480318Y59417I108J-168D01*
G01X1480344Y59424D01*
X1480363Y59423D01*
G03X1480460Y59420I95J1499D01*
G03Y62424I0J1502D01*
G03X1479778Y62260I0J-1502D01*
G01X1479777D01*
X1479776Y62259D01*
G02X1479679Y62238I-89J179D01*
G01X1479628Y62240D01*
X1479338Y62417D01*
X1479336Y62419D01*
X1479283Y62452D01*
G02X1479196Y62616I113J165D01*
G01Y84660D01*
G02X1479245Y84778I200J-14D01*
G01X1479264Y84797D01*
G02X1479270Y84802I131J-151D01*
G03Y87290I-842J1244D01*
G02X1479196Y87432I126J156D01*
G01Y92496D01*
G02X1479197Y92515I200J-1D01*
G02X1479237Y92617I199J-19D01*
G01X1479240Y92620D01*
G02X1479254Y92636I157J-124D01*
G01X1479338Y92721D01*
G02X1479343Y92726I144J-139D01*
G02X1479469Y92780I137J-146D01*
G03X1480882Y94279I-89J1499D01*
G01X1480883D01*
G03X1479512Y95776I-1503J0D01*
G01X1479465Y95779D01*
X1479433Y95796D01*
X1479432D01*
X1479427Y95799D01*
G02X1479378Y95836I95J176D01*
G01X1479311Y95908D01*
X1479181Y96049D01*
G02X1479141Y96132I156J126D01*
G02X1479137Y96170I196J40D01*
G01Y108877D01*
G02X1479168Y108984I200J0D01*
G01X1479183Y109007D01*
X1479224Y109044D01*
X1479251Y109057D01*
G03X1479796Y109498I-646J1356D01*
G01Y109499D01*
X1479804Y109509D01*
G02X1479811Y109517I154J-128D01*
G01X1479845Y109551D01*
G02X1479936Y109589I120J-160D01*
G01X1479955Y109592D01*
X1480228Y109631D01*
G02X1480294Y109626I18J-199D01*
G01X1480323Y109618D01*
X1480361Y109590D01*
G02X1480363Y109588I-140J-142D01*
G03X1481272Y109281I910J1196D01*
G01X1481274D01*
G03X1481322Y109282I-7J1503D01*
G01X1481368Y109285D01*
G03X1482591Y110063I-95J1500D01*
G02X1482739Y110151I166J-111D01*
G01X1482741D01*
G02X1482757Y110152I20J-199D01*
G01X1483084D01*
G02X1483243Y110058I-11J-200D01*
G03X1483382Y109855I1305J744D01*
G03X1483525Y109702I1166J947D01*
G01X1483528Y109699D01*
G03X1484567Y109282I1039J1086D01*
G03X1486069Y110784I0J1502D01*
G03X1485593Y111881I-1502J0D01*
G01X1485590Y111884D01*
G03X1484547Y112305I-1043J-1081D01*
G03X1483243Y111548I0J-1502D01*
G02X1483084Y111454I-170J106D01*
G01X1482788D01*
G02X1482736Y111461I0J200D01*
G02X1482690Y111480I53J193D01*
G01X1482608Y111527D01*
G02X1482570Y111555I99J174D01*
G01X1482552Y111572D01*
X1482545Y111584D01*
X1482539Y111593D01*
G03X1482302Y111878I-1265J-811D01*
G01X1482301Y111879D01*
G03X1481253Y112305I-1048J-1076D01*
G03X1480061Y111717I0J-1502D01*
G01X1480053Y111707D01*
G02X1480046Y111699I-154J128D01*
G01X1480012Y111665D01*
G02X1479921Y111627I-120J160D01*
G01X1479642Y111586D01*
G02X1479611Y111584I-28J198D01*
G01X1479495Y111623D01*
X1479477Y111635D01*
G03X1479446Y111656I-858J-1233D01*
G01X1479426Y111670D01*
X1479411Y111686D01*
G02X1479384Y111725I150J133D01*
G01X1479350Y111786D01*
X1479333Y111818D01*
G02X1479314Y111902I181J85D01*
G01Y111924D01*
G02X1479337Y112017I200J0D01*
G01X1479366Y112065D01*
G02X1479384Y112089I168J-107D01*
G01X1479401Y112107D01*
X1479426Y112123D01*
G03X1479959Y114083I-803J1271D01*
G03X1479659Y114483I-1336J-689D01*
G01X1479657Y114485D01*
G03X1479251Y114769I-1053J-1073D01*
G01X1479250Y114770D01*
G02X1479167Y114843I85J181D01*
G01X1479152Y114866D01*
X1479144Y114894D01*
G02X1479137Y114946I193J52D01*
G01Y115053D01*
G02X1479138Y115071I200J-2D01*
G02X1479169Y115158I199J-22D01*
G01X1479185Y115182D01*
X1479225Y115217D01*
X1479226D01*
X1479232Y115220D01*
G03X1480126Y116594I-609J1374D01*
G03X1479651Y117690I-1502J0D01*
G01X1479649Y117692D01*
G03X1479527Y117798I-1045J-1079D01*
G02X1479452Y117926I123J158D01*
G02X1479450Y117953I198J28D01*
G01Y118238D01*
G02X1479465Y118312I200J-2D01*
G01Y118314D01*
G02X1479515Y118386I186J-76D01*
G03X1480116Y119418I-890J1209D01*
G01X1480123Y119478D01*
G03X1480127Y119594I-1499J110D01*
G03X1479660Y120683I-1503J0D01*
G01X1479658Y120685D01*
X1479643Y120699D01*
G03X1479251Y120969I-1038J-1087D01*
G01X1479250Y120970D01*
G02X1479167Y121043I85J181D01*
G01X1479152Y121066D01*
X1479144Y121094D01*
G02X1479137Y121146I193J52D01*
G01Y122604D01*
G02X1479185Y122734I200J0D01*
G01X1479208Y122761D01*
X1479268Y122795D01*
X1479304Y122801D01*
G03X1480560Y124283I-246J1482D01*
G03X1480084Y125380I-1502J0D01*
G01X1480083Y125381D01*
G03X1480080Y125384I-143J-140D01*
G03X1479310Y125780I-1043J-1082D01*
G01X1479302Y125781D01*
X1479277Y125788D01*
G02X1479137Y125978I60J191D01*
G01Y131938D01*
G02X1479150Y132010I200J1D01*
G02X1479176Y132057I187J-72D01*
G02X1479251Y132119I161J-119D01*
G02X1479258Y132122I82J-182D01*
G01X1479596Y132267D01*
G02X1479710Y132280I79J-184D01*
G01X1479738Y132275D01*
X1479790Y132249D01*
X1479812Y132228D01*
G03X1479961Y132104I1034J1091D01*
G01X1479966Y132100D01*
X1479985Y132070D01*
X1479993Y132056D01*
G02X1480009Y132015I-177J-93D01*
G01X1480039Y131878D01*
X1480048Y131837D01*
G02X1480025Y131693I-196J-43D01*
G03X1479807Y130898I1344J-796D01*
G03X1482929I1561J0D01*
G03X1482266Y132176I-1563J0D01*
G02X1482185Y132297I114J164D01*
G01X1482147Y132476D01*
G02X1482146Y132536I197J33D01*
G01X1482151Y132568D01*
X1482169Y132603D01*
X1482170Y132604D01*
G03X1482275Y132849I-1323J712D01*
G01Y132850D01*
X1482287Y132886D01*
X1482309Y132913D01*
G02X1482356Y132955I155J-126D01*
G01X1482620Y133114D01*
X1482654Y133121D01*
G03X1483014Y133077I361J1458D01*
G03X1484516Y134579I0J1502D01*
G03X1484040Y135676I-1502J0D01*
G01X1484037Y135679D01*
G03X1482994Y136100I-1043J-1081D01*
G03X1481566Y135065I0J-1503D01*
G01X1481554Y135029D01*
X1481533Y135002D01*
G02X1481479Y134955I-156J125D01*
G01X1481365Y134887D01*
X1481240Y134813D01*
G02X1481186Y134794I-93J177D01*
G01X1481154Y134788D01*
X1481115Y134795D01*
G03X1480848Y134819I-267J-1478D01*
G01X1480847D01*
G03X1479798Y134393I0J-1505D01*
G01X1479784Y134380D01*
X1479768Y134364D01*
X1479711Y134354D01*
G02X1479607Y134363I-35J197D01*
G01X1479246Y134517D01*
G02X1479139Y134666I91J178D01*
G02X1479137Y134693I198J28D01*
G01Y167051D01*
G02X1479142Y167095I200J0D01*
G02X1479168Y167158I195J-44D01*
G01X1479169Y167159D01*
X1479193Y167193D01*
X1479242Y167229D01*
X1479274Y167240D01*
G03X1480302Y168665I-474J1425D01*
G03X1479828Y169760I-1502J0D01*
G02X1479824Y169764I139J143D01*
G03X1479822Y169766I-1063J-1061D01*
G01X1479821Y169767D01*
G03X1479272Y170103I-1040J-1083D01*
G01X1479270Y170104D01*
X1479227Y170125D01*
G02X1479137Y170287I110J167D01*
G01Y171051D01*
G02X1479142Y171095I200J0D01*
G02X1479168Y171158I195J-44D01*
G01X1479169Y171159D01*
X1479193Y171193D01*
X1479242Y171229D01*
X1479274Y171240D01*
G03X1480302Y172665I-474J1425D01*
G03X1479828Y173760I-1502J0D01*
G02X1479824Y173764I139J143D01*
G03X1479822Y173766I-1063J-1061D01*
G01X1479821Y173767D01*
G03X1479272Y174103I-1040J-1083D01*
G01X1479270Y174104D01*
X1479227Y174125D01*
G02X1479137Y174287I110J167D01*
G01Y175051D01*
G02X1479142Y175095I200J0D01*
G02X1479168Y175158I195J-44D01*
G01X1479169Y175159D01*
X1479193Y175193D01*
X1479242Y175229D01*
X1479274Y175240D01*
G03X1480302Y176665I-474J1425D01*
G03X1479828Y177760I-1502J0D01*
G02X1479824Y177764I139J143D01*
G03X1479822Y177766I-1063J-1061D01*
G01X1479821Y177767D01*
G03X1479272Y178103I-1040J-1083D01*
G01X1479270Y178104D01*
X1479227Y178125D01*
G02X1479137Y178287I110J167D01*
G01Y179051D01*
G02X1479142Y179095I200J0D01*
G02X1479168Y179158I195J-44D01*
G01X1479169Y179159D01*
X1479193Y179193D01*
X1479242Y179229D01*
X1479274Y179240D01*
G03X1480302Y180665I-474J1425D01*
G03X1479828Y181760I-1502J0D01*
G02X1479824Y181764I139J143D01*
G03X1479822Y181766I-1063J-1061D01*
G01X1479821Y181767D01*
G03X1479272Y182103I-1040J-1083D01*
G01X1479270Y182104D01*
X1479227Y182125D01*
G02X1479137Y182287I110J167D01*
G01Y185130D01*
G02X1479171Y185241I200J-1D01*
G01X1479179Y185252D01*
G02X1479228Y185298I160J-121D01*
G01X1479253Y185314D01*
X1479287Y185323D01*
G03X1480415Y186778I-374J1455D01*
G03X1479940Y187874I-1502J0D01*
G01X1479937Y187877D01*
G03X1479285Y188247I-1044J-1080D01*
G01X1479275Y188250D01*
G02X1479137Y188440I62J190D01*
G01Y191051D01*
G02X1479142Y191095I200J0D01*
G02X1479168Y191158I195J-44D01*
G01X1479169Y191159D01*
X1479193Y191193D01*
X1479242Y191229D01*
X1479274Y191240D01*
G03X1480302Y192665I-474J1425D01*
G03X1479828Y193760I-1502J0D01*
G02X1479824Y193764I139J143D01*
G03X1479822Y193766I-1063J-1061D01*
G01X1479821Y193767D01*
G03X1479272Y194103I-1040J-1083D01*
G01X1479270Y194104D01*
X1479227Y194125D01*
G02X1479137Y194287I110J167D01*
G01Y195051D01*
G02X1479142Y195095I200J0D01*
G02X1479168Y195158I195J-44D01*
G01X1479169Y195159D01*
X1479193Y195193D01*
X1479242Y195229D01*
X1479274Y195240D01*
G03X1480302Y196665I-474J1425D01*
G03X1479828Y197760I-1502J0D01*
G02X1479824Y197764I139J143D01*
G03X1479822Y197766I-1063J-1061D01*
G01X1479821Y197767D01*
G03X1479272Y198103I-1040J-1083D01*
G01X1479270Y198104D01*
X1479227Y198125D01*
G02X1479137Y198287I110J167D01*
G01Y199240D01*
G02X1479176Y199358I200J-1D01*
G01X1479194Y199383D01*
X1479244Y199419D01*
X1479278Y199430D01*
G03X1480334Y200864I-446J1434D01*
G03X1479859Y201960I-1502J0D01*
G01X1479858Y201961D01*
G03X1479832Y201986I-1054J-1070D01*
G03X1479830Y201988I-142J-140D01*
G03X1479274Y202313I-1019J-1105D01*
G02X1479217Y202342I61J190D01*
G01X1479194Y202359D01*
X1479172Y202389D01*
G02X1479137Y202502I165J113D01*
G01Y203240D01*
G02X1479148Y203305I200J0D01*
G01X1479277Y203429D01*
X1479319Y203443D01*
G03X1480334Y204864I-487J1421D01*
G03X1479859Y205960I-1502J0D01*
G01X1479858Y205961D01*
G03X1479841Y205977I-1038J-1086D01*
G02X1479778Y206123I137J146D01*
G01Y207606D01*
G02X1479843Y207754I200J0D01*
G03X1480334Y208864I-1009J1110D01*
G03X1479859Y209960I-1502J0D01*
G01X1479858Y209961D01*
G03X1479841Y209977I-1038J-1086D01*
G02X1479778Y210123I137J146D01*
G01Y211606D01*
G02X1479843Y211754I200J0D01*
G03X1480334Y212864I-1009J1110D01*
G03X1479859Y213960I-1502J0D01*
G01X1479858Y213961D01*
G03X1479841Y213977I-1038J-1086D01*
G02X1479778Y214123I137J146D01*
G01Y215606D01*
G02X1479843Y215754I200J0D01*
G03X1480334Y216864I-1009J1110D01*
G03X1479859Y217960I-1502J0D01*
G01X1479858Y217961D01*
G03X1479841Y217977I-1038J-1086D01*
G02X1479778Y218123I137J146D01*
G01Y220606D01*
G02X1479843Y220754I200J0D01*
G03X1480334Y221864I-1009J1110D01*
G03X1479859Y222960I-1502J0D01*
G01X1479858Y222961D01*
G03X1479841Y222977I-1038J-1086D01*
G02X1479778Y223123I137J146D01*
G01Y242109D01*
G02X1479837Y242251I200J0D01*
G01X1479956Y242370D01*
G02X1480034Y242418I141J-142D01*
G02X1480053Y242423I60J-191D01*
G01X1480100Y242421D01*
G03X1480162Y242420I51J1209D01*
G01X1480164D01*
G37*
G36*
G01X1479271Y276294D02*
X1554245D01*
G02X1554387Y276235I0J-200D01*
G01X1555671Y274951D01*
G02X1555673Y274949I-140J-142D01*
G02X1555730Y274809I-143J-140D01*
G01Y267385D01*
G02X1555617Y267205I-200J0D01*
G01X1555240Y267023D01*
X1555127Y267036D01*
X1555081Y267072D01*
G03X1554147Y267398I-934J-1175D01*
G03Y264394I0J-1502D01*
G03X1555081Y264720I0J1501D01*
G01X1555127Y264756D01*
X1555240Y264769D01*
X1555617Y264587D01*
G02X1555730Y264407I-87J-180D01*
G01Y257901D01*
X1555676Y257809D01*
X1555631Y257782D01*
X1555629D01*
X1555341Y257613D01*
G02X1555187Y257593I-101J173D01*
G01X1555133Y257608D01*
X1555111Y257620D01*
G03X1554389Y257805I-723J-1319D01*
G01X1554388D01*
G03Y254801I0J-1502D01*
G01X1554389D01*
G03X1555111Y254986I-1J1504D01*
G01X1555133Y254998D01*
X1555187Y255013D01*
G02X1555341Y254993I53J-193D01*
G01X1555630Y254824D01*
G02X1555633Y254822I-109J-167D01*
G02X1555730Y254651I-103J-171D01*
G01Y207177D01*
X1555723Y207152D01*
G03X1555672Y206763I1451J-388D01*
G01Y206755D01*
G03X1555723Y206372I1502J5D01*
G01X1555730Y206346D01*
Y202582D01*
G03X1555789Y202440I200J0D01*
G01X1556210Y202019D01*
G03X1556352Y201960I142J141D01*
G01X1559070D01*
G02X1559103Y201957I-2J-200D01*
G02X1559210Y201903I-32J-197D01*
G01X1559465Y201648D01*
G02X1559467Y201646I-140J-142D01*
G02X1559524Y201506I-143J-140D01*
G01Y193725D01*
G02X1559438Y193561I-200J0D01*
G01X1559188Y193386D01*
G02X1559074Y193350I-114J164D01*
G01X1558987D01*
X1558956Y193361D01*
G03X1558466Y193443I-490J-1420D01*
G01X1558450D01*
G03X1556964Y191941I16J-1502D01*
G03X1558466Y190439I1502J0D01*
G01X1558469D01*
G03X1558987Y190532I-2J1502D01*
G01X1559033Y190549D01*
X1559130Y190537D01*
X1559438Y190321D01*
G02X1559524Y190157I-114J-164D01*
G01Y165175D01*
G02X1559465Y165033I-200J0D01*
G01X1555999Y161567D01*
X1555971Y161538D01*
X1555897Y161508D01*
X1548883D01*
G02X1548712Y161604I0J200D01*
G01X1548535Y161896D01*
G02X1548519Y161930I172J102D01*
G02X1548530Y162094I188J70D01*
G01X1548533Y162100D01*
X1548550Y162135D01*
G03X1548702Y162788I-1350J658D01*
G01Y162790D01*
Y162815D01*
G03X1548299Y163817I-1502J-22D01*
G01X1548298Y163818D01*
G02X1548242Y163957I144J139D01*
G01Y164268D01*
X1548269Y164338D01*
X1548296Y164366D01*
G03Y166420I-1096J1027D01*
G01X1548269Y166448D01*
X1548242Y166518D01*
Y166868D01*
X1548269Y166938D01*
X1548296Y166966D01*
G03X1548702Y167993I-1096J1027D01*
G03X1548332Y168980I-1501J0D01*
G01X1548308Y169008D01*
X1548283Y169074D01*
Y169412D01*
X1548308Y169478D01*
X1548332Y169506D01*
G03X1548702Y170493I-1131J987D01*
G03X1545698I-1502J0D01*
G03X1546068Y169506I1501J0D01*
G01X1546092Y169478D01*
X1546117Y169412D01*
Y169074D01*
X1546092Y169008D01*
X1546068Y168980D01*
G03X1545698Y167993I1131J-987D01*
G03X1546104Y166966I1502J0D01*
G01X1546131Y166938D01*
X1546158Y166868D01*
Y166518D01*
X1546131Y166448D01*
X1546104Y166420D01*
G03Y164366I1096J-1027D01*
G01X1546131Y164338D01*
X1546158Y164268D01*
Y163918D01*
X1546131Y163849D01*
X1546104Y163820D01*
G03X1545698Y162821I1096J-1027D01*
G01Y162793D01*
G03X1545850Y162134I1502J-1D01*
G01X1545879Y162073D01*
G02X1545881Y161930I-186J-74D01*
G02X1545865Y161896I-188J68D01*
G01X1545688Y161605D01*
X1545661Y161559D01*
X1545570Y161508D01*
X1541946D01*
G02X1541788Y161585I0J200D01*
G01X1541565Y161870D01*
X1541546Y161959D01*
X1541557Y162005D01*
G03X1541602Y162368I-1457J365D01*
G03X1540100Y163870I-1502J0D01*
G03X1539073Y163464I0J-1502D01*
G01X1539045Y163437D01*
X1538975Y163410D01*
X1538625D01*
X1538555Y163437D01*
X1538527Y163464D01*
G03X1537500Y163870I-1027J-1096D01*
G03X1535998Y162368I0J-1502D01*
G03X1536043Y162005I1502J2D01*
G01X1536054Y161959D01*
X1536035Y161870D01*
X1535812Y161585D01*
G02X1535654Y161508I-158J123D01*
G01X1520506D01*
G02X1520364Y161567I0J200D01*
G01X1519708Y162223D01*
G02X1519650Y162364I142J141D01*
G01Y240157D01*
G03X1519591Y240298I-200J-1D01*
G01X1516537Y243352D01*
G03X1516397Y243410I-141J-142D01*
G01X1516177D01*
X1516161Y243413D01*
G03X1515920Y243428I-195J-1186D01*
G01X1509368D01*
G02X1509297Y243441I0J200D01*
G01X1509260Y243455D01*
X1509232Y243481D01*
G02X1509209Y243506I135J147D01*
G01X1508987Y243792D01*
X1508968Y243882D01*
X1508980Y243927D01*
G03X1509026Y244288I-1456J369D01*
G01Y244308D01*
G03X1507524Y245799I-1502J-11D01*
G03X1507157Y245753I2J-1502D01*
G01X1507101Y245739D01*
X1506994Y245773D01*
X1506686Y246131D01*
X1506668Y246242D01*
X1506690Y246295D01*
G03X1506806Y246874I-1387J579D01*
G03X1505304Y248376I-1502J0D01*
G03X1504275Y247968I0J-1502D01*
G01X1504241Y247936D01*
X1504155Y247909D01*
X1503801Y247958D01*
G02X1503793Y247959I21J199D01*
G02X1503656Y248055I36J197D01*
G03X1502362Y248794I-1294J-763D01*
G03Y245790I0J-1502D01*
G03X1503391Y246198I0J1502D01*
G01X1503425Y246230D01*
X1503511Y246257D01*
X1503865Y246208D01*
G02X1503872Y246207I-25J-198D01*
G02X1504013Y246106I-35J-197D01*
G03X1504016Y246100I180J86D01*
G03X1505304Y245372I1288J775D01*
G03X1505383Y245374I1J1502D01*
G01X1505384D01*
G03X1505446Y245378I-66J1501D01*
G01X1505480Y245382D01*
G03X1505562Y245394I-176J1492D01*
G01X1505563D01*
G03X1505671Y245418I-272J1477D01*
G01X1505727Y245432D01*
X1505834Y245398D01*
X1506142Y245040D01*
X1506160Y244929D01*
X1506138Y244876D01*
G03X1506022Y244308I1387J-579D01*
G01Y244296D01*
G03X1506067Y243930I1502J-1D01*
G01X1506068Y243929D01*
G02X1506032Y243755I-193J-51D01*
G01X1505839Y243506D01*
G02X1505816Y243481I-158J122D01*
G01X1505788Y243455D01*
X1505751Y243441D01*
G02X1505680Y243428I-71J187D01*
G01X1501827D01*
G03X1501633Y243413I-5J-1201D01*
G01X1501617Y243410D01*
X1500665D01*
X1500619Y243422D01*
X1500600Y243431D01*
X1500598Y243432D01*
G03X1499947Y243580I-650J-1354D01*
G01X1499916D01*
G03X1499292Y243430I31J-1502D01*
G01X1499272Y243420D01*
X1499228Y243410D01*
X1498237D01*
X1498221Y243413D01*
G03X1498027Y243428I-189J-1186D01*
G01X1493560D01*
G02X1493437Y243470I0J200D01*
G01X1493410Y243491D01*
X1493221Y243781D01*
X1493193Y243824D01*
X1493189Y243875D01*
X1493185Y243924D01*
X1493208Y243977D01*
G03X1493330Y244571I-1380J593D01*
G01Y244590D01*
G03X1490326I-1502J-19D01*
G01Y244570D01*
G03X1490451Y243971I1502J1D01*
G02X1490435Y243781I-183J-80D01*
G01X1490264Y243520D01*
G02X1490097Y243430I-167J110D01*
G01X1480167D01*
G02X1480026Y243488I0J200D01*
G01X1478436Y245078D01*
X1478407Y245106D01*
X1478377Y245180D01*
Y275400D01*
G02X1478434Y275540I200J0D01*
G01X1478435Y275541D01*
X1479129Y276235D01*
G02X1479131Y276237I142J-140D01*
G02X1479271Y276294I140J-143D01*
G37*
G36*
G01X1474006Y1186853D02*
X1474488D01*
G02X1474565Y1186838I1J-200D01*
G01X1478667Y1185137D01*
X1478732Y1185050D01*
X1478738Y1184995D01*
G03X1480231Y1183662I1493J170D01*
G01Y1183661D01*
G03X1481262Y1184070I0J1504D01*
G01X1481299Y1184105D01*
X1481394Y1184131D01*
X1482484Y1183882D01*
G02X1482581Y1183828I-45J-195D01*
G01X1496153Y1170256D01*
G02X1496201Y1170052I-142J-141D01*
G01X1496071Y1169658D01*
X1495984Y1169586D01*
X1495927Y1169578D01*
G03X1494648Y1168267I213J-1487D01*
G01X1494644Y1168228D01*
G03X1494637Y1168092I1496J-145D01*
G01Y1168090D01*
G03X1495235Y1166891I1503J1D01*
G01X1495236Y1166890D01*
G02X1495315Y1166733I-121J-159D01*
G01X1495317Y1166579D01*
Y1166577D01*
X1495318Y1166419D01*
G02X1495246Y1166264I-200J-1D01*
G01X1495244Y1166262D01*
X1495243Y1166261D01*
G03X1494683Y1165091I942J-1170D01*
G03X1496185Y1163589I1502J0D01*
G03X1497677Y1164915I0J1502D01*
G01X1497683Y1164969D01*
G03X1497090Y1166291I-1498J122D01*
G01X1497089Y1166292D01*
G02X1497010Y1166449I121J159D01*
G01X1497008Y1166603D01*
Y1166605D01*
X1497007Y1166763D01*
G02X1497079Y1166918I200J1D01*
G01X1497081Y1166920D01*
X1497082Y1166921D01*
G03X1497623Y1167854I-942J1170D01*
G01X1497628Y1167880D01*
X1497652Y1167934D01*
G02X1497770Y1168041I182J-82D01*
G01X1498101Y1168152D01*
G02X1498306Y1168103I63J-190D01*
G01X1506682Y1159727D01*
G02X1506740Y1159604I-141J-142D01*
G01X1506741Y1159594D01*
Y1156958D01*
G02X1506740Y1156941I-200J3D01*
G01X1506733Y1156858D01*
X1506607Y1156751D01*
X1506576Y1156753D01*
X1506465Y1156700D01*
X1506463D01*
X1506356Y1156649D01*
X1506238Y1156665D01*
X1506193Y1156705D01*
G03X1505130Y1157105I-1063J-1212D01*
G03X1503681Y1156202I0J-1614D01*
G01X1503656Y1156152D01*
X1503561Y1156091D01*
X1503092Y1156084D01*
X1502995Y1156142D01*
X1502968Y1156192D01*
G03X1501640Y1156993I-1328J-700D01*
G03Y1153989I0J-1502D01*
G03X1502968Y1154790I0J1501D01*
G01X1502995Y1154840D01*
X1503092Y1154898D01*
X1503561Y1154891D01*
X1503656Y1154830D01*
X1503681Y1154780D01*
G03X1505130Y1153877I1449J711D01*
G03X1506193Y1154277I0J1612D01*
G01X1506238Y1154317D01*
X1506356Y1154333D01*
X1506463Y1154282D01*
X1506465D01*
X1506628Y1154203D01*
G02X1506741Y1154023I-87J-180D01*
G01Y1144358D01*
G02X1506740Y1144341I-200J3D01*
G01X1506733Y1144258D01*
X1506607Y1144151D01*
X1506576Y1144153D01*
X1506465Y1144100D01*
X1506463D01*
X1506356Y1144049D01*
X1506238Y1144065D01*
X1506193Y1144105D01*
G03X1505130Y1144505I-1063J-1212D01*
G03X1503681Y1143602I0J-1614D01*
G01X1503656Y1143552D01*
X1503561Y1143491D01*
X1503092Y1143484D01*
X1502995Y1143542D01*
X1502968Y1143592D01*
G03X1501640Y1144393I-1328J-700D01*
G03Y1141389I0J-1502D01*
G03X1502968Y1142190I0J1501D01*
G01X1502995Y1142240D01*
X1503092Y1142298D01*
X1503561Y1142291D01*
X1503656Y1142230D01*
X1503681Y1142180D01*
G03X1505130Y1141277I1449J711D01*
G03X1506193Y1141677I0J1612D01*
G01X1506238Y1141717D01*
X1506356Y1141733D01*
X1506463Y1141682D01*
X1506465D01*
X1506628Y1141603D01*
G02X1506741Y1141423I-87J-180D01*
G01Y1131758D01*
G02X1506740Y1131741I-200J3D01*
G01X1506733Y1131658D01*
X1506607Y1131551D01*
X1506576Y1131553D01*
X1506465Y1131500D01*
X1506463D01*
X1506356Y1131449D01*
X1506238Y1131465D01*
X1506193Y1131505D01*
G03X1505130Y1131905I-1063J-1212D01*
G03X1503681Y1131002I0J-1614D01*
G01X1503656Y1130952D01*
X1503561Y1130891D01*
X1503092Y1130884D01*
X1502995Y1130942D01*
X1502968Y1130992D01*
G03X1501640Y1131793I-1328J-700D01*
G03Y1128789I0J-1502D01*
G03X1502968Y1129590I0J1501D01*
G01X1502995Y1129640D01*
X1503092Y1129698D01*
X1503561Y1129691D01*
X1503656Y1129630D01*
X1503681Y1129580D01*
G03X1505130Y1128677I1449J711D01*
G03X1506193Y1129077I0J1612D01*
G01X1506238Y1129117D01*
X1506356Y1129133D01*
X1506463Y1129082D01*
X1506465D01*
X1506628Y1129003D01*
G02X1506741Y1128823I-87J-180D01*
G01Y1119158D01*
G02X1506740Y1119141I-200J3D01*
G01X1506733Y1119058D01*
X1506607Y1118951D01*
X1506576Y1118953D01*
X1506465Y1118900D01*
X1506463D01*
X1506356Y1118849D01*
X1506238Y1118865D01*
X1506193Y1118905D01*
G03X1505130Y1119305I-1063J-1212D01*
G03X1503681Y1118402I0J-1614D01*
G01X1503656Y1118352D01*
X1503561Y1118291D01*
X1503092Y1118284D01*
X1502995Y1118342D01*
X1502968Y1118392D01*
G03X1501640Y1119193I-1328J-700D01*
G03Y1116189I0J-1502D01*
G03X1502968Y1116990I0J1501D01*
G01X1502995Y1117040D01*
X1503092Y1117098D01*
X1503561Y1117091D01*
X1503656Y1117030D01*
X1503681Y1116980D01*
G03X1505130Y1116077I1449J711D01*
G03X1506467Y1116787I0J1614D01*
G01X1506493Y1116826D01*
X1506572Y1116872D01*
X1506775Y1116886D01*
G02X1506930Y1116828I14J-200D01*
G01X1513255Y1110503D01*
G02X1513287Y1110461I-142J-141D01*
G01X1513301Y1110437D01*
X1513308Y1110411D01*
G03X1513543Y1109960I1159J317D01*
G01X1513544D01*
G03X1514142Y1109571I925J768D01*
G01X1514156Y1109567D01*
G02X1514242Y1109516I-56J-192D01*
G01X1516995Y1106763D01*
G02X1517027Y1106721I-142J-141D01*
G01X1517041Y1106697D01*
X1517048Y1106671D01*
G03X1517283Y1106220I1159J317D01*
G01X1517284D01*
G03X1517882Y1105831I925J768D01*
G01X1517896Y1105827D01*
G02X1517982Y1105776I-56J-192D01*
G01X1520736Y1103022D01*
G02X1520768Y1102980I-142J-141D01*
G01X1520782Y1102956D01*
X1520789Y1102930D01*
G03X1521024Y1102479I1159J317D01*
G01X1521025D01*
G03X1521623Y1102090I925J768D01*
G01X1521637Y1102086D01*
G02X1521723Y1102035I-56J-192D01*
G01X1524476Y1099282D01*
G02X1524508Y1099240I-142J-141D01*
G01X1524522Y1099216D01*
X1524529Y1099190D01*
G03X1524764Y1098739I1159J317D01*
G01X1524765D01*
G03X1525363Y1098350I925J768D01*
G01X1525377Y1098346D01*
G02X1525463Y1098295I-56J-192D01*
G01X1526481Y1097277D01*
G02X1526540Y1097135I-141J-142D01*
G01Y1097009D01*
G02X1526340Y1096809I-200J0D01*
G01X1526291D01*
X1526247Y1096832D01*
G03X1525689Y1096969I-557J-1065D01*
G03Y1094565I0J-1202D01*
G03X1526027Y1094614I-2J1202D01*
G01X1526074Y1094627D01*
X1526165Y1094611D01*
X1526460Y1094390D01*
G02X1526540Y1094230I-120J-160D01*
G01Y1093564D01*
G02X1526460Y1093404I-200J0D01*
G01X1526165Y1093183D01*
X1526074Y1093167D01*
X1526027Y1093180D01*
G03X1525689Y1093229I-340J-1153D01*
G03Y1090825I0J-1202D01*
G03X1526027Y1090874I-2J1202D01*
G01X1526074Y1090887D01*
X1526165Y1090871D01*
X1526460Y1090650D01*
G02X1526540Y1090490I-120J-160D01*
G01Y1089824D01*
G02X1526460Y1089664I-200J0D01*
G01X1526165Y1089443D01*
X1526074Y1089427D01*
X1526027Y1089440D01*
G03X1525689Y1089489I-340J-1153D01*
G03Y1087085I0J-1202D01*
G03X1526027Y1087134I-2J1202D01*
G01X1526074Y1087147D01*
X1526165Y1087131D01*
X1526460Y1086910D01*
G02X1526540Y1086750I-120J-160D01*
G01Y1086084D01*
G02X1526460Y1085924I-200J0D01*
G01X1526165Y1085703D01*
X1526074Y1085687D01*
X1526027Y1085700D01*
G03X1525689Y1085749I-340J-1153D01*
G03Y1083345I0J-1202D01*
G03X1526027Y1083394I-2J1202D01*
G01X1526074Y1083407D01*
X1526165Y1083391D01*
X1526460Y1083170D01*
G02X1526540Y1083010I-120J-160D01*
G01Y1082344D01*
G02X1526460Y1082184I-200J0D01*
G01X1526165Y1081963D01*
X1526074Y1081947D01*
X1526027Y1081960D01*
G03X1525689Y1082009I-340J-1153D01*
G03Y1079605I0J-1202D01*
G03X1526027Y1079654I-2J1202D01*
G01X1526074Y1079667D01*
X1526165Y1079651D01*
X1526460Y1079430D01*
G02X1526540Y1079270I-120J-160D01*
G01Y1078603D01*
G02X1526460Y1078443I-200J0D01*
G01X1526165Y1078222D01*
X1526074Y1078206D01*
X1526027Y1078219D01*
G03X1525689Y1078268I-340J-1153D01*
G03Y1075864I0J-1202D01*
G03X1526027Y1075913I-2J1202D01*
G01X1526074Y1075926D01*
X1526165Y1075910D01*
X1526460Y1075689D01*
G02X1526540Y1075529I-120J-160D01*
G01Y1074863D01*
G02X1526460Y1074703I-200J0D01*
G01X1526165Y1074482D01*
X1526074Y1074466D01*
X1526027Y1074479D01*
G03X1525689Y1074528I-340J-1153D01*
G03Y1072124I0J-1202D01*
G03X1526027Y1072173I-2J1202D01*
G01X1526074Y1072186D01*
X1526165Y1072170D01*
X1526460Y1071949D01*
G02X1526540Y1071789I-120J-160D01*
G01Y1052523D01*
G02X1526427Y1052343I-200J0D01*
G01X1526050Y1052162D01*
X1525936Y1052175D01*
X1525890Y1052211D01*
G03X1524953Y1052539I-937J-1174D01*
G03Y1049535I0J-1502D01*
G03X1525890Y1049863I0J1502D01*
G01X1525936Y1049899D01*
X1526050Y1049912D01*
X1526427Y1049731D01*
G02X1526540Y1049551I-87J-180D01*
G01Y1026658D01*
X1526460Y1026552D01*
X1526395Y1026534D01*
G03Y1023646I416J-1444D01*
G01X1526460Y1023628D01*
X1526540Y1023522D01*
Y1018730D01*
G02X1526481Y1018588I-200J0D01*
G01X1515422Y1007529D01*
G02X1515280Y1007470I-142J141D01*
G01X1509021D01*
G02X1508832Y1007604I0J200D01*
G01X1508686Y1008020D01*
X1508721Y1008142D01*
X1508770Y1008182D01*
G03X1509333Y1009354I-938J1172D01*
G03X1508736Y1010552I-1502J-1D01*
G01X1508699Y1010581D01*
X1508658Y1010662D01*
X1508652Y1011071D01*
X1508691Y1011154D01*
X1508727Y1011183D01*
G03X1509288Y1012354I-942J1171D01*
G03X1506284I-1502J0D01*
G03X1506881Y1011156I1502J1D01*
G01X1506918Y1011127D01*
X1506959Y1011046D01*
X1506965Y1010637D01*
X1506926Y1010554D01*
X1506890Y1010525D01*
G03X1506329Y1009354I942J-1171D01*
G03X1506892Y1008182I1501J0D01*
G01X1506941Y1008142D01*
X1506976Y1008020D01*
X1506830Y1007604D01*
G02X1506641Y1007470I-189J66D01*
G01X1496529D01*
G02X1496340Y1007604I0J200D01*
G01X1496194Y1008020D01*
X1496229Y1008142D01*
X1496278Y1008182D01*
G03X1496841Y1009354I-938J1172D01*
G03X1493837I-1502J0D01*
G03X1494400Y1008182I1501J0D01*
G01X1494449Y1008142D01*
X1494484Y1008020D01*
X1494338Y1007604D01*
G02X1494149Y1007470I-189J66D01*
G01X1493029D01*
G02X1492840Y1007604I0J200D01*
G01X1492694Y1008020D01*
X1492729Y1008142D01*
X1492778Y1008182D01*
G03X1493341Y1009354I-938J1172D01*
G03X1490337I-1502J0D01*
G03X1490900Y1008182I1501J0D01*
G01X1490949Y1008142D01*
X1490984Y1008020D01*
X1490838Y1007604D01*
G02X1490649Y1007470I-189J66D01*
G01X1487220D01*
G02X1487031Y1007604I0J200D01*
G01X1486885Y1008020D01*
X1486920Y1008142D01*
X1486969Y1008182D01*
G03X1487532Y1009354I-938J1172D01*
G03X1484528I-1502J0D01*
G03X1485091Y1008182I1501J0D01*
G01X1485140Y1008142D01*
X1485175Y1008020D01*
X1485029Y1007604D01*
G02X1484840Y1007470I-189J66D01*
G01X1484396D01*
G02X1484241Y1007544I0J200D01*
G01X1484017Y1007820D01*
X1483995Y1007908D01*
X1484005Y1007952D01*
G03X1484037Y1008262I-1470J308D01*
G03X1481033I-1502J0D01*
G03X1481551Y1007127I1502J0D01*
G01X1481582Y1007100D01*
X1481618Y1007025D01*
X1481630Y1006691D01*
G02X1481571Y1006542I-200J-7D01*
G01X1477930Y1002901D01*
G03X1477887Y1002836I142J-141D01*
G01X1477843Y1002731D01*
X1477815Y1002703D01*
X1476188Y1001075D01*
X1476160Y1001046D01*
X1476086Y1001016D01*
X1474798D01*
G02X1474656Y1001075I0J200D01*
G01X1472699Y1003032D01*
G02X1472640Y1003174I141J142D01*
G01Y1016047D01*
G02X1472699Y1016189I200J0D01*
G01X1473861Y1017352D01*
X1479059Y1022550D01*
G03X1479118Y1022692I-141J142D01*
G01Y1033203D01*
G02X1479181Y1033348I200J-1D01*
G01X1479422Y1033577D01*
X1479498Y1033605D01*
X1479540Y1033602D01*
G03X1479624Y1033600I78J1500D01*
G03Y1036604I0J1502D01*
G03X1479540Y1036602I-6J-1502D01*
G01X1479498Y1036599D01*
X1479422Y1036627D01*
X1479181Y1036856D01*
G02X1479118Y1037001I137J146D01*
G01Y1049302D01*
G02X1479212Y1049472I200J0D01*
G01X1479545Y1049679D01*
X1479648Y1049684D01*
X1479694Y1049661D01*
G03X1487990Y1047732I8296J16874D01*
G01X1487991D01*
G03Y1085338I0J18803D01*
G01X1487984D01*
G03X1486997Y1085312I1J-18803D01*
G01X1486954Y1085310D01*
X1486914Y1085325D01*
G02X1486844Y1085371I72J187D01*
G01X1472751Y1099464D01*
X1472734Y1099484D01*
X1472730Y1099489D01*
G03X1472621Y1099613I-965J-739D01*
G01X1471474Y1100761D01*
X1471136Y1101099D01*
G02X1471134Y1101104I185J77D01*
G01Y1116756D01*
G02X1471163Y1116859I200J-1D01*
G01X1471176Y1116881D01*
X1471201Y1116920D01*
G02X1471223Y1116949I170J-106D01*
G01X1471357Y1117092D01*
G02X1471448Y1117148I147J-136D01*
G01X1471473Y1117155D01*
X1471493Y1117156D01*
G03X1472877Y1118654I-119J1498D01*
G03X1471488Y1120153I-1503J0D01*
G01X1471450Y1120156D01*
X1471383Y1120188D01*
X1471307Y1120270D01*
X1471224Y1120359D01*
G02X1471201Y1120388I144J138D01*
G01X1471177Y1120425D01*
G02X1471175Y1120429I178J91D01*
G01X1471163Y1120449D01*
G02X1471134Y1120552I171J104D01*
G01Y1183952D01*
G02X1471193Y1184094I200J0D01*
G01X1471836Y1184737D01*
X1472624Y1185526D01*
G03X1472730Y1185647I-859J860D01*
G01X1472734Y1185652D01*
X1472751Y1185672D01*
X1473873Y1186794D01*
G02X1473996Y1186852I142J-141D01*
G01X1474006Y1186853D01*
G37*
G36*
G01X1574135Y202336D02*
X1577647D01*
G02X1577788Y202278I0J-200D01*
G01X1579828Y200238D01*
X1579843Y200207D01*
G03X1579882Y200132I1352J655D01*
G01X1579883Y200131D01*
G03X1579898Y200105I1308J738D01*
G01X1579911Y200083D01*
X1579927Y200027D01*
X1579940Y199981D01*
Y197600D01*
G02X1579907Y197490I-200J0D01*
G03Y195840I1254J-825D01*
G02X1579940Y195730I-167J-110D01*
G01Y193600D01*
G02X1579907Y193490I-200J0D01*
G03Y191840I1254J-825D01*
G02X1579940Y191730I-167J-110D01*
G01Y187518D01*
X1579930Y187475D01*
X1579919Y187453D01*
G03Y186103I1355J-675D01*
G01X1579930Y186081D01*
X1579940Y186038D01*
Y181600D01*
G02X1579907Y181490I-200J0D01*
G03Y179840I1254J-825D01*
G02X1579940Y179730I-167J-110D01*
G01Y177600D01*
G02X1579907Y177490I-200J0D01*
G03Y175840I1254J-825D01*
G02X1579940Y175730I-167J-110D01*
G01Y173600D01*
G02X1579907Y173490I-200J0D01*
G03Y171840I1254J-825D01*
G02X1579940Y171730I-167J-110D01*
G01Y169600D01*
G02X1579907Y169490I-200J0D01*
G03Y167840I1254J-825D01*
G02X1579940Y167730I-167J-110D01*
G01Y163086D01*
G02X1579885Y162947I-200J-1D01*
G01X1579803Y162862D01*
X1579770Y162846D01*
X1579678Y162801D01*
X1579645Y162797D01*
G03Y159815I182J-1491D01*
G01X1579678Y159811D01*
X1579771Y159766D01*
G02X1579828Y159724I-88J-180D01*
G01X1579885Y159665D01*
G02X1579940Y159526I-145J-138D01*
G01Y151308D01*
G02X1579740Y151108I-200J0D01*
G01X1573166D01*
G02X1572990Y151213I0J200D01*
G01X1572824Y151523D01*
G02X1572800Y151625I176J95D01*
G01X1572802Y151682D01*
X1572833Y151729D01*
G03X1573085Y152562I-1251J833D01*
G03X1571583Y154064I-1502J0D01*
G03X1570289Y153325I0J-1502D01*
G01X1570263Y153281D01*
X1570178Y153229D01*
X1570000Y153219D01*
X1569747Y153204D01*
X1569657Y153245D01*
X1569627Y153285D01*
G03X1568433Y153875I-1194J-913D01*
G03X1566931Y152373I0J-1502D01*
G03X1567096Y151689I1502J0D01*
G01X1567120Y151642D01*
X1567116Y151539D01*
X1566910Y151203D01*
G02X1566740Y151108I-170J105D01*
G01X1557422D01*
G02X1557294Y151155I1J200D01*
G01X1556461Y151988D01*
X1556156Y152292D01*
G03X1554741Y152878I-1415J-1415D01*
G01X1548381D01*
G03X1546966Y152292I0J-2001D01*
G01X1543629Y148955D01*
G03X1543106Y148042I1414J-1416D01*
G03X1543042Y147540I1938J-502D01*
G03X1545040Y145538I2002J0D01*
G01X1545044D01*
G03X1545546Y145602I0J2002D01*
G03X1546459Y146125I-503J1937D01*
G01X1549151Y148817D01*
G02X1549293Y148876I142J-141D01*
G01X1551771D01*
G02X1551920Y148809I0J-200D01*
G01X1552119Y148588D01*
G02X1552169Y148437I-149J-133D01*
G01Y148434D01*
G03X1552161Y148277I1494J-155D01*
G03X1553663Y146775I1502J0D01*
G03X1554852Y147359I0J1502D01*
G01X1554876Y147390D01*
X1554909Y147410D01*
G02X1554979Y147435I101J-173D01*
G01X1555248Y147479D01*
G02X1555392Y147447I32J-198D01*
G01X1555393Y147446D01*
G03X1555857Y147214I1120J1659D01*
G03X1556512Y147104I654J1892D01*
G01X1579740D01*
G02X1579940Y146904I0J-200D01*
G01Y124540D01*
X1579937Y124524D01*
G03X1579918Y124283I1483J-238D01*
G03X1579937Y124042I1502J-3D01*
G01X1579940Y124026D01*
Y120792D01*
G02X1579926Y120718I-200J0D01*
G01X1579888Y120621D01*
X1579864Y120594D01*
G03Y118594I1122J-1000D01*
G01X1579888Y118567D01*
X1579926Y118470D01*
G02X1579940Y118396I-186J-74D01*
G01Y117752D01*
X1579886Y117618D01*
X1579863Y117592D01*
G03X1579484Y116594I1124J-998D01*
G01Y116592D01*
G03X1579788Y115687I1503J1D01*
G02X1579828Y115567I-160J-120D01*
G01Y114421D01*
G02X1579788Y114301I-200J0D01*
G03Y112487I1199J-907D01*
G02X1579828Y112367I-160J-120D01*
G01Y111688D01*
G03X1579858Y111583I200J0D01*
G01X1579909Y111504D01*
G02X1579940Y111396I-169J-107D01*
G01Y109734D01*
G02X1579881Y109592I-200J0D01*
G01X1578938Y108649D01*
G02X1578796Y108590I-142J141D01*
G01X1542124D01*
G02X1541960Y108676I0J200D01*
G03X1538996I-1482J-1027D01*
G02X1538832Y108590I-164J114D01*
G01X1522551D01*
G02X1522409Y108649I0J200D01*
G01X1521350Y109708D01*
X1521325Y109753D01*
X1521318Y109780D01*
G03X1520232Y110866I-1456J-370D01*
G01X1520205Y110873D01*
X1520160Y110898D01*
X1520098Y110960D01*
G02X1520039Y111102I141J142D01*
G01Y114907D01*
X1520126Y115016D01*
X1520195Y115031D01*
G03Y117961I-333J1465D01*
G01X1520126Y117976D01*
X1520039Y118085D01*
Y122963D01*
X1520139Y123076D01*
X1520215Y123085D01*
G03Y126067I-181J1491D01*
G01X1520139Y126076D01*
X1520039Y126189D01*
Y159263D01*
G02X1520098Y159405I200J0D01*
G01X1520961Y160268D01*
G02X1521103Y160327I142J-141D01*
G01X1556620D01*
G03X1556762Y160386I0J200D01*
G01X1560467Y164091D01*
G03X1560526Y164233I-141J142D01*
G01Y201567D01*
G02X1560585Y201709I200J0D01*
G01X1561153Y202277D01*
G02X1561295Y202336I142J-141D01*
G01X1570995D01*
G02X1571172Y202229I0J-200D01*
G01X1571336Y201916D01*
G02X1571325Y201711I-177J-93D01*
G01X1571324Y201710D01*
G03X1571063Y200873I1241J-846D01*
G01Y200845D01*
G03X1574067I1502J19D01*
G01Y200865D01*
G03X1573806Y201711I-1502J0D01*
G01X1573774Y201757D01*
X1573768Y201867D01*
X1573958Y202229D01*
G02X1574135Y202336I177J-93D01*
G37*
G36*
G01X1549515Y1261536D02*
G03X1550700Y1261719I0J3926D01*
G01X1552560Y1262308D01*
G03X1553986Y1263118I-1184J3744D01*
G01X1554002Y1263132D01*
X1554039Y1263154D01*
X1603635Y1278854D01*
G03X1604125Y1279046I-1184J3743D01*
G01X1616099Y1284692D01*
G02X1616111Y1284698I95J-176D01*
G01X1616941Y1285021D01*
G03X1616969Y1285032I-1409J3627D01*
G01X1616970D01*
G03X1616993Y1285042I-1540J3573D01*
G02X1616999Y1285044I66J-189D01*
G03X1617017Y1285051I-1401J3630D01*
G03X1617021Y1285053I-87J179D01*
G03X1617056Y1285067I-1428J3620D01*
G03X1617058Y1285069I-131J133D01*
G03X1617120Y1285096I-1523J3581D01*
G02X1617122Y1285098I133J-131D01*
G01X1674163Y1310691D01*
G02X1674176Y1310696I78J-184D01*
G01X1723191Y1328674D01*
G02X1723260Y1328686I68J-188D01*
G01X1743171D01*
G03X1743313Y1328745I0J200D01*
G01X1761500Y1346932D01*
G03X1761559Y1347074I-141J142D01*
G01Y1406738D01*
G03X1761500Y1406880I-200J0D01*
G01X1736059Y1432321D01*
G02X1736035Y1432349I139J144D01*
G01X1724849Y1448736D01*
G02X1724814Y1448849I165J113D01*
G01Y1545940D01*
G02X1724818Y1545978I200J-2D01*
G02X1724871Y1546080I196J-37D01*
G01X1735710Y1556919D01*
G03X1735769Y1557061I-141J142D01*
G01Y1626133D01*
G03X1735710Y1626275I-200J0D01*
G01X1734075Y1627910D01*
G03X1733933Y1627969I-142J-141D01*
G01X1728613D01*
G02X1728589Y1627970I-4J200D01*
G02X1728475Y1628024I24J199D01*
G01X1728191Y1628309D01*
X1725707Y1630793D01*
G03X1724811Y1631164I-896J-896D01*
G01X1721116D01*
G02X1720981Y1631217I1J200D01*
G03X1720095Y1631564I-887J-960D01*
G01X1648258D01*
G03X1647334Y1631181I0J-1306D01*
G01X1644181Y1628028D01*
G02X1644039Y1627969I-142J141D01*
G01X1633393D01*
G02X1633251Y1628028I0J200D01*
G01X1632375Y1628904D01*
G03X1632233Y1628963I-142J-141D01*
G01X1632190D01*
G02X1631990Y1629163I0J200D01*
G01Y1641353D01*
G02X1632190Y1641553I200J0D01*
G01X1758721D01*
X1758731D01*
G02X1758885Y1641468I-10J-200D01*
G01X1759069Y1641168D01*
G02X1759090Y1641026I-174J-98D01*
G01X1759077Y1640973D01*
X1759068Y1640954D01*
G03X1759066Y1640950I178J-91D01*
G03X1758920Y1640313I1356J-646D01*
G01Y1640293D01*
G03X1761924I1502J10D01*
G01Y1640313D01*
G03X1761778Y1640950I-1502J-9D01*
G03X1761776Y1640954I-180J-87D01*
G01X1761767Y1640973D01*
X1761754Y1641026D01*
G02X1761776Y1641170I195J44D01*
G01X1761953Y1641457D01*
G02X1762026Y1641527I170J-104D01*
G01X1762027Y1641528D01*
G02X1762124Y1641553I97J-175D01*
G01X1766721D01*
X1766731D01*
G02X1766885Y1641468I-10J-200D01*
G01X1767069Y1641168D01*
G02X1767090Y1641026I-174J-98D01*
G01X1767077Y1640973D01*
X1767068Y1640954D01*
G03X1767066Y1640950I178J-91D01*
G03X1766920Y1640313I1356J-646D01*
G01Y1640293D01*
G03X1769924I1502J10D01*
G01Y1640313D01*
G03X1769778Y1640950I-1502J-9D01*
G03X1769776Y1640954I-180J-87D01*
G01X1769767Y1640973D01*
X1769754Y1641026D01*
G02X1769776Y1641170I195J44D01*
G01X1769953Y1641457D01*
G02X1770026Y1641527I170J-104D01*
G01X1770027Y1641528D01*
G02X1770124Y1641553I97J-175D01*
G01X1770721D01*
X1770731D01*
G02X1770885Y1641468I-10J-200D01*
G01X1771069Y1641168D01*
G02X1771090Y1641026I-174J-98D01*
G01X1771077Y1640973D01*
X1771068Y1640954D01*
G03X1771066Y1640950I178J-91D01*
G03X1770920Y1640313I1356J-646D01*
G01Y1640293D01*
G03X1773924I1502J10D01*
G01Y1640313D01*
G03X1773778Y1640950I-1502J-9D01*
G03X1773776Y1640954I-180J-87D01*
G01X1773767Y1640973D01*
X1773754Y1641026D01*
G02X1773775Y1641168I195J44D01*
G01X1773959Y1641468D01*
G02X1774113Y1641553I164J-115D01*
G01X1829864D01*
G02X1830006Y1641494I0J-200D01*
G01X1835841Y1635659D01*
G02X1835900Y1635517I-141J-142D01*
G01Y1316559D01*
G02X1835841Y1316417I-200J0D01*
G01X1829482Y1310058D01*
G02X1829340Y1309999I-142J141D01*
G01X1825272D01*
G02X1825130Y1310058I0J200D01*
G01X1825077Y1310111D01*
G03X1824935Y1310170I-142J-141D01*
G01X1723090D01*
G03X1722948Y1310111I0J-200D01*
G01X1700819Y1287982D01*
G03X1700760Y1287840I141J-142D01*
G01Y1251898D01*
G03X1700775Y1251821I200J-1D01*
G01X1700804Y1251753D01*
G02X1700819Y1251676I-185J-76D01*
G01Y1141596D01*
G02X1700805Y1141521I-200J-1D01*
G01X1700790Y1141485D01*
X1698687Y1139382D01*
G02X1698637Y1139346I-140J142D01*
G02X1698546Y1139324I-91J178D01*
G01X1687822D01*
G02X1687649Y1139425I1J200D01*
G01X1687475Y1139762D01*
X1687456Y1139798D01*
X1687460Y1139854D01*
G02X1687495Y1139954I200J-14D01*
G01X1687496Y1139955D01*
G03X1687717Y1140649I-981J695D01*
G03X1685313I-1202J0D01*
G03X1685534Y1139956I1202J1D01*
G01Y1139954D01*
X1685535D01*
G02X1685570Y1139854I-165J-114D01*
G01X1685574Y1139798D01*
X1685555Y1139762D01*
X1685381Y1139425D01*
G02X1685208Y1139324I-174J99D01*
G01X1684082D01*
G02X1683909Y1139425I1J200D01*
G01X1683735Y1139762D01*
X1683716Y1139798D01*
X1683720Y1139854D01*
G02X1683755Y1139954I200J-14D01*
G01X1683756Y1139955D01*
G03X1683977Y1140649I-981J695D01*
G03X1681573I-1202J0D01*
G03X1681579Y1140533I1202J4D01*
G01Y1140530D01*
G02X1681560Y1140425I-199J-18D01*
G02X1681487Y1140344I-179J88D01*
G01X1681193Y1140157D01*
G02X1681164Y1140142I-106J169D01*
G02X1681033Y1140133I-78J184D01*
G01X1681001Y1140142D01*
G02X1680960Y1140158I52J193D01*
G01X1680952Y1140163D01*
G03X1680461Y1140406I-1916J-3254D01*
G02X1680429Y1140422I73J186D01*
G02X1680403Y1140441I105J171D01*
G02X1680336Y1140598I133J150D01*
G03X1680337Y1140649I-1301J51D01*
G03X1679035Y1141951I-1302J0D01*
G03X1678835Y1141936I-3J-1302D01*
G03X1677747Y1140842I200J-1287D01*
G02X1677610Y1140681I-198J29D01*
G02X1677567Y1140672I-62J190D01*
G03X1677373Y1140650I328J-3762D01*
G01X1677372D01*
G03X1677209Y1140624I513J-3742D01*
G01X1677186Y1140620D01*
X1677139D01*
G03X1676958Y1140650I-708J-3710D01*
G01X1676957D01*
X1676944Y1140652D01*
G03X1676764Y1140672I-507J-3743D01*
G02X1676700Y1140688I16J199D01*
G02X1676583Y1140842I81J183D01*
G03X1675295Y1141951I-1288J-193D01*
G01X1675282D01*
G03X1675062Y1141930I13J-1302D01*
G01X1675056Y1141929D01*
X1675040Y1141927D01*
G02X1674884Y1141979I-20J199D01*
G01X1674883Y1141980D01*
G02X1674819Y1142126I136J147D01*
G01Y1142788D01*
G02X1674878Y1142930I200J0D01*
G01X1674879Y1142931D01*
X1675090Y1143133D01*
G02X1675224Y1143188I138J-145D01*
G01X1675238D01*
G03X1675293Y1143187I49J1201D01*
G01X1675296D01*
G03Y1145591I-1J1202D01*
G01X1675293D01*
G03X1675237Y1145590I-7J-1202D01*
G01X1675196Y1145588D01*
X1675158Y1145603D01*
G02X1675091Y1145645I71J187D01*
G01X1674881Y1145845D01*
G02X1674819Y1145989I138J145D01*
G01Y1150268D01*
G02X1674878Y1150410I200J0D01*
G01X1674879Y1150411D01*
X1675090Y1150613D01*
G02X1675224Y1150668I138J-145D01*
G01X1675238D01*
G03X1675293Y1150667I49J1201D01*
G01X1675296D01*
G03Y1153071I-1J1202D01*
G01X1675293D01*
G03X1675237Y1153070I-7J-1202D01*
G01X1675196Y1153068D01*
X1675158Y1153083D01*
G02X1675091Y1153125I71J187D01*
G01X1674881Y1153325D01*
G02X1674819Y1153469I138J145D01*
G01Y1157749D01*
G02X1674878Y1157891I200J0D01*
G01X1674879Y1157892D01*
X1675090Y1158094D01*
G02X1675224Y1158149I138J-145D01*
G01X1675238D01*
G03X1675293Y1158148I49J1201D01*
G01X1675296D01*
G03Y1160552I-1J1202D01*
G01X1675293D01*
G03X1675237Y1160551I-7J-1202D01*
G01X1675196Y1160549D01*
X1675158Y1160564D01*
G02X1675091Y1160606I71J187D01*
G01X1674881Y1160806D01*
G02X1674819Y1160950I138J145D01*
G01Y1165229D01*
G02X1674878Y1165371I200J0D01*
G01X1674879Y1165372D01*
X1675090Y1165574D01*
G02X1675224Y1165629I138J-145D01*
G01X1675238D01*
G03X1675293Y1165628I49J1201D01*
G01X1675296D01*
G03Y1168032I-1J1202D01*
G01X1675293D01*
G03X1675237Y1168031I-7J-1202D01*
G01X1675196Y1168029D01*
X1675158Y1168044D01*
G02X1675091Y1168086I71J187D01*
G01X1674881Y1168286D01*
G02X1674819Y1168430I138J145D01*
G01Y1172709D01*
G02X1674878Y1172851I200J0D01*
G01X1674879Y1172852D01*
X1675090Y1173054D01*
G02X1675224Y1173109I138J-145D01*
G01X1675238D01*
G03X1675293Y1173108I49J1201D01*
G01X1675296D01*
G03Y1175512I-1J1202D01*
G01X1675293D01*
G03X1675237Y1175511I-7J-1202D01*
G01X1675196Y1175509D01*
X1675158Y1175524D01*
G02X1675091Y1175566I71J187D01*
G01X1674881Y1175766D01*
G02X1674819Y1175910I138J145D01*
G01Y1180190D01*
G02X1674878Y1180332I200J0D01*
G01X1674879Y1180333D01*
X1675090Y1180535D01*
G02X1675224Y1180590I138J-145D01*
G01X1675238D01*
G03X1675293Y1180589I49J1201D01*
G01X1675296D01*
G03Y1182993I-1J1202D01*
G01X1675293D01*
G03X1675237Y1182992I-7J-1202D01*
G01X1675196Y1182990D01*
X1675158Y1183005D01*
G02X1675091Y1183047I71J187D01*
G01X1674881Y1183247D01*
G02X1674819Y1183391I138J145D01*
G01Y1187670D01*
G02X1674878Y1187812I200J0D01*
G01X1674879Y1187813D01*
X1675090Y1188015D01*
G02X1675224Y1188070I138J-145D01*
G01X1675238D01*
G03X1675293Y1188069I49J1201D01*
G01X1675296D01*
G03Y1190473I-1J1202D01*
G01X1675293D01*
G03X1675237Y1190472I-7J-1202D01*
G01X1675196Y1190470D01*
X1675158Y1190485D01*
G02X1675091Y1190527I71J187D01*
G01X1674881Y1190727D01*
G02X1674819Y1190871I138J145D01*
G01Y1195150D01*
G02X1674878Y1195292I200J0D01*
G01X1674879Y1195293D01*
X1675090Y1195495D01*
G02X1675224Y1195550I138J-145D01*
G01X1675238D01*
G03X1675293Y1195549I49J1201D01*
G01X1675296D01*
G03Y1197953I-1J1202D01*
G01X1675293D01*
G03X1675237Y1197952I-7J-1202D01*
G01X1675196Y1197950D01*
X1675158Y1197965D01*
G02X1675091Y1198007I71J187D01*
G01X1674881Y1198207D01*
G02X1674819Y1198351I138J145D01*
G01Y1202530D01*
G02X1674830Y1202595I200J0D01*
G02X1674875Y1202669I189J-64D01*
G01X1675003Y1202792D01*
X1675089Y1202875D01*
G02X1675156Y1202918I139J-144D01*
G01X1675194Y1202932D01*
X1675236Y1202930D01*
G03X1675256Y1202929I75J1300D01*
G01X1675258D01*
G03X1675295Y1202928I54J1301D01*
G01X1675485D01*
G02X1675634Y1202862I1J-200D01*
G01X1675833Y1202642D01*
G02X1675884Y1202490I-148J-134D01*
G01Y1202489D01*
G03X1675878Y1202362I1281J-124D01*
G03X1678452I1287J0D01*
G03X1678446Y1202488I-1287J2D01*
G01Y1202490D01*
G02X1678497Y1202642I199J18D01*
G01X1678696Y1202862D01*
G02X1678845Y1202928I148J-134D01*
G01X1679035D01*
G03Y1205534I0J1303D01*
G01X1675295D01*
G03X1675270Y1205533I40J-1302D01*
G01X1675266D01*
G03X1675236Y1205532I28J-1302D01*
G01X1675194Y1205530D01*
X1675156Y1205544D01*
G02X1675089Y1205587I72J187D01*
G01X1674881Y1205787D01*
G02X1674819Y1205931I138J145D01*
G01Y1210010D01*
G02X1674830Y1210075I200J0D01*
G02X1674875Y1210149I189J-64D01*
G01X1675003Y1210272D01*
X1675089Y1210355D01*
G02X1675156Y1210398I139J-144D01*
G01X1675194Y1210412D01*
X1675236Y1210410D01*
G03X1675256Y1210409I75J1300D01*
G01X1675258D01*
G03X1675295Y1210408I54J1301D01*
G01X1675485D01*
G02X1675634Y1210342I1J-200D01*
G01X1675833Y1210122D01*
G02X1675884Y1209970I-148J-134D01*
G01Y1209969D01*
G03X1675878Y1209842I1281J-124D01*
G03X1678452I1287J0D01*
G03X1678446Y1209968I-1287J2D01*
G01Y1209970D01*
G02X1678497Y1210122I199J18D01*
G01X1678696Y1210342D01*
G02X1678845Y1210408I148J-134D01*
G01X1679035D01*
G03Y1213014I0J1303D01*
G01X1675295D01*
G03X1675270Y1213013I40J-1302D01*
G01X1675266D01*
G03X1675236Y1213012I28J-1302D01*
G01X1675194Y1213010D01*
X1675156Y1213024D01*
G02X1675089Y1213067I72J187D01*
G01X1674881Y1213267D01*
G02X1674819Y1213411I138J145D01*
G01Y1217491D01*
G02X1674830Y1217556I200J0D01*
G02X1674875Y1217630I189J-64D01*
G01X1675015Y1217765D01*
X1675089Y1217836D01*
G02X1675156Y1217878I138J-145D01*
G01X1675194Y1217893D01*
X1675236Y1217891D01*
G03X1675294Y1217890I51J1301D01*
G01X1675486D01*
G02X1675635Y1217824I1J-200D01*
G01X1675833Y1217605D01*
G02X1675884Y1217451I-148J-134D01*
G01Y1217450D01*
G03X1675878Y1217322I1281J-124D01*
G03X1678452I1287J0D01*
G03X1678446Y1217450I-1287J4D01*
G01Y1217451D01*
G02X1678497Y1217605I199J20D01*
G01X1678695Y1217824D01*
G02X1678844Y1217890I148J-134D01*
G01X1679035D01*
G03Y1220494I0J1302D01*
G01X1675296D01*
X1675294D01*
G03X1675236Y1220493I-7J-1302D01*
G01X1675194Y1220491D01*
X1675156Y1220505D01*
G02X1675089Y1220548I72J187D01*
G01X1674881Y1220748D01*
G02X1674819Y1220892I138J145D01*
G01Y1223086D01*
G03X1674760Y1223228I-200J0D01*
G01X1672916Y1225073D01*
G02X1672878Y1225127I142J140D01*
G02X1672858Y1225214I180J87D01*
G01Y1226672D01*
G03X1672207Y1227800I-1303J0D01*
G03X1671555Y1227974I-650J-1128D01*
G03X1671408Y1227966I-3J-1303D01*
G01X1671363Y1227961D01*
X1671277Y1227990D01*
X1671023Y1228243D01*
G02X1670965Y1228405I141J142D01*
G01Y1228406D01*
G03X1670972Y1228543I-1280J134D01*
G03X1669685Y1229830I-1287J0D01*
G03X1668535Y1229122I0J-1288D01*
G01X1668510Y1229071D01*
X1668414Y1229012D01*
X1667233D01*
X1667136Y1229072D01*
X1667111Y1229123D01*
G03X1664779I-1166J-581D01*
G01X1664754Y1229072D01*
X1664657Y1229012D01*
X1663475D01*
X1663379Y1229071D01*
X1663354Y1229122D01*
G03X1661054I-1150J-580D01*
G01X1661029Y1229071D01*
X1660933Y1229012D01*
X1659752D01*
X1659655Y1229072D01*
X1659630Y1229123D01*
G03X1657298I-1166J-581D01*
G01X1657273Y1229072D01*
X1657176Y1229012D01*
X1655956D01*
G02X1655780Y1229117I0J200D01*
G03X1653668I-1056J-574D01*
G02X1653492Y1229012I-176J95D01*
G01X1652272D01*
X1652175Y1229072D01*
X1652150Y1229123D01*
G03X1649818I-1166J-581D01*
G01X1649793Y1229072D01*
X1649696Y1229012D01*
X1648476D01*
G02X1648300Y1229117I0J200D01*
G03X1646188I-1056J-574D01*
G02X1646012Y1229012I-176J95D01*
G01X1644792D01*
X1644695Y1229072D01*
X1644670Y1229123D01*
G03X1642338I-1166J-581D01*
G01X1642313Y1229072D01*
X1642216Y1229012D01*
X1640995D01*
G02X1640819Y1229117I0J200D01*
G03X1638707I-1056J-574D01*
G02X1638531Y1229012I-176J95D01*
G01X1637311D01*
X1637214Y1229072D01*
X1637189Y1229123D01*
G03X1634857I-1166J-581D01*
G01X1634832Y1229072D01*
X1634735Y1229012D01*
X1633515D01*
G02X1633339Y1229117I0J200D01*
G03X1631227I-1056J-574D01*
G02X1631051Y1229012I-176J95D01*
G01X1629831D01*
X1629734Y1229072D01*
X1629709Y1229123D01*
G03X1627377I-1166J-581D01*
G01X1627352Y1229072D01*
X1627255Y1229012D01*
X1626074D01*
X1625978Y1229071D01*
X1625953Y1229122D01*
G03X1623653I-1150J-580D01*
G01X1623628Y1229071D01*
X1623532Y1229012D01*
X1622351D01*
X1622254Y1229072D01*
X1622229Y1229123D01*
G03X1619897I-1166J-581D01*
G01X1619872Y1229072D01*
X1619775Y1229012D01*
X1618593D01*
X1618497Y1229071D01*
X1618472Y1229122D01*
G03X1616172I-1150J-580D01*
G01X1616147Y1229071D01*
X1616051Y1229012D01*
X1614870D01*
X1614773Y1229072D01*
X1614748Y1229123D01*
G03X1612416I-1166J-581D01*
G01X1612391Y1229072D01*
X1612294Y1229012D01*
X1611113D01*
X1611017Y1229071D01*
X1610992Y1229122D01*
G03X1608692I-1150J-580D01*
G01X1608667Y1229071D01*
X1608571Y1229012D01*
X1607390D01*
X1607293Y1229072D01*
X1607268Y1229123D01*
G03X1604936I-1166J-581D01*
G01X1604911Y1229072D01*
X1604814Y1229012D01*
X1603633D01*
X1603537Y1229071D01*
X1603512Y1229122D01*
G03X1601212I-1150J-580D01*
G01X1601187Y1229071D01*
X1601091Y1229012D01*
X1599910D01*
X1599813Y1229072D01*
X1599788Y1229123D01*
G03X1597456I-1166J-581D01*
G01X1597431Y1229072D01*
X1597334Y1229012D01*
X1596153D01*
X1596057Y1229071D01*
X1596032Y1229122D01*
G03X1593732I-1150J-580D01*
G01X1593707Y1229071D01*
X1593611Y1229012D01*
X1592429D01*
X1592332Y1229072D01*
X1592307Y1229123D01*
G03X1589975I-1166J-581D01*
G01X1589950Y1229072D01*
X1589853Y1229012D01*
X1588672D01*
X1588576Y1229071D01*
X1588551Y1229122D01*
G03X1586251I-1150J-580D01*
G01X1586226Y1229071D01*
X1586130Y1229012D01*
X1584949D01*
X1584852Y1229072D01*
X1584827Y1229123D01*
G03X1582495I-1166J-581D01*
G01X1582470Y1229072D01*
X1582373Y1229012D01*
X1581192D01*
X1581096Y1229071D01*
X1581071Y1229122D01*
G03X1578771I-1150J-580D01*
G01X1578746Y1229071D01*
X1578650Y1229012D01*
X1577469D01*
X1577372Y1229072D01*
X1577347Y1229123D01*
G03X1575015I-1166J-581D01*
G01X1574990Y1229072D01*
X1574893Y1229012D01*
X1573712D01*
X1573616Y1229071D01*
X1573591Y1229122D01*
G03X1571291I-1150J-580D01*
G01X1571266Y1229071D01*
X1571170Y1229012D01*
X1569988D01*
X1569891Y1229072D01*
X1569866Y1229123D01*
G03X1567534I-1166J-581D01*
G01X1567509Y1229072D01*
X1567412Y1229012D01*
X1566192D01*
G02X1566016Y1229117I0J200D01*
G03X1563904I-1056J-574D01*
G02X1563728Y1229012I-176J95D01*
G01X1562508D01*
X1562411Y1229072D01*
X1562386Y1229123D01*
G03X1560054I-1166J-581D01*
G01X1560029Y1229072D01*
X1559932Y1229012D01*
X1558712D01*
G02X1558536Y1229117I0J200D01*
G03X1556424I-1056J-574D01*
G02X1556248Y1229012I-176J95D01*
G01X1555028D01*
X1554931Y1229072D01*
X1554906Y1229123D01*
G03X1552574I-1166J-581D01*
G01X1552549Y1229072D01*
X1552452Y1229012D01*
X1551232D01*
G02X1551056Y1229117I0J200D01*
G03X1548944I-1056J-574D01*
G02X1548768Y1229012I-176J95D01*
G01X1547547D01*
X1547450Y1229072D01*
X1547425Y1229123D01*
G03X1545093I-1166J-581D01*
G01X1545068Y1229072D01*
X1544971Y1229012D01*
X1543751D01*
G02X1543575Y1229117I0J200D01*
G03X1541463I-1056J-574D01*
G02X1541287Y1229012I-176J95D01*
G01X1540067D01*
X1539970Y1229072D01*
X1539945Y1229123D01*
G03X1537613I-1166J-581D01*
G01X1537588Y1229072D01*
X1537491Y1229012D01*
X1536271D01*
G02X1536095Y1229117I0J200D01*
G03X1533983I-1056J-574D01*
G02X1533807Y1229012I-176J95D01*
G01X1532587D01*
X1532490Y1229072D01*
X1532465Y1229123D01*
G03X1530133I-1166J-581D01*
G01X1530108Y1229072D01*
X1530011Y1229012D01*
X1528791D01*
G02X1528615Y1229117I0J200D01*
G03X1526503I-1056J-574D01*
G02X1526327Y1229012I-176J95D01*
G01X1525107D01*
X1525010Y1229072D01*
X1524985Y1229123D01*
G03X1522653I-1166J-581D01*
G01X1522628Y1229072D01*
X1522531Y1229012D01*
X1521310D01*
G02X1521134Y1229117I0J200D01*
G03X1520078Y1229745I-1056J-574D01*
G03X1519688Y1229680I0J-1201D01*
G02X1519658Y1229672I-66J189D01*
G01X1519607Y1229663D01*
G02X1519407Y1229863I0J200D01*
G01X1519418Y1229919D01*
G02X1519427Y1229953I197J-34D01*
G03X1519440Y1229989I-1219J460D01*
G03X1519510Y1230408I-1232J421D01*
G01Y1230409D01*
G03Y1230411I-1302J1D01*
G01X1519511Y1230440D01*
G03X1518209Y1231716I-1303J-27D01*
G01X1514836D01*
G02X1514636Y1231916I0J200D01*
G01Y1236696D01*
Y1236698D01*
G03X1514635Y1236816I-3926J26D01*
G01X1514535Y1240125D01*
G02X1514591Y1240270I200J6D01*
G01X1514618Y1240298D01*
X1514693Y1240330D01*
X1514745D01*
G02X1514894Y1240264I0J-200D01*
G01X1515093Y1240043D01*
G02X1515143Y1239889I-149J-134D01*
G01Y1239888D01*
G03X1515136Y1239763I1195J-130D01*
G03X1517540I1202J0D01*
G03X1517533Y1239887I-1202J-6D01*
G01Y1239889D01*
G02X1517583Y1240043I199J20D01*
G01X1517782Y1240264D01*
G02X1517931Y1240330I149J-134D01*
G01X1518210D01*
G03X1518435Y1240350I-2J1303D01*
G01X1518437D01*
X1518469Y1240355D01*
X1518558Y1240328D01*
X1518824Y1240073D01*
G02X1518885Y1239907I-138J-145D01*
G01Y1239906D01*
G03X1518876Y1239763I1193J-147D01*
G03X1520078Y1240965I1202J0D01*
G03X1519935Y1240956I4J-1202D01*
G01X1519934D01*
G02X1519766Y1241016I-24J199D01*
G01X1519512Y1241282D01*
X1519484Y1241371D01*
X1519488Y1241397D01*
G03X1519510Y1241633I-1281J238D01*
G03X1518207Y1242936I-1303J0D01*
G01X1517794D01*
X1517791D01*
G02X1517598Y1243176I3J200D01*
G02X1517600Y1243185I196J-39D01*
G03X1517618Y1243266I-1261J323D01*
G02X1517798Y1243429I197J-36D01*
G03X1518172Y1243479I-319J3814D01*
G02X1518244I36J-197D01*
G03X1518618Y1243429I693J3764D01*
G02X1518798Y1243266I-17J-199D01*
G03X1520078Y1242201I1280J237D01*
G03X1521380Y1243503I0J1302D01*
G01Y1243507D01*
G02X1521505Y1243692I200J0D01*
G03X1521938Y1243898I-1425J3553D01*
G02X1522153Y1243885I97J-175D01*
G03X1522184Y1243863I2201J3069D01*
G01X1522205Y1243848D01*
X1522268Y1243773D01*
X1522279Y1243750D01*
G03X1522511Y1243332I3411J1620D01*
G02X1522540Y1243261I-167J-110D01*
G03X1523577Y1242224I1279J242D01*
G02X1523648Y1242195I-39J-196D01*
G03X1523990Y1242000I2039J3179D01*
G02X1524082Y1241905I-90J-179D01*
G03X1524411Y1241327I3478J1597D01*
G02X1524439Y1241269I-164J-115D01*
G03X1525325Y1240382I1251J363D01*
G02X1525383Y1240355I-54J-192D01*
G03X1526132Y1239952I2177J3148D01*
G02X1526257Y1239767I-75J-185D01*
G01Y1239763D01*
G03X1528861I1302J0D01*
G01Y1239767D01*
G02X1528986Y1239952I200J0D01*
G03X1530265Y1240797I-1427J3550D01*
G01X1530266Y1240798D01*
G03X1531031Y1241894I-2707J2704D01*
G02X1531148Y1241999I181J-84D01*
G01X1531264Y1242038D01*
G02X1531421Y1242026I64J-189D01*
G03X1531467Y1242002I1770J3336D01*
G03X1531471Y1242000I1691J3377D01*
G02X1531561Y1241906I-92J-178D01*
G03X1531891Y1241327I3477J1598D01*
G02X1531919Y1241269I-164J-115D01*
G03X1532805Y1240382I1251J363D01*
G02X1532863Y1240355I-54J-192D01*
G03X1533612Y1239952I2177J3148D01*
G02X1533737Y1239767I-75J-185D01*
G01Y1239763D01*
G03X1536341I1302J0D01*
G01Y1239767D01*
G02X1536466Y1239952I200J0D01*
G03X1537745Y1240797I-1427J3550D01*
G01X1537746Y1240798D01*
G03X1538590Y1242076I-2706J2705D01*
G02X1538775Y1242201I185J-75D01*
G01X1538779D01*
G03X1540081Y1243503I0J1302D01*
G03X1539016Y1244783I-1302J0D01*
G02X1538853Y1244963I36J197D01*
G03X1538804Y1245337I-3814J-309D01*
G02Y1245409I196J36D01*
G03X1538853Y1245783I-3765J683D01*
G02X1539016Y1245963I199J-17D01*
G03X1539095Y1245980I-234J1281D01*
G02X1539344Y1245786I49J-194D01*
G01Y1245373D01*
G03X1540647Y1244070I1303J0D01*
G01X1540648D01*
G03X1540874Y1244090I-1J1303D01*
G01X1540876D01*
X1540910Y1244096D01*
X1540999Y1244068D01*
X1541265Y1243813D01*
G02X1541326Y1243647I-138J-145D01*
G01Y1243646D01*
G03X1541317Y1243503I1193J-147D01*
G03X1542519Y1244705I1202J0D01*
G03X1542375Y1244696I3J-1202D01*
G01X1542374D01*
G02X1542206Y1244756I-24J199D01*
G01X1541952Y1245022D01*
X1541924Y1245111D01*
X1541928Y1245137D01*
G03X1541950Y1245373I-1281J238D01*
G01Y1245650D01*
G02X1542016Y1245799I200J0D01*
G01X1542270Y1246026D01*
X1542350Y1246052D01*
X1542392Y1246048D01*
G03X1542519Y1246041I130J1195D01*
G03Y1248445I0J1202D01*
G01X1542517D01*
G03X1542203Y1248403I1J-1202D01*
G01X1542177Y1248396D01*
X1542150D01*
G02X1541950Y1248596I0J200D01*
G01Y1248811D01*
X1541967Y1248866D01*
X1541983Y1248891D01*
G03X1542330Y1249557I-3204J2093D01*
G02X1542515Y1249682I185J-75D01*
G01X1542519D01*
G03X1543821Y1250984I0J1302D01*
G03X1542756Y1252264I-1302J0D01*
G02X1542593Y1252444I36J197D01*
G03X1542543Y1252818I-3814J-319D01*
G02Y1252890I197J36D01*
G03X1542593Y1253264I-3764J693D01*
G02X1542756Y1253444I199J-17D01*
G03X1543821Y1254724I-237J1280D01*
G03X1542519Y1256026I-1302J0D01*
G01X1542515D01*
G02X1542330Y1256151I0J200D01*
G03X1541927Y1256900I-3551J-1428D01*
G02X1541900Y1256958I165J112D01*
G03X1541534Y1257549I-1250J-365D01*
G03X1541287Y1257729I-885J-955D01*
G02X1541199Y1257830I98J174D01*
G01X1541156Y1257941D01*
G02X1541154Y1258082I186J73D01*
G03X1541369Y1259017I-3690J1341D01*
G01X1541375Y1259076D01*
X1541451Y1259168D01*
X1549024Y1261566D01*
X1549066Y1261561D01*
G03X1549515Y1261536I442J3901D01*
G37*
G36*
G01X1611280Y54588D02*
X1639405D01*
X1639599Y54394D01*
Y52785D01*
X1639405Y52591D01*
X1611280D01*
G03X1605343Y46654I0J-5937D01*
G01Y7874D01*
G02X1599469Y2000I-5874J0D01*
G01X1552224D01*
G02X1546350Y7874I0J5874D01*
G01Y46654D01*
G03X1545263Y50079I-5939J0D01*
G01Y50191D01*
X1545272Y50200D01*
X1547511D01*
G02X1548348Y46654I-7097J-3547D01*
G01Y7874D01*
G03X1552224Y3998I3876J0D01*
G01X1599469D01*
G03X1603346Y7874I0J3877D01*
G01Y46654D01*
G02X1611280Y54588I7934J0D01*
G37*
G36*
G01X1556932Y275932D02*
X1578867D01*
X1578941Y275902D01*
X1578969Y275873D01*
X1579580Y275262D01*
G02X1579639Y275120I-141J-142D01*
G01Y205020D01*
X1579609Y204946D01*
X1579580Y204918D01*
X1578059Y203397D01*
G02X1577917Y203338I-142J141D01*
G01X1557050D01*
X1556976Y203368D01*
X1556948Y203397D01*
X1556790Y203555D01*
G02X1556732Y203696I142J141D01*
G01Y204858D01*
G02X1556792Y205001I200J0D01*
G01X1557026Y205230D01*
X1557100Y205259D01*
X1557140Y205258D01*
X1557174D01*
G03Y208262I0J1502D01*
G01X1557140D01*
X1557100Y208261D01*
X1557026Y208290D01*
X1556792Y208519D01*
G02X1556732Y208661I140J143D01*
G01Y255107D01*
G02X1556850Y255289I200J0D01*
G01X1557174Y255436D01*
G02X1557345Y255432I81J-183D01*
G01X1557395Y255407D01*
X1557414Y255392D01*
G03X1558388Y255033I975J1143D01*
G03Y258037I0J1502D01*
G03X1557414Y257678I1J-1502D01*
G01X1557395Y257663D01*
X1557345Y257638D01*
G02X1557174Y257634I-90J179D01*
G01X1556850Y257781D01*
G02X1556732Y257963I82J182D01*
G01Y275732D01*
G02X1556932Y275932I200J0D01*
G37*
G36*
G01X1592461Y242420D02*
G03X1592598Y242428I-2J1210D01*
G01X1592610Y242429D01*
X1595771D01*
X1595783Y242428D01*
G03X1595919Y242420I139J1202D01*
G01X1600383D01*
G02X1600419Y242417I1J-200D01*
G01X1600436Y242414D01*
G02X1600539Y242361I-36J-197D01*
G01X1600728Y242180D01*
G02X1600789Y242046I-139J-144D01*
G01Y242042D01*
G03X1601189Y241077I1501J57D01*
G01X1601191Y241075D01*
X1601194Y241072D01*
G03X1601200Y241065I1143J974D01*
G01X1601202Y241063D01*
X1601207Y241057D01*
G03X1602309Y240576I1102J1022D01*
G03X1603811Y242057I0J1502D01*
G01X1603812Y242098D01*
X1603843Y242170D01*
X1604017Y242338D01*
X1604040Y242360D01*
G02X1604144Y242414I140J-143D01*
G01X1604179Y242420D01*
X1608044D01*
G03X1608185Y242428I2J1210D01*
G01X1611587D01*
G03X1611728Y242420I139J1202D01*
G01X1618320D01*
G02X1618415Y242396I0J-200D01*
G01X1618441Y242382D01*
X1620915Y239908D01*
X1620927Y239895D01*
X1620968Y239854D01*
G02X1620991Y239762I-177J-93D01*
G01Y153175D01*
G02X1620988Y153139I-200J-1D01*
G01X1620977Y153081D01*
X1620944Y153023D01*
X1620918Y153000D01*
G03X1620614Y147733I2440J-2783D01*
G01X1620632Y147713D01*
X1620633Y147711D01*
G03X1620823Y147517I2738J2492D01*
G03X1620876Y147469I2511J2719D01*
G01X1620877Y147468D01*
G03X1620894Y147452I2545J2687D01*
G01X1620910Y147437D01*
X1620934Y147404D01*
X1620974Y147312D01*
G02X1620991Y147232I-183J-81D01*
G01Y125108D01*
X1620980Y125076D01*
G03X1620894Y124576I1416J-501D01*
G03X1620980Y124076I1502J1D01*
G01X1620991Y124044D01*
Y122986D01*
G03X1621006Y122910I200J0D01*
G01X1621026Y122863D01*
G02X1621041Y122786I-185J-76D01*
G01Y117488D01*
G02X1621004Y117371I-200J-1D01*
G03X1620722Y116496I1220J-876D01*
G03X1621004Y115621I1502J1D01*
G02X1621041Y115504I-163J-116D01*
G01Y110681D01*
G03X1621054Y110611I200J1D01*
G02X1621066Y110527I-188J-70D01*
G01X1621057Y110411D01*
G02X1621018Y110306I-199J14D01*
G03X1620722Y109410I1206J-895D01*
G03X1622224Y107908I1502J0D01*
G03X1623156Y108232I0J1502D01*
G01X1623217Y108280D01*
X1623367Y108272D01*
X1623971Y107668D01*
G03X1624113Y107609I142J141D01*
G01X1624689D01*
X1624706Y107606D01*
G03X1624786Y107595I204J1184D01*
G01X1624787D01*
G03X1624911Y107588I130J1195D01*
G01X1640838D01*
G02X1641038Y107402I0J-200D01*
G01Y104249D01*
G03X1641069Y103915I1802J-1D01*
G01X1641074Y103886D01*
X1641068Y103829D01*
X1641057Y103802D01*
G02X1640986Y103713I-185J75D01*
G01X1640955Y103692D01*
G02X1640750Y103678I-114J164D01*
G03X1640063Y103845I-688J-1333D01*
G03X1638561Y102343I0J-1502D01*
G03X1638982Y101300I1502J0D01*
G01X1638985Y101297D01*
X1638987Y101295D01*
G03X1640082Y100821I1095J1028D01*
G03X1641582Y102242I0J1502D01*
G01Y102244D01*
G02X1641676Y102401I199J-13D01*
G01X1641994Y102601D01*
X1642091Y102608D01*
X1642136Y102589D01*
G03X1642838Y102446I704J1660D01*
G01X1642909D01*
X1642933Y102449D01*
X1642939D01*
G03X1644642Y104249I-100J1800D01*
G01Y107402D01*
G02X1644842Y107588I200J-14D01*
G01X1681086D01*
G02X1681226Y107531I0J-200D01*
G01X1681227Y107530D01*
X1682641Y106116D01*
G02X1682700Y105974I-141J-142D01*
G01Y94814D01*
X1682688Y94781D01*
G03X1682602Y94280I1416J-501D01*
G01Y94279D01*
G03X1682688Y93778I1502J0D01*
G01X1682700Y93744D01*
Y87557D01*
X1682633Y87457D01*
X1682577Y87433D01*
G03Y84659I574J-1387D01*
G01X1682633Y84635D01*
X1682700Y84535D01*
Y62345D01*
Y62331D01*
X1682693Y62237D01*
X1682584Y62139D01*
G03X1682576Y62131I137J-145D01*
G01X1682417Y61971D01*
X1682346Y61941D01*
X1682306Y61940D01*
G03X1681227Y61457I25J-1502D01*
G01X1681197Y61425D01*
X1681118Y61392D01*
X1680730Y61402D01*
X1680653Y61439D01*
X1680625Y61473D01*
G03X1679470Y62015I-1155J-960D01*
G03Y59011I0J-1502D01*
G03X1680573Y59494I0J1501D01*
G01X1680603Y59526D01*
X1680682Y59559D01*
X1681070Y59549D01*
X1681147Y59512D01*
X1681175Y59478D01*
G03X1682306Y58936I1155J960D01*
G01X1682345D01*
X1682418Y58905D01*
X1682593Y58728D01*
X1682642Y58678D01*
G02X1682699Y58552I-142J-140D01*
G01X1682700Y58538D01*
Y54060D01*
G02X1682641Y53918I-200J0D01*
G01X1681439Y52716D01*
G02X1681297Y52657I-142J141D01*
G01X1662767D01*
G02X1662625Y52716I0J200D01*
G01X1657484Y57857D01*
G03X1657387Y57911I-142J-141D01*
G01X1657349Y57920D01*
X1657288Y57962D01*
X1657062Y58297D01*
X1657052Y58395D01*
X1657071Y58442D01*
G03X1657693Y61614I-7780J3173D01*
G03X1657691Y61814I-8402J16D01*
G01Y61815D01*
X1657690Y61834D01*
G03X1655335Y67451I-8399J-219D01*
G01X1655317Y67469D01*
X1655257Y67530D01*
G03X1649272Y70036I-5986J-5896D01*
G03X1640870Y61634I0J-8402D01*
G03X1641483Y58485I8402J1D01*
G01X1641490Y58467D01*
X1641498Y58425D01*
G02X1641468Y58275I-196J-39D01*
G01X1641285Y58004D01*
G02X1641119Y57916I-166J112D01*
G01X1633974D01*
G02X1633796Y58026I1J200D01*
G01X1633623Y58367D01*
X1633632Y58479D01*
X1633665Y58525D01*
G03X1634376Y60583I-2988J2184D01*
G01Y60584D01*
X1634379Y60639D01*
Y60709D01*
G03X1633935Y62466I-3702J-1D01*
G01X1633911Y62511D01*
Y62611D01*
X1634101Y62963D01*
X1634185Y63018D01*
X1634236Y63022D01*
G03X1636649Y69456I-319J3789D01*
G01X1636648Y69457D01*
G03X1632429Y70338I-2750J-2626D01*
G03X1630549Y65032I1469J-3507D01*
G01X1630550Y65029D01*
X1630556Y65017D01*
X1630562Y65003D01*
G02X1630547Y64817I-184J-79D01*
G01X1630544Y64813D01*
X1630374Y64528D01*
G02X1630202Y64430I-172J102D01*
G01X1623358D01*
G03X1619657Y60729I0J-3701D01*
G01Y60727D01*
G03X1620365Y58552I3701J2D01*
G01X1620398Y58505D01*
X1620407Y58395D01*
X1620194Y57974D01*
X1620099Y57916D01*
X1583345D01*
G02X1583203Y57975I0J200D01*
G01X1582438Y58740D01*
G02X1582397Y58962I142J141D01*
G01Y58963D01*
X1582547Y59302D01*
G02X1582628Y59393I183J-81D01*
G01X1582656Y59410D01*
X1582712Y59424D01*
X1582741Y59422D01*
X1582747D01*
G03X1582822Y59420I78J1500D01*
G03Y62424I0J1502D01*
G03X1582140Y62260I0J-1502D01*
G01X1582093Y62236D01*
X1581990Y62240D01*
X1581654Y62446D01*
G02X1581559Y62616I105J170D01*
G01Y84598D01*
G02X1581582Y84691I200J0D01*
G01X1581634Y84790D01*
X1581663Y84824D01*
X1581681Y84837D01*
G03Y87255I-891J1209D01*
G01X1581663Y87268D01*
X1581634Y87302D01*
X1581582Y87401D01*
G02X1581559Y87494I177J93D01*
G01Y92495D01*
G02X1581617Y92636I200J0D01*
G01X1581727Y92747D01*
X1581793Y92777D01*
X1581831Y92780D01*
G03X1583244Y94279I-89J1499D01*
G01X1583245D01*
G03X1581873Y95776I-1503J0D01*
G01X1581829Y95779D01*
X1581792Y95798D01*
G02X1581737Y95840I92J178D01*
G01X1581553Y96039D01*
G02X1581500Y96175I147J136D01*
G01Y108877D01*
G02X1581613Y109058I200J1D01*
G01X1581614D01*
G03X1582159Y109500I-648J1355D01*
G01X1582168Y109512D01*
X1582178Y109522D01*
X1582190Y109534D01*
G02X1582302Y109590I141J-142D01*
G01X1582346Y109597D01*
X1582613Y109636D01*
X1582690Y109616D01*
X1582722Y109591D01*
G03X1583635Y109282I913J1194D01*
G03X1584922Y110009I0J1503D01*
G01X1584936Y110031D01*
X1584970Y110066D01*
X1585072Y110125D01*
G02X1585112Y110143I101J-172D01*
G02X1585149Y110152I66J-189D01*
G02X1585173Y110153I20J-199D01*
G01X1585384D01*
G02X1585481Y110128I0J-200D01*
G01X1585582Y110072D01*
X1585618Y110037D01*
X1585632Y110015D01*
G03X1585831Y109759I1279J789D01*
G01X1585833Y109757D01*
X1585835Y109755D01*
G03X1586929Y109282I1094J1029D01*
G03X1588431Y110784I0J1502D01*
G03X1588010Y111827I-1502J0D01*
G01X1588007Y111830D01*
X1588000Y111837D01*
G03X1586910Y112306I-1090J-1032D01*
G03X1585609Y111555I0J-1502D01*
G02X1585436Y111455I-173J100D01*
G01X1585097D01*
G02X1584925Y111553I0J200D01*
G03X1584729Y111813I-1290J-769D01*
G01X1584726Y111816D01*
X1584722Y111821D01*
G03X1584719Y111824I-1064J-1061D01*
G01X1584718Y111825D01*
G03X1583616Y112306I-1102J-1022D01*
G03X1582424Y111718I0J-1502D01*
G01X1582415Y111706D01*
X1582405Y111696D01*
X1582393Y111684D01*
G02X1582281Y111628I-141J142D01*
G01X1582027Y111590D01*
G02X1581934Y111598I-30J198D01*
G01X1581857Y111624D01*
X1581834Y111640D01*
G03X1581811Y111655I-832J-1250D01*
G01X1581791Y111669D01*
X1581774Y111688D01*
G02X1581746Y111727I147J135D01*
G01X1581701Y111809D01*
G02X1581677Y111904I176J95D01*
G01Y111924D01*
G02X1581702Y112021I200J0D01*
G01X1581719Y112051D01*
G02X1581785Y112122I175J-97D01*
G01X1581787Y112123D01*
X1581788D01*
G03X1582488Y113394I-804J1271D01*
G03X1582083Y114420I-1502J0D01*
G01X1582081Y114422D01*
X1582078Y114426D01*
G03X1582073Y114431I-1065J-1060D01*
G03X1582071Y114433I-142J-140D01*
G03X1581614Y114770I-1104J-1019D01*
G01X1581561Y114795D01*
X1581500Y114892D01*
Y115049D01*
G02X1581616Y115231I200J0D01*
G03X1582488Y116594I-629J1363D01*
G03X1582068Y117636I-1503J0D01*
G01X1582066Y117638D01*
X1582064Y117640D01*
G03X1581890Y117799I-1097J-1026D01*
G02X1581813Y117957I123J158D01*
G01Y118190D01*
G02X1581834Y118278I200J-1D01*
G01X1581881Y118374D01*
X1581908Y118408D01*
X1581925Y118421D01*
G03X1582488Y119594I-940J1173D01*
G03X1582083Y120620I-1502J0D01*
G01X1582081Y120622D01*
X1582078Y120626D01*
G03X1582073Y120631I-1065J-1060D01*
G03X1582071Y120633I-142J-140D01*
G03X1581614Y120970I-1104J-1019D01*
G01X1581561Y120995D01*
X1581500Y121092D01*
Y122677D01*
X1581595Y122789D01*
X1581667Y122801D01*
G03X1582506Y125321I-247J1482D01*
G01X1582504Y125323D01*
X1582502Y125326D01*
G03X1581665Y125782I-1100J-1023D01*
G01X1581593Y125795D01*
X1581500Y125905D01*
Y131939D01*
G02X1581611Y132118I200J0D01*
G01X1581616Y132121D01*
X1581956Y132267D01*
G02X1582074Y132280I80J-183D01*
G01X1582105Y132274D01*
X1582156Y132247D01*
X1582177Y132226D01*
G03X1583229Y131796I1052J1072D01*
G03X1584667Y132865I0J1502D01*
G01X1584678Y132901D01*
X1584723Y132959D01*
X1584983Y133115D01*
X1585015Y133121D01*
G03X1585376Y133077I361J1459D01*
G03X1586878Y134579I0J1502D01*
G03X1586457Y135622I-1502J0D01*
G01X1586454Y135625D01*
X1586447Y135632D01*
G03X1585357Y136101I-1090J-1032D01*
G03X1583929Y135066I0J-1503D01*
G01X1583928Y135064D01*
G02X1583841Y134955I-190J62D01*
G01X1583584Y134802D01*
X1583514Y134789D01*
X1583478Y134796D01*
G03X1583211Y134820I-267J-1478D01*
G01X1583210D01*
G03X1582175Y134407I0J-1503D01*
G01X1582131Y134366D01*
X1582014Y134345D01*
X1581621Y134513D01*
G02X1581500Y134697I79J184D01*
G01Y167050D01*
G02X1581536Y167163I200J-1D01*
G01Y167164D01*
G02X1581635Y167239I164J-114D01*
G01X1581637Y167240D01*
G03X1582664Y168665I-475J1425D01*
G03X1582241Y169710I-1502J0D01*
G01X1582238Y169713D01*
X1582236Y169715D01*
G03X1581646Y170100I-1093J-1030D01*
G01X1581635Y170104D01*
X1581611Y170116D01*
G02X1581500Y170295I89J179D01*
G01Y171050D01*
G02X1581536Y171163I200J-1D01*
G01Y171164D01*
G02X1581635Y171239I164J-114D01*
G01X1581637Y171240D01*
G03X1582664Y172665I-475J1425D01*
G03X1582241Y173710I-1502J0D01*
G01X1582238Y173713D01*
X1582236Y173715D01*
G03X1581646Y174100I-1093J-1030D01*
G01X1581635Y174104D01*
X1581611Y174116D01*
G02X1581500Y174295I89J179D01*
G01Y175050D01*
G02X1581536Y175163I200J-1D01*
G01Y175164D01*
G02X1581635Y175239I164J-114D01*
G01X1581637Y175240D01*
G03X1582664Y176665I-475J1425D01*
G03X1582241Y177710I-1502J0D01*
G01X1582238Y177713D01*
X1582236Y177715D01*
G03X1581646Y178100I-1093J-1030D01*
G01X1581635Y178104D01*
X1581611Y178116D01*
G02X1581500Y178295I89J179D01*
G01Y179050D01*
G02X1581536Y179163I200J-1D01*
G01Y179164D01*
G02X1581635Y179239I164J-114D01*
G01X1581637Y179240D01*
G03X1582664Y180665I-475J1425D01*
G03X1582241Y181710I-1502J0D01*
G01X1582238Y181713D01*
X1582236Y181715D01*
G03X1581646Y182100I-1093J-1030D01*
G01X1581635Y182104D01*
X1581611Y182116D01*
G02X1581500Y182295I89J179D01*
G01Y185199D01*
X1581583Y185306D01*
X1581650Y185324D01*
G03X1582777Y186778I-374J1454D01*
G03X1582764Y186978I-1502J3D01*
G01X1582763Y186988D01*
G03X1582356Y187821I-1488J-211D01*
G01X1582354Y187823D01*
X1582347Y187831D01*
G03X1581650Y188247I-1090J-1034D01*
G01X1581648Y188248D01*
X1581643Y188250D01*
G02X1581500Y188441I57J192D01*
G01Y191050D01*
G02X1581536Y191163I200J-1D01*
G01Y191164D01*
G02X1581635Y191239I164J-114D01*
G01X1581637Y191240D01*
G03X1582664Y192665I-475J1425D01*
G03X1582241Y193710I-1502J0D01*
G01X1582238Y193713D01*
X1582236Y193715D01*
G03X1581646Y194100I-1093J-1030D01*
G01X1581635Y194104D01*
X1581611Y194116D01*
G02X1581500Y194295I89J179D01*
G01Y195050D01*
G02X1581536Y195163I200J-1D01*
G01Y195164D01*
G02X1581635Y195239I164J-114D01*
G01X1581637Y195240D01*
G03X1582664Y196665I-475J1425D01*
G03X1582241Y197710I-1502J0D01*
G01X1582238Y197713D01*
X1582236Y197715D01*
G03X1581646Y198100I-1093J-1030D01*
G01X1581635Y198104D01*
X1581611Y198116D01*
G02X1581500Y198295I89J179D01*
G01Y199305D01*
X1581577Y199410D01*
X1581641Y199430D01*
G03X1582696Y200864I-447J1434D01*
G03X1582277Y201905I-1503J0D01*
G01X1582274Y201908D01*
X1582272Y201910D01*
G03X1581638Y202313I-1097J-1026D01*
G01X1581608Y202323D01*
X1581557Y202359D01*
X1581539Y202385D01*
G02X1581500Y202503I161J119D01*
G01Y203305D01*
X1581577Y203410D01*
X1581641Y203430D01*
G03X1582696Y204864I-447J1434D01*
G03X1582277Y205905I-1503J0D01*
G01X1582274Y205908D01*
X1582272Y205910D01*
G03X1581638Y206313I-1097J-1026D01*
G01X1581608Y206323D01*
X1581557Y206359D01*
X1581539Y206385D01*
G02X1581500Y206503I161J119D01*
G01Y207305D01*
X1581577Y207410D01*
X1581641Y207430D01*
G03X1582696Y208864I-447J1434D01*
G03X1582277Y209905I-1503J0D01*
G01X1582274Y209908D01*
X1582272Y209910D01*
G03X1581638Y210313I-1097J-1026D01*
G01X1581608Y210323D01*
X1581557Y210359D01*
X1581539Y210385D01*
G02X1581500Y210503I161J119D01*
G01Y211305D01*
X1581577Y211410D01*
X1581641Y211430D01*
G03X1582696Y212864I-447J1434D01*
G03X1582277Y213905I-1503J0D01*
G01X1582274Y213908D01*
X1582272Y213910D01*
G03X1581638Y214313I-1097J-1026D01*
G01X1581608Y214323D01*
X1581557Y214359D01*
X1581539Y214385D01*
G02X1581500Y214503I161J119D01*
G01Y215305D01*
X1581577Y215410D01*
X1581641Y215430D01*
G03X1582696Y216864I-447J1434D01*
G03X1582277Y217905I-1503J0D01*
G01X1582274Y217908D01*
X1582272Y217910D01*
G03X1581638Y218313I-1097J-1026D01*
G01X1581608Y218323D01*
X1581557Y218359D01*
X1581539Y218385D01*
G02X1581500Y218503I161J119D01*
G01Y220305D01*
X1581577Y220410D01*
X1581641Y220430D01*
G03X1582696Y221864I-447J1434D01*
G03X1582277Y222905I-1503J0D01*
G01X1582274Y222908D01*
X1582272Y222910D01*
G03X1581638Y223313I-1097J-1026D01*
G01X1581608Y223323D01*
X1581557Y223359D01*
X1581539Y223385D01*
G02X1581500Y223503I161J119D01*
G01Y241469D01*
G02X1581559Y241611I200J0D01*
G01X1582342Y242394D01*
X1582421Y242424D01*
X1582464Y242422D01*
G03X1582527Y242420I70J1208D01*
G01X1592461D01*
G37*
G36*
G01X1581633Y276294D02*
X1656607D01*
G02X1656749Y276235I0J-200D01*
G01X1658033Y274951D01*
G02X1658035Y274949I-140J-142D01*
G02X1658092Y274809I-143J-140D01*
G01Y267385D01*
G02X1657979Y267205I-200J0D01*
G01X1657602Y267023D01*
X1657489Y267036D01*
X1657443Y267072D01*
G03X1656509Y267398I-934J-1175D01*
G03Y264394I0J-1502D01*
G03X1657443Y264720I0J1501D01*
G01X1657489Y264756D01*
X1657602Y264769D01*
X1657979Y264587D01*
G02X1658092Y264407I-87J-180D01*
G01Y257901D01*
X1658038Y257809D01*
X1657993Y257782D01*
X1657991D01*
X1657703Y257613D01*
G02X1657549Y257593I-101J173D01*
G01X1657495Y257608D01*
X1657473Y257620D01*
G03X1656751Y257805I-723J-1319D01*
G01X1656750D01*
G03Y254801I0J-1502D01*
G01X1656751D01*
G03X1657473Y254986I-1J1504D01*
G01X1657495Y254998D01*
X1657549Y255013D01*
G02X1657703Y254993I53J-193D01*
G01X1657992Y254824D01*
G02X1657995Y254822I-109J-167D01*
G02X1658092Y254651I-103J-171D01*
G01Y207177D01*
X1658085Y207152D01*
G03X1658034Y206763I1451J-388D01*
G01Y206755D01*
G03X1658085Y206372I1502J5D01*
G01X1658092Y206346D01*
Y202582D01*
G03X1658151Y202440I200J0D01*
G01X1658572Y202019D01*
G03X1658714Y201960I142J141D01*
G01X1661432D01*
G02X1661465Y201957I-2J-200D01*
G02X1661572Y201903I-32J-197D01*
G01X1661827Y201648D01*
G02X1661829Y201646I-140J-142D01*
G02X1661886Y201506I-143J-140D01*
G01Y193725D01*
G02X1661800Y193561I-200J0D01*
G01X1661550Y193386D01*
G02X1661436Y193350I-114J164D01*
G01X1661349D01*
X1661318Y193361D01*
G03X1660828Y193443I-490J-1420D01*
G01X1660812D01*
G03X1659326Y191941I16J-1502D01*
G03X1660828Y190439I1502J0D01*
G01X1660831D01*
G03X1661349Y190532I-2J1502D01*
G01X1661395Y190549D01*
X1661492Y190537D01*
X1661800Y190321D01*
G02X1661886Y190157I-114J-164D01*
G01Y165175D01*
G02X1661827Y165033I-200J0D01*
G01X1658361Y161567D01*
X1658333Y161538D01*
X1658259Y161508D01*
X1651245D01*
G02X1651074Y161604I0J200D01*
G01X1650897Y161896D01*
G02X1650881Y161930I172J102D01*
G02X1650892Y162094I188J70D01*
G01X1650895Y162100D01*
X1650912Y162135D01*
G03X1651064Y162788I-1350J658D01*
G01Y162790D01*
Y162815D01*
G03X1650661Y163817I-1502J-22D01*
G01X1650660Y163818D01*
G02X1650604Y163957I144J139D01*
G01Y164268D01*
X1650631Y164338D01*
X1650658Y164366D01*
G03Y166420I-1096J1027D01*
G01X1650631Y166448D01*
X1650604Y166518D01*
Y166868D01*
X1650631Y166938D01*
X1650658Y166966D01*
G03X1651064Y167993I-1096J1027D01*
G03X1650694Y168980I-1501J0D01*
G01X1650670Y169008D01*
X1650645Y169074D01*
Y169412D01*
X1650670Y169478D01*
X1650694Y169506D01*
G03X1651064Y170493I-1131J987D01*
G03X1648060I-1502J0D01*
G03X1648430Y169506I1501J0D01*
G01X1648454Y169478D01*
X1648479Y169412D01*
Y169074D01*
X1648454Y169008D01*
X1648430Y168980D01*
G03X1648060Y167993I1131J-987D01*
G03X1648466Y166966I1502J0D01*
G01X1648493Y166938D01*
X1648520Y166868D01*
Y166518D01*
X1648493Y166448D01*
X1648466Y166420D01*
G03Y164366I1096J-1027D01*
G01X1648493Y164338D01*
X1648520Y164268D01*
Y163918D01*
X1648493Y163849D01*
X1648466Y163820D01*
G03X1648060Y162821I1096J-1027D01*
G01Y162793D01*
G03X1648212Y162134I1502J-1D01*
G01X1648241Y162073D01*
G02X1648243Y161930I-186J-74D01*
G02X1648227Y161896I-188J68D01*
G01X1648050Y161605D01*
X1648023Y161559D01*
X1647932Y161508D01*
X1644308D01*
G02X1644150Y161585I0J200D01*
G01X1643927Y161870D01*
X1643908Y161959D01*
X1643919Y162005D01*
G03X1643964Y162368I-1457J365D01*
G03X1642462Y163870I-1502J0D01*
G03X1641435Y163464I0J-1502D01*
G01X1641407Y163437D01*
X1641337Y163410D01*
X1640987D01*
X1640917Y163437D01*
X1640889Y163464D01*
G03X1639862Y163870I-1027J-1096D01*
G03X1638360Y162368I0J-1502D01*
G03X1638405Y162005I1502J2D01*
G01X1638416Y161959D01*
X1638397Y161870D01*
X1638174Y161585D01*
G02X1638016Y161508I-158J123D01*
G01X1622868D01*
G02X1622726Y161567I0J200D01*
G01X1622070Y162223D01*
G02X1622012Y162364I142J141D01*
G01Y240157D01*
G03X1621953Y240298I-200J-1D01*
G01X1621656Y240595D01*
X1621654Y240598D01*
G03X1621641Y240611I-856J-843D01*
G01X1621640Y240612D01*
X1619173Y243079D01*
G03X1619147Y243104I-845J-853D01*
G01X1619145Y243106D01*
X1618899Y243352D01*
G03X1618759Y243410I-141J-142D01*
G01X1618543D01*
X1618526Y243413D01*
G03X1618325Y243430I-201J-1185D01*
G01X1611730D01*
G02X1611572Y243507I0J200D01*
G01X1611349Y243793D01*
X1611330Y243882D01*
X1611342Y243928D01*
G03X1611388Y244297I-1457J369D01*
G03X1609886Y245799I-1502J0D01*
G03X1609519Y245753I2J-1502D01*
G01X1609463Y245739D01*
X1609356Y245773D01*
X1609048Y246131D01*
X1609030Y246242D01*
X1609052Y246295D01*
G03X1609168Y246874I-1387J579D01*
G03X1607666Y248376I-1502J0D01*
G03X1606637Y247968I0J-1502D01*
G01X1606603Y247936D01*
X1606517Y247909D01*
X1606163Y247958D01*
G02X1606155Y247959I21J199D01*
G02X1606018Y248055I36J197D01*
G03X1604724Y248794I-1294J-763D01*
G03Y245790I0J-1502D01*
G03X1605753Y246198I0J1502D01*
G01X1605787Y246230D01*
X1605873Y246257D01*
X1606227Y246208D01*
G02X1606234Y246207I-25J-198D01*
G02X1606375Y246106I-35J-197D01*
G03X1606378Y246100I180J86D01*
G03X1607666Y245372I1288J775D01*
G03X1607745Y245374I1J1502D01*
G01X1607746D01*
G03X1607808Y245378I-66J1501D01*
G01X1607842Y245382D01*
G03X1607924Y245394I-176J1492D01*
G01X1607925D01*
G03X1608033Y245418I-272J1477D01*
G01X1608089Y245432D01*
X1608196Y245398D01*
X1608504Y245040D01*
X1608521Y244930D01*
X1608499Y244876D01*
G03X1608393Y244474I1387J-581D01*
G01X1608388Y244419D01*
G03X1608383Y244297I1498J-122D01*
G01Y244295D01*
G03X1608429Y243927I1503J1D01*
G01X1608441Y243881D01*
X1608422Y243792D01*
X1608200Y243507D01*
G02X1608042Y243430I-158J123D01*
G01X1604190D01*
G03X1603991Y243413I2J-1201D01*
G01X1603974Y243410D01*
X1603027D01*
X1602981Y243422D01*
X1602962Y243431D01*
X1602960Y243432D01*
G03X1602309Y243580I-650J-1354D01*
G01X1602278D01*
G03X1601654Y243430I31J-1502D01*
G01X1601634Y243420D01*
X1601590Y243410D01*
X1600606D01*
X1600589Y243413D01*
G03X1600390Y243430I-201J-1184D01*
G01X1595921D01*
G02X1595754Y243520I0J200D01*
G01X1595583Y243781D01*
G02X1595567Y243971I167J110D01*
G03X1595692Y244571I-1377J600D01*
G01Y244590D01*
G03X1592688I-1502J-19D01*
G01Y244570D01*
G03X1592813Y243971I1502J1D01*
G01X1592832Y243928D01*
X1592828Y243838D01*
X1592807Y243797D01*
G02X1592797Y243781I-175J98D01*
G01X1592627Y243521D01*
X1592599Y243478D01*
X1592511Y243430D01*
X1582529D01*
G02X1582387Y243489I0J200D01*
G01X1580798Y245078D01*
X1580769Y245106D01*
X1580739Y245180D01*
Y275400D01*
G02X1580796Y275540I200J0D01*
G01X1580797Y275541D01*
X1581491Y276235D01*
G02X1581493Y276237I142J-140D01*
G02X1581633Y276294I140J-143D01*
G37*
G36*
G01X1631879Y478533D02*
G03X1632865Y478164I986J1133D01*
G03X1633065Y478177I3J1502D01*
G03X1634349Y479429I-200J1489D01*
G01X1634355Y479472D01*
X1634400Y479544D01*
X1634717Y479754D01*
X1634799Y479769D01*
X1634840Y479759D01*
G03X1635264Y479708I426J1751D01*
G01X1635265D01*
G03X1635689Y479759I-2J1802D01*
G01X1635731Y479769D01*
X1635812Y479754D01*
X1636130Y479544D01*
X1636174Y479474D01*
X1636181Y479432D01*
G03X1637665Y478163I1484J233D01*
G03Y481167I0J1502D01*
G01X1637664D01*
G03X1637406Y481145I-2J-1502D01*
G01X1637397Y481143D01*
X1637377Y481141D01*
G02X1637231Y481189I-15J200D01*
G01X1637100Y481302D01*
X1637064Y481386D01*
X1637066Y481432D01*
G03X1637068Y481510I-1801J85D01*
G01Y484910D01*
G03X1637066Y484982I-1803J-14D01*
G01Y484995D01*
G02X1637136Y485147I200J0D01*
G01X1637198Y485200D01*
X1637201Y485203D01*
X1637230Y485228D01*
G02X1637397Y485274I131J-151D01*
G03X1637664Y485250I267J1478D01*
G01X1637673D01*
G03X1639167Y486752I-8J1502D01*
G03X1637665Y488254I-1502J0D01*
G03X1636182Y486989I0J-1502D01*
G01Y486988D01*
X1636175Y486945D01*
X1636152Y486910D01*
G02X1636095Y486852I-168J108D01*
G01X1635813Y486665D01*
X1635732Y486651D01*
X1635691Y486661D01*
G03X1635600Y486681I-432J-1750D01*
G01X1635545Y486692D01*
X1635463Y486765D01*
X1635342Y487156D01*
G02X1635392Y487357I191J59D01*
G01X1638548Y490513D01*
G02X1638690Y490572I142J-141D01*
G01X1643854D01*
G02X1644020Y490483I0J-200D01*
G01X1644233Y490162D01*
X1644242Y490064D01*
X1644222Y490017D01*
G03X1644105Y489439I1385J-581D01*
G01Y489417D01*
G03X1647109I1502J18D01*
G01Y489437D01*
G03X1646992Y490017I-1502J-1D01*
G01X1646972Y490064D01*
X1646981Y490162D01*
X1647194Y490483D01*
G02X1647360Y490572I166J-111D01*
G01X1698838D01*
G02X1698948Y490539I0J-200D01*
G01X1699002Y490504D01*
X1699040Y490459D01*
X1699052Y490430D01*
G03X1699078Y490372I3595J1577D01*
G02X1699077Y490209I-183J-80D01*
G03X1698728Y488591I3578J-1618D01*
G03X1698736Y488342I3927J2D01*
G02X1698727Y488269I-200J-12D01*
G03X1698670Y488015I1432J-455D01*
G02X1698537Y487852I-198J26D01*
G03X1698073Y487660I1266J-3717D01*
G01X1695106D01*
G02X1694967Y487716I0J200D01*
G03X1692253Y488806I-2715J-2837D01*
G03X1688889Y486904I0J-3926D01*
G02X1688840Y486848I-172J101D01*
G03X1688254Y485657I917J-1191D01*
G01X1688255Y485620D01*
G03X1688302Y485283I1502J38D01*
G03X1688325Y485202I1456J370D01*
G02X1688334Y485129I-191J-61D01*
G03X1688326Y484879I3919J-251D01*
G03X1688675Y483261I3927J0D01*
G02Y483097I-182J-82D01*
G03X1688326Y481479I3578J-1618D01*
G03X1688334Y481229I3927J1D01*
G02X1688325Y481156I-200J-12D01*
G03X1688261Y480839I1432J-454D01*
G01Y480837D01*
X1688258Y480811D01*
G03X1688254Y480702I1499J-110D01*
G01Y480701D01*
G03X1688840Y479510I1503J0D01*
G02X1688889Y479454I-123J-157D01*
G03X1692253Y477552I3364J2024D01*
G03X1694967Y478642I-1J3927D01*
G02X1695106Y478698I139J-144D01*
G01X1698540D01*
X1698655Y478589D01*
X1698660Y478510D01*
G03X1698668Y478418I1499J84D01*
G01Y478417D01*
G03X1698688Y478292I1492J175D01*
G03X1698727Y478142I1471J302D01*
G02X1698736Y478069I-191J-61D01*
G03X1698728Y477818I3919J-251D01*
G03X1699077Y476200I3927J0D01*
G02Y476036I-182J-82D01*
G03X1698728Y474418I3578J-1618D01*
G03X1698735Y474204I3926J21D01*
G02X1698724Y474127I-200J-11D01*
G03X1698722Y474121I1436J-482D01*
G01X1698712Y474093D01*
X1698678Y474045D01*
X1698561Y473956D01*
X1698504Y473936D01*
X1698472Y473934D01*
G03X1697693Y473826I142J-3889D01*
G03X1697068Y473616I922J-3780D01*
G02X1697063Y473614I-77J185D01*
G03X1696859Y473526I1453J-3648D01*
G01X1696818Y473507D01*
X1696817D01*
X1696777Y473488D01*
X1695105D01*
X1695098D01*
G02X1694987Y473526I7J200D01*
G02X1694966Y473543I115J164D01*
G03X1692254Y474632I-2714J-2837D01*
G01X1692253D01*
G03X1688889Y472731I0J-3927D01*
G02X1688840Y472675I-172J101D01*
G03X1688254Y471489I917J-1191D01*
G01X1688255Y471447D01*
G03X1688302Y471110I1502J38D01*
G03X1688325Y471029I1456J370D01*
G02X1688334Y470956I-191J-61D01*
G03X1688326Y470706I3919J-251D01*
G03X1688675Y469088I3927J0D01*
G02Y468924I-182J-82D01*
G03X1688326Y467306I3578J-1618D01*
G03X1688334Y467056I3927J1D01*
G02X1688325Y466983I-200J-12D01*
G03X1688261Y466666I1432J-454D01*
G01Y466664D01*
X1688258Y466638D01*
G03X1688254Y466529I1499J-110D01*
G01Y466528D01*
G03X1688840Y465337I1503J0D01*
G02X1688889Y465281I-123J-157D01*
G03X1692253Y463380I3364J2026D01*
G01X1692254D01*
G03X1694966Y464469I-2J3926D01*
G02X1694987Y464486I136J-147D01*
G02X1695098Y464524I118J-162D01*
G01X1702842D01*
G03X1705023Y465186I-1J3927D01*
G01X1716613Y472929D01*
G03X1718060Y474691I-2180J3266D01*
G01X1723370Y487513D01*
G02X1723517Y487633I185J-77D01*
G01X1723519D01*
X1723553Y487639D01*
X1723648Y487656D01*
G02X1723830Y487595I35J-197D01*
G03X1724930Y487116I1100J1024D01*
G03X1726432Y488618I0J1502D01*
G03X1726063Y489604I-1502J0D01*
G01X1726062Y489605D01*
X1726061Y489606D01*
G02X1726013Y489736I152J130D01*
G01Y489999D01*
G02X1726025Y490067I200J0D01*
G01X1726038Y490104D01*
X1726063Y490132D01*
G03X1726280Y490460I-1133J986D01*
G01X1726306Y490512D01*
X1726402Y490572D01*
X1727205D01*
G02X1727255Y490566I1J-200D01*
G01X1727324Y490548D01*
X1727345Y490537D01*
G03X1728731I693J1333D01*
G01X1728752Y490548D01*
X1728821Y490566D01*
G02X1728871Y490572I49J-194D01*
G01X1729705D01*
G02X1729755Y490566I1J-200D01*
G01X1729824Y490548D01*
X1729845Y490537D01*
G03X1731231I693J1333D01*
G01X1731252Y490548D01*
X1731321Y490566D01*
G02X1731371Y490572I49J-194D01*
G01X1734693D01*
G02X1734839Y490509I0J-200D01*
G01X1735038Y490298D01*
G02X1735092Y490152I-146J-137D01*
G01Y490151D01*
G03X1735090Y490070I1500J-78D01*
G03X1735459Y489084I1502J0D01*
G01X1735460Y489083D01*
X1735461Y489082D01*
G02X1735509Y488952I-152J-130D01*
G01Y488689D01*
G02X1735497Y488621I-200J0D01*
G01X1735484Y488584D01*
X1735459Y488556D01*
G03X1735090Y487570I1133J-986D01*
G03X1738094I1502J0D01*
G03X1737725Y488556I-1502J0D01*
G01X1737724Y488557D01*
X1737723Y488558D01*
G02X1737675Y488688I152J130D01*
G01Y488951D01*
G02X1737687Y489019I200J0D01*
G01X1737700Y489056D01*
X1737725Y489084D01*
G03X1738094Y490070I-1133J986D01*
G03X1738092Y490151I-1502J3D01*
G01Y490152D01*
G02X1738146Y490298I200J9D01*
G01X1738345Y490509D01*
G02X1738393Y490547I147J-136D01*
G01X1738394D01*
G02X1738491Y490572I97J-175D01*
G01X1743705D01*
G02X1743884Y490462I0J-200D01*
G01X1744044Y490142D01*
G02X1744026Y489933I-178J-90D01*
G03X1743729Y489036I1206J-897D01*
G03X1745231Y487534I1502J0D01*
G03X1746723Y488860I0J1502D01*
G01X1746729Y488916D01*
G03X1746734Y489036I-1498J123D01*
G03X1746452Y489912I-1503J0D01*
G01X1746435Y489935D01*
G02X1746418Y490143I162J118D01*
G01X1746456Y490219D01*
X1746578Y490462D01*
G02X1746757Y490572I179J-90D01*
G01X1768466D01*
G02X1768593Y490527I1J-200D01*
G01Y490526D01*
G02X1768662Y490415I-126J-155D01*
G01X1768663Y490412D01*
Y490410D01*
G03X1771607Y490411I1472J301D01*
G01X1771614Y490445D01*
X1771648Y490502D01*
X1771674Y490525D01*
G02X1771804Y490572I129J-153D01*
G01X1781917D01*
G02X1782059Y490513I0J-200D01*
G01X1791768Y480804D01*
G02X1791827Y480662I-141J-142D01*
G01Y475836D01*
G02X1791702Y475651I-200J0D01*
G01X1791522Y475578D01*
X1791301Y475489D01*
X1791182Y475515D01*
X1791139Y475559D01*
G03X1790061Y476015I-1078J-1046D01*
G03Y473011I0J-1502D01*
G03X1791139Y473467I0J1502D01*
G01X1791140Y473468D01*
X1791141Y473469D01*
X1791183Y473512D01*
X1791302Y473537D01*
X1791702Y473375D01*
G02X1791827Y473190I-75J-185D01*
G01Y469880D01*
G02X1791719Y469703I-200J0D01*
G01X1791708Y469697D01*
X1791367Y469565D01*
G02X1791295Y469552I-71J187D01*
G01X1791231D01*
X1791154Y469586D01*
X1791125Y469617D01*
G03X1790014Y470109I-1111J-1008D01*
G03Y467105I0J-1502D01*
G03X1791130Y467602I0J1501D01*
G01X1791172Y467649D01*
X1791292Y467677D01*
X1791698Y467521D01*
G02X1791718Y467512I-72J-187D01*
G01X1791719Y467511D01*
G02X1791827Y467334I-92J-177D01*
G01Y454295D01*
G02X1791802Y454198I-200J0D01*
G01X1791746Y454098D01*
X1791713Y454062D01*
X1791693Y454049D01*
G03Y451549I834J-1250D01*
G01X1791713Y451536D01*
X1791746Y451500D01*
X1791802Y451400D01*
G02X1791827Y451303I-175J-97D01*
G01Y403057D01*
G02X1791707Y402874I-200J0D01*
G01X1791371Y402728D01*
G02X1791156Y402764I-80J183D01*
G03X1790136Y403163I-1020J-1104D01*
G03X1788634Y401661I0J-1502D01*
G03X1789003Y400675I1502J0D01*
G01X1789004Y400674D01*
X1789005Y400673D01*
G02X1789053Y400543I-152J-130D01*
G01Y400280D01*
G02X1789041Y400212I-200J0D01*
G01X1789028Y400175D01*
X1789003Y400147D01*
G03Y398175I1132J-986D01*
G01X1789004Y398174D01*
X1789005Y398173D01*
G02X1789053Y398043I-152J-130D01*
G01Y397780D01*
G02X1789041Y397712I-200J0D01*
G01X1789028Y397675D01*
X1789003Y397647D01*
G03X1788634Y396661I1133J-986D01*
G03X1790136Y395159I1502J0D01*
G03X1791156Y395558I0J1503D01*
G02X1791316Y395610I136J-147D01*
G01X1791345Y395606D01*
X1791707Y395448D01*
G02X1791827Y395265I-80J-183D01*
G01Y305428D01*
G02X1791730Y305257I-200J0D01*
G01X1791436Y305081D01*
G02X1791240Y305076I-102J171D01*
G01X1791239D01*
G03X1790534Y305252I-706J-1326D01*
G01X1790511D01*
G03X1789195Y304433I22J-1502D01*
G02X1789056Y304339I-171J103D01*
G01X1788765Y304275D01*
G02X1788680I-43J196D01*
G01X1788633Y304285D01*
G03X1787674Y304632I-960J-1153D01*
G03Y301628I0J-1502D01*
G03X1789012Y302447I0J1502D01*
G02X1789151Y302541I171J-103D01*
G01X1789442Y302605D01*
G02X1789527I42J-196D01*
G01X1789574Y302595D01*
G03X1790533Y302248I960J1153D01*
G01X1790534D01*
G03X1791239Y302424I-1J1502D01*
G01X1791286Y302449D01*
X1791390Y302446D01*
X1791730Y302243D01*
G02X1791827Y302072I-103J-171D01*
G01Y299912D01*
G02X1791768Y299770I-200J0D01*
G01X1788759Y296761D01*
G02X1788617Y296702I-142J141D01*
G01X1592666D01*
X1592654Y296704D01*
G03X1592541Y296713I-153J-1205D01*
G01X1592539D01*
G03X1592497Y296714I-50J-1213D01*
G01X1592166D01*
G02X1592149Y296721I68J188D01*
G01X1589102Y299768D01*
X1589092Y299779D01*
X1589041Y299830D01*
G02X1589036Y299842I182J83D01*
G01Y440918D01*
G02X1589095Y441060I200J0D01*
G01X1604293Y456258D01*
G02X1604575I141J-142D01*
G01X1624141Y436692D01*
G03X1624185Y436649I1634J1628D01*
G01X1624188Y436647D01*
X1624190Y436645D01*
X1624222Y436614D01*
X1624254Y436530D01*
X1624245Y436413D01*
G02X1624187Y436289I-199J18D01*
G01X1624159Y436261D01*
X1624146Y436252D01*
G03X1623516Y435029I872J-1223D01*
G03X1626520I1502J0D01*
G03X1626377Y435668I-1502J-1D01*
G01X1626359Y435706D01*
X1626357Y435788D01*
X1626461Y436049D01*
G02X1626577Y436162I186J-74D01*
G03X1628078Y438323I-805J2161D01*
G01Y438324D01*
G03X1627403Y439954I-2306J0D01*
G01X1625325Y442031D01*
G02X1625289Y442264I141J141D01*
G01Y442265D01*
G03X1625457Y442955I-1334J690D01*
G01Y442956D01*
G03X1623955Y444458I-1502J0D01*
G01X1623954D01*
G03X1623263Y444290I-1J-1502D01*
G01X1623205Y444259D01*
X1623077Y444279D01*
X1608553Y458804D01*
X1608524Y458832D01*
X1608494Y458906D01*
Y460375D01*
G02X1608553Y460517I200J0D01*
G01X1615806Y467771D01*
X1615816Y467782D01*
X1615828Y467791D01*
G03X1615951Y467898I-734J967D01*
G01X1617149Y469096D01*
G02X1617367Y469139I141J-142D01*
G01X1617423Y469116D01*
X1617490Y469016D01*
Y467461D01*
G03X1617872Y466539I1306J1D01*
G01X1618920Y465491D01*
X1618945Y465450D01*
X1618952Y465427D01*
G03X1620385Y464372I1433J446D01*
G03X1621887Y465874I0J1502D01*
G03X1620832Y467307I-1501J0D01*
G01X1620808Y467315D01*
X1620768Y467339D01*
X1620161Y467945D01*
X1620132Y467973D01*
X1620102Y468047D01*
Y471984D01*
G02X1620161Y472126I200J0D01*
G01X1625821Y477786D01*
G02X1626039Y477829I141J-142D01*
G01X1626095Y477806D01*
X1626162Y477706D01*
Y474424D01*
G03X1626164Y474345I1803J6D01*
G02X1626084Y474175I-200J-10D01*
G01X1626002Y474104D01*
G02X1625960Y474075I-134J149D01*
G01X1625958D01*
G02X1625834Y474057I-89J179D01*
G03X1625566Y474081I-267J-1478D01*
G01X1625557D01*
G03X1624063Y472579I8J-1502D01*
G03X1625565Y471077I1502J0D01*
G03X1627049Y472346I0J1502D01*
G01X1627056Y472388D01*
X1627100Y472458D01*
X1627418Y472668D01*
X1627499Y472683D01*
X1627541Y472673D01*
G03X1627965Y472622I426J1751D01*
G03X1628389Y472673I-2J1802D01*
G01X1628431Y472683D01*
X1628512Y472668D01*
X1628830Y472458D01*
X1628874Y472388D01*
X1628881Y472346D01*
G03X1630365Y471077I1484J233D01*
G03X1631351Y471446I0J1502D01*
G02X1631353Y471448I142J-140D01*
G02X1631483Y471496I130J-152D01*
G01X1631746D01*
G02X1631814Y471484I0J-200D01*
G01X1631851Y471471D01*
X1631879Y471446D01*
G03X1632865Y471077I986J1133D01*
G01X1632866D01*
G03X1633132Y471101I-1J1502D01*
G01X1633177Y471109D01*
X1633264Y471085D01*
X1633430Y470942D01*
X1633466Y470858D01*
X1633464Y470812D01*
G03X1633462Y470737I1801J-86D01*
G01Y467337D01*
G03X1633464Y467258I1803J6D01*
G02X1633384Y467088I-200J-10D01*
G01X1633302Y467017D01*
G02X1633260Y466988I-134J149D01*
G01X1633258D01*
G02X1633134Y466970I-89J179D01*
G03X1632866Y466994I-267J-1478D01*
G01X1632857D01*
G03X1631363Y465492I8J-1502D01*
G03X1632865Y463990I1502J0D01*
G03X1634349Y465257I0J1503D01*
G01X1634355Y465298D01*
X1634400Y465371D01*
X1634682Y465558D01*
G02X1634754Y465588I111J-166D01*
G01X1634799Y465596D01*
G03X1635032Y465549I472J1740D01*
G01X1635034D01*
X1635046Y465548D01*
G03X1635265Y465534I224J1788D01*
G03X1635552Y465557I0J1803D01*
G01X1635553D01*
G03X1635689Y465586I-308J1776D01*
G01X1635731Y465596D01*
X1635812Y465582D01*
X1636095Y465395D01*
G02X1636124Y465371I-112J-165D01*
G02X1636178Y465280I-139J-144D01*
G03X1636805Y464261I1487J212D01*
G01X1636849Y464231D01*
X1636894Y464138D01*
X1636878Y463871D01*
Y463869D01*
X1636872Y463748D01*
G02X1636810Y463613I-200J10D01*
G01X1636792Y463596D01*
X1636768Y463582D01*
X1636766Y463581D01*
G03X1635987Y462264I724J-1317D01*
G03X1638991I1502J0D01*
G03X1638349Y463495I-1501J0D01*
G01X1638305Y463525D01*
X1638260Y463618D01*
X1638276Y463885D01*
Y463887D01*
X1638282Y464008D01*
G02X1638344Y464143I200J-10D01*
G01X1638362Y464160D01*
X1638386Y464174D01*
X1638388Y464175D01*
G03X1639167Y465492I-724J1317D01*
G03X1637665Y466994I-1502J0D01*
G01X1637664D01*
G03X1637406Y466972I-2J-1502D01*
G01X1637397Y466970D01*
X1637377Y466968D01*
G02X1637231Y467016I-15J200D01*
G01X1637100Y467129D01*
X1637064Y467213D01*
X1637066Y467259D01*
G03X1637068Y467337I-1801J85D01*
G01Y470737D01*
G03X1637066Y470809I-1803J-14D01*
G01Y470822D01*
G02X1637136Y470974I200J0D01*
G01X1637198Y471027D01*
X1637201Y471030D01*
X1637230Y471055D01*
G02X1637397Y471101I131J-151D01*
G03X1637664Y471077I267J1478D01*
G01X1637673D01*
G03X1639167Y472579I-8J1502D01*
G03X1637665Y474081I-1502J0D01*
G03X1636182Y472816I0J-1502D01*
G01Y472815D01*
X1636175Y472772D01*
X1636152Y472737D01*
G02X1636095Y472679I-168J108D01*
G01X1635813Y472492D01*
X1635732Y472478D01*
X1635691Y472488D01*
G03X1635265Y472540I-430J-1751D01*
G03X1634839Y472488I4J-1803D01*
G01X1634798Y472478D01*
X1634717Y472492D01*
X1634435Y472679D01*
G02X1634378Y472737I111J166D01*
G01X1634355Y472772D01*
X1634348Y472815D01*
Y472816D01*
G03X1632865Y474081I-1483J-237D01*
G03X1631879Y473712I0J-1502D01*
G02X1631877Y473710I-142J140D01*
G02X1631747Y473662I-130J152D01*
G01X1631484D01*
G02X1631416Y473674I0J200D01*
G01X1631379Y473687D01*
X1631351Y473712D01*
G03X1630365Y474081I-986J-1133D01*
G01X1630364D01*
G03X1630106Y474059I-2J-1502D01*
G01X1630097Y474057D01*
X1630077Y474055D01*
G02X1629931Y474103I-15J200D01*
G01X1629800Y474216D01*
X1629764Y474300D01*
X1629766Y474346D01*
G03X1629768Y474424I-1801J85D01*
G01Y477824D01*
G03X1629766Y477896I-1803J-14D01*
G01Y477909D01*
G02X1629836Y478061I200J0D01*
G01X1629898Y478114D01*
X1629901Y478117D01*
X1629930Y478142D01*
G02X1630097Y478188I131J-151D01*
G03X1630364Y478164I267J1478D01*
G01X1630373D01*
G03X1630542Y478175I-13J1502D01*
G03X1631351Y478534I-177J1491D01*
G02X1631353Y478535I88J-173D01*
G02X1631483Y478583I130J-152D01*
G01X1631746D01*
G02X1631814Y478571I0J-200D01*
G01X1631851Y478558D01*
X1631879Y478533D01*
G37*
G36*
G01X1676497Y202336D02*
X1680009D01*
G02X1680150Y202278I0J-200D01*
G01X1682190Y200238D01*
X1682205Y200207D01*
G03X1682244Y200132I1352J655D01*
G01X1682245Y200131D01*
G03X1682260Y200105I1308J738D01*
G01X1682273Y200083D01*
X1682289Y200027D01*
X1682302Y199981D01*
Y197600D01*
G02X1682269Y197490I-200J0D01*
G03Y195840I1254J-825D01*
G02X1682302Y195730I-167J-110D01*
G01Y193600D01*
G02X1682269Y193490I-200J0D01*
G03Y191840I1254J-825D01*
G02X1682302Y191730I-167J-110D01*
G01Y187518D01*
X1682292Y187475D01*
X1682281Y187453D01*
G03Y186103I1355J-675D01*
G01X1682292Y186081D01*
X1682302Y186038D01*
Y181600D01*
G02X1682269Y181490I-200J0D01*
G03Y179840I1254J-825D01*
G02X1682302Y179730I-167J-110D01*
G01Y177600D01*
G02X1682269Y177490I-200J0D01*
G03Y175840I1254J-825D01*
G02X1682302Y175730I-167J-110D01*
G01Y173600D01*
G02X1682269Y173490I-200J0D01*
G03Y171840I1254J-825D01*
G02X1682302Y171730I-167J-110D01*
G01Y169600D01*
G02X1682269Y169490I-200J0D01*
G03Y167840I1254J-825D01*
G02X1682302Y167730I-167J-110D01*
G01Y163086D01*
G02X1682247Y162947I-200J-1D01*
G01X1682165Y162862D01*
X1682132Y162846D01*
X1682040Y162801D01*
X1682007Y162797D01*
G03Y159815I182J-1491D01*
G01X1682040Y159811D01*
X1682133Y159766D01*
G02X1682190Y159724I-88J-180D01*
G01X1682247Y159665D01*
G02X1682302Y159526I-145J-138D01*
G01Y151308D01*
G02X1682102Y151108I-200J0D01*
G01X1675528D01*
G02X1675352Y151213I0J200D01*
G01X1675186Y151523D01*
G02X1675162Y151625I176J95D01*
G01X1675164Y151682D01*
X1675195Y151729D01*
G03X1675447Y152562I-1251J833D01*
G03X1673945Y154064I-1502J0D01*
G03X1672651Y153325I0J-1502D01*
G01X1672625Y153281D01*
X1672540Y153229D01*
X1672362Y153219D01*
X1672109Y153204D01*
X1672019Y153245D01*
X1671989Y153285D01*
G03X1670795Y153875I-1194J-913D01*
G03X1669293Y152373I0J-1502D01*
G03X1669458Y151689I1502J0D01*
G01X1669482Y151642D01*
X1669478Y151539D01*
X1669272Y151203D01*
G02X1669102Y151108I-170J105D01*
G01X1659784D01*
G02X1659656Y151155I1J200D01*
G01X1658823Y151988D01*
X1658518Y152292D01*
G03X1657103Y152878I-1415J-1415D01*
G01X1650743D01*
G03X1649328Y152292I0J-2001D01*
G01X1645991Y148955D01*
G03X1645468Y148042I1414J-1416D01*
G03X1645404Y147540I1938J-502D01*
G03X1647402Y145538I2002J0D01*
G01X1647406D01*
G03X1647908Y145602I0J2002D01*
G03X1648821Y146125I-503J1937D01*
G01X1651513Y148817D01*
G02X1651655Y148876I142J-141D01*
G01X1654133D01*
G02X1654282Y148809I0J-200D01*
G01X1654481Y148588D01*
G02X1654531Y148437I-149J-133D01*
G01Y148434D01*
G03X1654523Y148277I1494J-155D01*
G03X1656025Y146775I1502J0D01*
G03X1657214Y147359I0J1502D01*
G01X1657238Y147390D01*
X1657271Y147410D01*
G02X1657341Y147435I101J-173D01*
G01X1657610Y147479D01*
G02X1657754Y147447I32J-198D01*
G01X1657755Y147446D01*
G03X1658219Y147214I1120J1659D01*
G03X1658874Y147104I654J1892D01*
G01X1682102D01*
G02X1682302Y146904I0J-200D01*
G01Y124540D01*
X1682299Y124524D01*
G03X1682280Y124283I1483J-238D01*
G03X1682299Y124042I1502J-3D01*
G01X1682302Y124026D01*
Y120792D01*
G02X1682288Y120718I-200J0D01*
G01X1682250Y120621D01*
X1682226Y120594D01*
G03Y118594I1122J-1000D01*
G01X1682250Y118567D01*
X1682288Y118470D01*
G02X1682302Y118396I-186J-74D01*
G01Y117752D01*
X1682248Y117618D01*
X1682225Y117592D01*
G03X1681846Y116594I1124J-998D01*
G01Y116592D01*
G03X1682150Y115687I1503J1D01*
G02X1682190Y115567I-160J-120D01*
G01Y114421D01*
G02X1682150Y114301I-200J0D01*
G03Y112487I1199J-907D01*
G02X1682190Y112367I-160J-120D01*
G01Y111688D01*
G03X1682220Y111583I200J0D01*
G01X1682271Y111504D01*
G02X1682302Y111396I-169J-107D01*
G01Y109734D01*
G02X1682243Y109592I-200J0D01*
G01X1681300Y108649D01*
G02X1681158Y108590I-142J141D01*
G01X1644486D01*
G02X1644322Y108676I0J200D01*
G03X1641358I-1482J-1027D01*
G02X1641194Y108590I-164J114D01*
G01X1624913D01*
G02X1624771Y108649I0J200D01*
G01X1623712Y109708D01*
X1623687Y109753D01*
X1623680Y109780D01*
G03X1622594Y110866I-1456J-370D01*
G01X1622567Y110873D01*
X1622522Y110898D01*
X1622460Y110960D01*
G02X1622401Y111102I141J142D01*
G01Y114907D01*
X1622488Y115016D01*
X1622557Y115031D01*
G03Y117961I-333J1465D01*
G01X1622488Y117976D01*
X1622401Y118085D01*
Y122963D01*
X1622501Y123076D01*
X1622577Y123085D01*
G03Y126067I-181J1491D01*
G01X1622501Y126076D01*
X1622401Y126189D01*
Y159263D01*
G02X1622460Y159405I200J0D01*
G01X1623323Y160268D01*
G02X1623465Y160327I142J-141D01*
G01X1658982D01*
G03X1659124Y160386I0J200D01*
G01X1662829Y164091D01*
G03X1662888Y164233I-141J142D01*
G01Y201567D01*
G02X1662947Y201709I200J0D01*
G01X1663515Y202277D01*
G02X1663657Y202336I142J-141D01*
G01X1673357D01*
G02X1673534Y202229I0J-200D01*
G01X1673698Y201916D01*
G02X1673687Y201711I-177J-93D01*
G01X1673686Y201710D01*
G03X1673425Y200873I1241J-846D01*
G01Y200845D01*
G03X1676429I1502J19D01*
G01Y200865D01*
G03X1676168Y201711I-1502J0D01*
G01X1676136Y201757D01*
X1676130Y201867D01*
X1676320Y202229D01*
G02X1676497Y202336I177J-93D01*
G37*
G36*
G01X1713642Y54588D02*
X1742687D01*
X1742830Y54445D01*
Y52734D01*
X1742687Y52591D01*
X1713642D01*
G03X1707705Y46654I0J-5937D01*
G01Y7874D01*
G02X1701831Y2000I-5874J0D01*
G01X1654587D01*
G02X1648713Y7874I0J5874D01*
G01Y46210D01*
X1650710D01*
Y7874D01*
G03X1654585Y3998I3876J0D01*
G01X1701831D01*
G03X1705708Y7874I0J3877D01*
G01Y46654D01*
G02X1713642Y54588I7934J0D01*
G37*
G36*
G01X1659294Y275932D02*
X1681229D01*
X1681303Y275902D01*
X1681331Y275873D01*
X1681942Y275262D01*
G02X1682001Y275120I-141J-142D01*
G01Y205020D01*
X1681971Y204946D01*
X1681942Y204918D01*
X1680421Y203397D01*
G02X1680279Y203338I-142J141D01*
G01X1659412D01*
X1659338Y203368D01*
X1659310Y203397D01*
X1659152Y203555D01*
G02X1659094Y203696I142J141D01*
G01Y204858D01*
G02X1659154Y205001I200J0D01*
G01X1659388Y205230D01*
X1659462Y205259D01*
X1659502Y205258D01*
X1659536D01*
G03Y208262I0J1502D01*
G01X1659502D01*
X1659462Y208261D01*
X1659388Y208290D01*
X1659154Y208519D01*
G02X1659094Y208661I140J143D01*
G01Y255107D01*
G02X1659212Y255289I200J0D01*
G01X1659536Y255436D01*
G02X1659707Y255432I81J-183D01*
G01X1659757Y255407D01*
X1659776Y255392D01*
G03X1660750Y255033I975J1143D01*
G03Y258037I0J1502D01*
G03X1659776Y257678I1J-1502D01*
G01X1659757Y257663D01*
X1659707Y257638D01*
G02X1659536Y257634I-90J179D01*
G01X1659212Y257781D01*
G02X1659094Y257963I82J182D01*
G01Y275732D01*
G02X1659294Y275932I200J0D01*
G37*
G36*
G01X1694823Y242420D02*
G03X1694960Y242428I-2J1210D01*
G01X1694972Y242429D01*
X1698133D01*
X1698145Y242428D01*
G03X1698281Y242420I139J1202D01*
G01X1702745D01*
G02X1702781Y242417I1J-200D01*
G01X1702798Y242414D01*
G02X1702901Y242361I-36J-197D01*
G01X1703090Y242180D01*
G02X1703151Y242046I-139J-144D01*
G01Y242042D01*
G03X1703551Y241077I1501J57D01*
G01X1703553Y241075D01*
X1703556Y241072D01*
G03X1703562Y241065I1143J974D01*
G01X1703564Y241063D01*
X1703569Y241057D01*
G03X1704671Y240576I1102J1022D01*
G03X1706173Y242057I0J1502D01*
G01X1706174Y242098D01*
X1706205Y242170D01*
X1706379Y242338D01*
X1706402Y242360D01*
G02X1706506Y242414I140J-143D01*
G01X1706541Y242420D01*
X1710406D01*
G03X1710547Y242428I2J1210D01*
G01X1713949D01*
G03X1714090Y242420I139J1202D01*
G01X1720682D01*
G02X1720777Y242396I0J-200D01*
G01X1720803Y242382D01*
X1723277Y239908D01*
X1723289Y239895D01*
X1723330Y239854D01*
G02X1723353Y239762I-177J-93D01*
G01Y153175D01*
G02X1723350Y153139I-200J-1D01*
G01X1723339Y153081D01*
X1723306Y153023D01*
X1723280Y153000D01*
G03X1722976Y147733I2440J-2783D01*
G01X1722994Y147713D01*
X1722995Y147711D01*
G03X1723185Y147517I2738J2492D01*
G03X1723238Y147469I2511J2719D01*
G01X1723239Y147468D01*
G03X1723256Y147452I2545J2687D01*
G01X1723272Y147437D01*
X1723296Y147404D01*
X1723336Y147312D01*
G02X1723353Y147232I-183J-81D01*
G01Y125108D01*
X1723342Y125076D01*
G03X1723256Y124576I1416J-501D01*
G03X1723342Y124076I1502J1D01*
G01X1723353Y124044D01*
Y122986D01*
G03X1723368Y122910I200J0D01*
G01X1723388Y122863D01*
G02X1723403Y122786I-185J-76D01*
G01Y117488D01*
G02X1723366Y117371I-200J-1D01*
G03X1723084Y116496I1220J-876D01*
G03X1723366Y115621I1502J1D01*
G02X1723403Y115504I-163J-116D01*
G01Y110681D01*
G03X1723416Y110611I200J1D01*
G02X1723428Y110527I-188J-70D01*
G01X1723419Y110411D01*
G02X1723380Y110306I-199J14D01*
G03X1723084Y109410I1206J-895D01*
G03X1724586Y107908I1502J0D01*
G03X1725518Y108232I0J1502D01*
G01X1725579Y108280D01*
X1725729Y108272D01*
X1726333Y107668D01*
G03X1726475Y107609I142J141D01*
G01X1727053D01*
X1727073Y107605D01*
G03X1727088Y107602I243J1177D01*
G01X1727091D01*
X1727106Y107600D01*
G03X1727176Y107592I171J1189D01*
G03X1727273Y107588I98J1198D01*
G01X1743200D01*
G02X1743400Y107402I0J-200D01*
G01Y104249D01*
G03X1743431Y103915I1802J-1D01*
G01X1743436Y103886D01*
X1743430Y103829D01*
X1743419Y103802D01*
G02X1743348Y103713I-185J75D01*
G01X1743317Y103692D01*
G02X1743112Y103678I-114J164D01*
G03X1742425Y103845I-688J-1333D01*
G03X1740923Y102343I0J-1502D01*
G03X1741344Y101300I1502J0D01*
G01X1741347Y101297D01*
X1741349Y101295D01*
G03X1742444Y100821I1095J1028D01*
G03X1743944Y102242I0J1502D01*
G01Y102244D01*
G02X1744038Y102401I199J-13D01*
G01X1744356Y102601D01*
X1744453Y102608D01*
X1744498Y102589D01*
G03X1745200Y102446I704J1660D01*
G01X1745271D01*
X1745295Y102449D01*
X1745301D01*
G03X1747004Y104249I-100J1800D01*
G01Y107402D01*
G02X1747204Y107588I200J-14D01*
G01X1783448D01*
G02X1783588Y107531I0J-200D01*
G01X1783589Y107530D01*
X1785003Y106116D01*
G02X1785062Y105974I-141J-142D01*
G01Y94814D01*
X1785050Y94781D01*
G03X1784964Y94280I1416J-501D01*
G01Y94279D01*
G03X1785050Y93778I1502J0D01*
G01X1785062Y93744D01*
Y87557D01*
X1784997Y87458D01*
X1784941Y87434D01*
X1784939Y87433D01*
X1784933Y87431D01*
G03X1784939Y84659I580J-1385D01*
G01X1784995Y84635D01*
X1785062Y84536D01*
Y62248D01*
X1784975Y62139D01*
X1784907Y62123D01*
G03Y59197I339J-1463D01*
G01X1784975Y59181D01*
X1785062Y59072D01*
Y58660D01*
X1785042Y58599D01*
X1785022Y58572D01*
G03Y56764I1199J-904D01*
G02X1785062Y56643I-160J-120D01*
G01Y54060D01*
G02X1785003Y53918I-200J0D01*
G01X1783801Y52716D01*
G02X1783659Y52657I-142J141D01*
G01X1765129D01*
G02X1764987Y52716I0J200D01*
G01X1759846Y57857D01*
G03X1759749Y57911I-142J-141D01*
G01X1759711Y57920D01*
X1759650Y57962D01*
X1759425Y58296D01*
X1759415Y58394D01*
X1759434Y58441D01*
G03X1760055Y61459I-7780J3174D01*
G03X1760056Y61610I-8401J131D01*
G01Y61614D01*
G03X1757555Y67595I-8402J0D01*
G03X1751634Y70036I-5921J-5961D01*
G03X1743232Y61634I0J-8402D01*
G03X1743845Y58485I8402J1D01*
G01X1743852Y58467D01*
X1743860Y58425D01*
G02X1743830Y58275I-196J-39D01*
G01X1743647Y58004D01*
G02X1743481Y57916I-166J112D01*
G01X1736336D01*
G02X1736158Y58026I1J200D01*
G01X1735985Y58367D01*
X1735994Y58479D01*
X1736027Y58525D01*
G03X1736738Y60583I-2988J2184D01*
G01Y60584D01*
X1736741Y60639D01*
Y60709D01*
G03X1736297Y62466I-3702J-1D01*
G01X1736273Y62511D01*
Y62611D01*
X1736463Y62963D01*
X1736547Y63018D01*
X1736598Y63022D01*
G03X1739011Y69456I-319J3789D01*
G01X1739010Y69457D01*
G03X1734791Y70338I-2750J-2626D01*
G03X1732911Y65032I1469J-3507D01*
G01X1732912Y65029D01*
X1732918Y65017D01*
X1732924Y65003D01*
G02X1732909Y64817I-184J-79D01*
G01X1732906Y64813D01*
X1732736Y64528D01*
G02X1732564Y64430I-172J102D01*
G01X1725720D01*
G03X1722019Y60729I0J-3701D01*
G01Y60727D01*
G03X1722727Y58552I3701J2D01*
G01X1722760Y58505D01*
X1722769Y58395D01*
X1722556Y57974D01*
X1722461Y57916D01*
X1685707D01*
G02X1685565Y57975I0J200D01*
G01X1684800Y58740D01*
G02X1684759Y58962I142J141D01*
G01Y58963D01*
X1684909Y59302D01*
G02X1684990Y59393I183J-81D01*
G01X1685018Y59410D01*
X1685074Y59424D01*
X1685103Y59422D01*
X1685109D01*
G03X1685184Y59420I78J1500D01*
G03Y62424I0J1502D01*
G03X1684502Y62260I0J-1502D01*
G01X1684455Y62236D01*
X1684352Y62240D01*
X1684016Y62446D01*
G02X1683921Y62616I105J170D01*
G01Y84598D01*
G02X1683944Y84691I200J0D01*
G01X1683996Y84790D01*
X1684025Y84824D01*
X1684043Y84837D01*
G03Y87255I-891J1209D01*
G01X1684025Y87268D01*
X1683996Y87302D01*
X1683944Y87401D01*
G02X1683921Y87494I177J93D01*
G01Y92495D01*
G02X1683979Y92636I200J0D01*
G01X1684089Y92747D01*
X1684155Y92777D01*
X1684193Y92780D01*
G03X1685606Y94279I-89J1499D01*
G01X1685607D01*
G03X1684235Y95776I-1503J0D01*
G01X1684191Y95779D01*
X1684154Y95798D01*
G02X1684099Y95840I92J178D01*
G01X1683915Y96039D01*
G02X1683862Y96175I147J136D01*
G01Y108877D01*
G02X1683975Y109058I200J1D01*
G01X1683976D01*
G03X1684521Y109500I-648J1355D01*
G01X1684530Y109512D01*
X1684540Y109522D01*
X1684552Y109534D01*
G02X1684664Y109590I141J-142D01*
G01X1684708Y109597D01*
X1684975Y109636D01*
X1685052Y109616D01*
X1685084Y109591D01*
G03X1685997Y109282I913J1194D01*
G03X1687284Y110009I0J1503D01*
G01X1687298Y110031D01*
X1687332Y110066D01*
X1687434Y110125D01*
G02X1687474Y110143I101J-172D01*
G02X1687511Y110152I66J-189D01*
G02X1687535Y110153I20J-199D01*
G01X1687746D01*
G02X1687843Y110128I0J-200D01*
G01X1687944Y110072D01*
X1687980Y110037D01*
X1687994Y110015D01*
G03X1688193Y109759I1279J789D01*
G01X1688195Y109757D01*
X1688197Y109755D01*
G03X1689291Y109282I1094J1029D01*
G03X1690793Y110784I0J1502D01*
G03X1690372Y111827I-1502J0D01*
G01X1690369Y111830D01*
X1690362Y111837D01*
G03X1689272Y112306I-1090J-1032D01*
G03X1687971Y111555I0J-1502D01*
G02X1687798Y111455I-173J100D01*
G01X1687459D01*
G02X1687287Y111553I0J200D01*
G03X1687091Y111813I-1290J-769D01*
G01X1687088Y111816D01*
X1687084Y111821D01*
G03X1687081Y111824I-1064J-1061D01*
G01X1687080Y111825D01*
G03X1685978Y112306I-1102J-1022D01*
G03X1684786Y111718I0J-1502D01*
G01X1684777Y111706D01*
X1684767Y111696D01*
X1684755Y111684D01*
G02X1684643Y111628I-141J142D01*
G01X1684389Y111590D01*
G02X1684296Y111598I-30J198D01*
G01X1684219Y111624D01*
X1684196Y111640D01*
G03X1684173Y111655I-832J-1250D01*
G01X1684153Y111669D01*
X1684136Y111688D01*
G02X1684108Y111727I147J135D01*
G01X1684063Y111809D01*
G02X1684039Y111904I176J95D01*
G01Y111924D01*
G02X1684064Y112021I200J0D01*
G01X1684081Y112051D01*
G02X1684147Y112122I175J-97D01*
G01X1684149Y112123D01*
X1684150D01*
G03X1684850Y113394I-804J1271D01*
G03X1684445Y114420I-1502J0D01*
G01X1684443Y114422D01*
X1684440Y114426D01*
G03X1684435Y114431I-1065J-1060D01*
G03X1684433Y114433I-142J-140D01*
G03X1683976Y114770I-1104J-1019D01*
G01X1683923Y114795D01*
X1683862Y114892D01*
Y115049D01*
G02X1683978Y115231I200J0D01*
G03X1684850Y116594I-629J1363D01*
G03X1684430Y117636I-1503J0D01*
G01X1684428Y117638D01*
X1684426Y117640D01*
G03X1684252Y117799I-1097J-1026D01*
G02X1684175Y117957I123J158D01*
G01Y118190D01*
G02X1684196Y118278I200J-1D01*
G01X1684243Y118374D01*
X1684270Y118408D01*
X1684287Y118421D01*
G03X1684850Y119594I-940J1173D01*
G03X1684445Y120620I-1502J0D01*
G01X1684443Y120622D01*
X1684440Y120626D01*
G03X1684435Y120631I-1065J-1060D01*
G03X1684433Y120633I-142J-140D01*
G03X1683976Y120970I-1104J-1019D01*
G01X1683923Y120995D01*
X1683862Y121092D01*
Y122677D01*
X1683957Y122789D01*
X1684029Y122801D01*
G03X1684868Y125321I-247J1482D01*
G01X1684866Y125323D01*
X1684864Y125326D01*
G03X1684027Y125782I-1100J-1023D01*
G01X1683955Y125795D01*
X1683862Y125905D01*
Y131939D01*
G02X1683983Y132123I200J0D01*
G01X1684376Y132292D01*
X1684493Y132271D01*
X1684537Y132229D01*
G03X1684706Y132090I1037J1089D01*
G01X1684736Y132070D01*
X1684757Y132039D01*
G02X1684787Y131974I-164J-115D01*
G01X1684818Y131848D01*
Y131846D01*
X1684858Y131684D01*
X1684849Y131613D01*
X1684833Y131581D01*
G03X1684669Y130895I1338J-683D01*
G01Y130876D01*
G03X1686171Y129396I1502J22D01*
G03X1687673Y130898I0J1502D01*
G03X1687036Y132126I-1502J0D01*
G01X1687007Y132146D01*
X1686986Y132177D01*
G02X1686957Y132242I165J113D01*
G01X1686894Y132497D01*
G02X1686909Y132634I194J48D01*
G01X1686910Y132635D01*
Y132636D01*
G03X1687000Y132851I-1336J686D01*
G01X1687011Y132886D01*
X1687056Y132941D01*
X1687345Y133115D01*
X1687377Y133121D01*
G03X1687738Y133077I361J1459D01*
G03X1689240Y134579I0J1502D01*
G03X1688819Y135622I-1502J0D01*
G01X1688816Y135625D01*
X1688809Y135632D01*
G03X1687719Y136101I-1090J-1032D01*
G03X1686291Y135066I0J-1503D01*
G01X1686290Y135064D01*
G02X1686203Y134955I-190J62D01*
G01X1685946Y134802D01*
X1685876Y134789D01*
X1685840Y134796D01*
G03X1685573Y134820I-267J-1478D01*
G01X1685572D01*
G03X1684537Y134407I0J-1503D01*
G01X1684493Y134366D01*
X1684376Y134345D01*
X1683983Y134513D01*
G02X1683862Y134697I79J184D01*
G01Y167050D01*
G02X1683898Y167163I200J-1D01*
G01Y167164D01*
G02X1683997Y167239I164J-114D01*
G01X1683999Y167240D01*
G03X1685026Y168665I-475J1425D01*
G03X1684603Y169710I-1502J0D01*
G01X1684600Y169713D01*
X1684598Y169715D01*
G03X1684008Y170100I-1093J-1030D01*
G01X1683997Y170104D01*
X1683973Y170116D01*
G02X1683862Y170295I89J179D01*
G01Y171050D01*
G02X1683898Y171163I200J-1D01*
G01Y171164D01*
G02X1683997Y171239I164J-114D01*
G01X1683999Y171240D01*
G03X1685026Y172665I-475J1425D01*
G03X1684603Y173710I-1502J0D01*
G01X1684600Y173713D01*
X1684598Y173715D01*
G03X1684008Y174100I-1093J-1030D01*
G01X1683997Y174104D01*
X1683973Y174116D01*
G02X1683862Y174295I89J179D01*
G01Y175050D01*
G02X1683898Y175163I200J-1D01*
G01Y175164D01*
G02X1683997Y175239I164J-114D01*
G01X1683999Y175240D01*
G03X1685026Y176665I-475J1425D01*
G03X1684603Y177710I-1502J0D01*
G01X1684600Y177713D01*
X1684598Y177715D01*
G03X1684008Y178100I-1093J-1030D01*
G01X1683997Y178104D01*
X1683973Y178116D01*
G02X1683862Y178295I89J179D01*
G01Y179050D01*
G02X1683898Y179163I200J-1D01*
G01Y179164D01*
G02X1683997Y179239I164J-114D01*
G01X1683999Y179240D01*
G03X1685026Y180665I-475J1425D01*
G03X1684603Y181710I-1502J0D01*
G01X1684600Y181713D01*
X1684598Y181715D01*
G03X1684008Y182100I-1093J-1030D01*
G01X1683997Y182104D01*
X1683973Y182116D01*
G02X1683862Y182295I89J179D01*
G01Y185199D01*
X1683945Y185306D01*
X1684012Y185324D01*
G03X1685139Y186778I-374J1454D01*
G03X1685126Y186978I-1502J3D01*
G01X1685125Y186988D01*
G03X1684718Y187821I-1488J-211D01*
G01X1684716Y187823D01*
X1684709Y187831D01*
G03X1684012Y188247I-1090J-1034D01*
G01X1684010Y188248D01*
X1684005Y188250D01*
G02X1683862Y188441I57J192D01*
G01Y191050D01*
G02X1683898Y191163I200J-1D01*
G01Y191164D01*
G02X1683997Y191239I164J-114D01*
G01X1683999Y191240D01*
G03X1685026Y192665I-475J1425D01*
G03X1684603Y193710I-1502J0D01*
G01X1684600Y193713D01*
X1684598Y193715D01*
G03X1684008Y194100I-1093J-1030D01*
G01X1683997Y194104D01*
X1683973Y194116D01*
G02X1683862Y194295I89J179D01*
G01Y195015D01*
G02X1683897Y195128I200J0D01*
G01X1683970Y195236D01*
X1684017Y195272D01*
X1684046Y195284D01*
G03X1684008Y198100I-541J1401D01*
G01X1683997Y198104D01*
X1683973Y198116D01*
G02X1683862Y198295I89J179D01*
G01Y199305D01*
X1683939Y199410D01*
X1684003Y199430D01*
G03X1685058Y200864I-447J1434D01*
G03X1684639Y201905I-1503J0D01*
G01X1684636Y201908D01*
X1684634Y201910D01*
G03X1684000Y202313I-1097J-1026D01*
G01X1683970Y202323D01*
X1683919Y202359D01*
X1683901Y202385D01*
G02X1683862Y202503I161J119D01*
G01Y203305D01*
X1683939Y203410D01*
X1684003Y203430D01*
G03X1685058Y204864I-447J1434D01*
G03X1684639Y205905I-1503J0D01*
G01X1684636Y205908D01*
X1684634Y205910D01*
G03X1684000Y206313I-1097J-1026D01*
G01X1683970Y206323D01*
X1683919Y206359D01*
X1683901Y206385D01*
G02X1683862Y206503I161J119D01*
G01Y207305D01*
X1683939Y207410D01*
X1684003Y207430D01*
G03X1685058Y208864I-447J1434D01*
G03X1684639Y209905I-1503J0D01*
G01X1684636Y209908D01*
X1684634Y209910D01*
G03X1684000Y210313I-1097J-1026D01*
G01X1683970Y210323D01*
X1683919Y210359D01*
X1683901Y210385D01*
G02X1683862Y210503I161J119D01*
G01Y211305D01*
X1683939Y211410D01*
X1684003Y211430D01*
G03X1685058Y212864I-447J1434D01*
G03X1684639Y213905I-1503J0D01*
G01X1684636Y213908D01*
X1684634Y213910D01*
G03X1684000Y214313I-1097J-1026D01*
G01X1683970Y214323D01*
X1683919Y214359D01*
X1683901Y214385D01*
G02X1683862Y214503I161J119D01*
G01Y215305D01*
X1683939Y215410D01*
X1684003Y215430D01*
G03X1685058Y216864I-447J1434D01*
G03X1684639Y217905I-1503J0D01*
G01X1684636Y217908D01*
X1684634Y217910D01*
G03X1684000Y218313I-1097J-1026D01*
G01X1683970Y218323D01*
X1683919Y218359D01*
X1683901Y218385D01*
G02X1683862Y218503I161J119D01*
G01Y220305D01*
X1683939Y220410D01*
X1684003Y220430D01*
G03X1685058Y221864I-447J1434D01*
G03X1684639Y222905I-1503J0D01*
G01X1684636Y222908D01*
X1684634Y222910D01*
G03X1684000Y223313I-1097J-1026D01*
G01X1683970Y223323D01*
X1683919Y223359D01*
X1683901Y223385D01*
G02X1683862Y223503I161J119D01*
G01Y241469D01*
G02X1683921Y241611I200J0D01*
G01X1684704Y242394D01*
X1684783Y242424D01*
X1684826Y242422D01*
G03X1684889Y242420I70J1208D01*
G01X1694823D01*
G37*
G36*
G01X1683995Y276294D02*
X1758969D01*
G02X1759111Y276235I0J-200D01*
G01X1760395Y274951D01*
G02X1760397Y274949I-140J-142D01*
G02X1760454Y274809I-143J-140D01*
G01Y267385D01*
G02X1760341Y267205I-200J0D01*
G01X1759964Y267023D01*
X1759851Y267036D01*
X1759805Y267072D01*
G03X1758871Y267398I-934J-1175D01*
G03Y264394I0J-1502D01*
G03X1759805Y264720I0J1501D01*
G01X1759851Y264756D01*
X1759964Y264769D01*
X1760341Y264587D01*
G02X1760454Y264407I-87J-180D01*
G01Y257901D01*
X1760400Y257809D01*
X1760355Y257782D01*
X1760353D01*
X1760065Y257613D01*
G02X1759911Y257593I-101J173D01*
G01X1759857Y257608D01*
X1759835Y257620D01*
G03X1759113Y257805I-723J-1319D01*
G01X1759112D01*
G03Y254801I0J-1502D01*
G01X1759113D01*
G03X1759835Y254986I-1J1504D01*
G01X1759857Y254998D01*
X1759911Y255013D01*
G02X1760065Y254993I53J-193D01*
G01X1760354Y254824D01*
G02X1760357Y254822I-109J-167D01*
G02X1760454Y254651I-103J-171D01*
G01Y207177D01*
X1760447Y207152D01*
G03X1760396Y206763I1451J-388D01*
G01Y206755D01*
G03X1760447Y206372I1502J5D01*
G01X1760454Y206346D01*
Y202582D01*
G03X1760513Y202440I200J0D01*
G01X1760934Y202019D01*
G03X1761076Y201960I142J141D01*
G01X1763794D01*
G02X1763827Y201957I-2J-200D01*
G02X1763934Y201903I-32J-197D01*
G01X1764189Y201648D01*
G02X1764191Y201646I-140J-142D01*
G02X1764248Y201506I-143J-140D01*
G01Y193725D01*
G02X1764162Y193561I-200J0D01*
G01X1763912Y193386D01*
G02X1763798Y193350I-114J164D01*
G01X1763711D01*
X1763680Y193361D01*
G03X1763190Y193443I-490J-1420D01*
G01X1763174D01*
G03X1761688Y191941I16J-1502D01*
G03X1763190Y190439I1502J0D01*
G01X1763193D01*
G03X1763711Y190532I-2J1502D01*
G01X1763757Y190549D01*
X1763854Y190537D01*
X1764162Y190321D01*
G02X1764248Y190157I-114J-164D01*
G01Y165175D01*
G02X1764189Y165033I-200J0D01*
G01X1760723Y161567D01*
X1760695Y161538D01*
X1760621Y161508D01*
X1753607D01*
G02X1753436Y161604I0J200D01*
G01X1753259Y161896D01*
G02X1753243Y161930I172J102D01*
G02X1753254Y162094I188J70D01*
G01X1753257Y162100D01*
X1753274Y162135D01*
G03X1753426Y162788I-1350J658D01*
G01Y162790D01*
Y162815D01*
G03X1753023Y163817I-1502J-22D01*
G01X1753022Y163818D01*
G02X1752966Y163957I144J139D01*
G01Y164268D01*
X1752993Y164338D01*
X1753020Y164366D01*
G03Y166420I-1096J1027D01*
G01X1752993Y166448D01*
X1752966Y166518D01*
Y166868D01*
X1752993Y166938D01*
X1753020Y166966D01*
G03X1753426Y167993I-1096J1027D01*
G03X1753056Y168980I-1501J0D01*
G01X1753032Y169008D01*
X1753007Y169074D01*
Y169412D01*
X1753032Y169478D01*
X1753056Y169506D01*
G03X1753426Y170493I-1131J987D01*
G03X1750422I-1502J0D01*
G03X1750792Y169506I1501J0D01*
G01X1750816Y169478D01*
X1750841Y169412D01*
Y169074D01*
X1750816Y169008D01*
X1750792Y168980D01*
G03X1750422Y167993I1131J-987D01*
G03X1750828Y166966I1502J0D01*
G01X1750855Y166938D01*
X1750882Y166868D01*
Y166518D01*
X1750855Y166448D01*
X1750828Y166420D01*
G03Y164366I1096J-1027D01*
G01X1750855Y164338D01*
X1750882Y164268D01*
Y163918D01*
X1750855Y163849D01*
X1750828Y163820D01*
G03X1750422Y162821I1096J-1027D01*
G01Y162793D01*
G03X1750574Y162134I1502J-1D01*
G01X1750603Y162073D01*
G02X1750605Y161930I-186J-74D01*
G02X1750589Y161896I-188J68D01*
G01X1750412Y161605D01*
X1750385Y161559D01*
X1750294Y161508D01*
X1746670D01*
G02X1746512Y161585I0J200D01*
G01X1746289Y161870D01*
X1746270Y161959D01*
X1746281Y162005D01*
G03X1746326Y162368I-1457J365D01*
G03X1744824Y163870I-1502J0D01*
G03X1743797Y163464I0J-1502D01*
G01X1743769Y163437D01*
X1743699Y163410D01*
X1743349D01*
X1743279Y163437D01*
X1743251Y163464D01*
G03X1742224Y163870I-1027J-1096D01*
G03X1740722Y162368I0J-1502D01*
G03X1740767Y162005I1502J2D01*
G01X1740778Y161959D01*
X1740759Y161870D01*
X1740536Y161585D01*
G02X1740378Y161508I-158J123D01*
G01X1725230D01*
G02X1725088Y161567I0J200D01*
G01X1724432Y162223D01*
G02X1724374Y162364I142J141D01*
G01Y240157D01*
G03X1724315Y240298I-200J-1D01*
G01X1724018Y240595D01*
X1724016Y240598D01*
G03X1724003Y240611I-856J-843D01*
G01X1724002Y240612D01*
X1721535Y243079D01*
G03X1721509Y243104I-845J-853D01*
G01X1721507Y243106D01*
X1721261Y243352D01*
G03X1721121Y243410I-141J-142D01*
G01X1720905D01*
X1720888Y243413D01*
G03X1720687Y243430I-201J-1185D01*
G01X1714092D01*
G02X1713934Y243507I0J200D01*
G01X1713711Y243793D01*
X1713692Y243882D01*
X1713704Y243928D01*
G03X1713750Y244297I-1457J369D01*
G03X1712248Y245799I-1502J0D01*
G03X1711881Y245753I2J-1502D01*
G01X1711825Y245739D01*
X1711718Y245773D01*
X1711410Y246131D01*
X1711392Y246242D01*
X1711414Y246295D01*
G03X1711530Y246874I-1387J579D01*
G03X1710028Y248376I-1502J0D01*
G03X1708999Y247968I0J-1502D01*
G01X1708965Y247936D01*
X1708879Y247909D01*
X1708525Y247958D01*
G02X1708517Y247959I21J199D01*
G02X1708380Y248055I36J197D01*
G03X1707086Y248794I-1294J-763D01*
G03Y245790I0J-1502D01*
G03X1708115Y246198I0J1502D01*
G01X1708149Y246230D01*
X1708235Y246257D01*
X1708589Y246208D01*
G02X1708596Y246207I-25J-198D01*
G02X1708737Y246106I-35J-197D01*
G03X1708740Y246100I180J86D01*
G03X1710028Y245372I1288J775D01*
G03X1710107Y245374I1J1502D01*
G01X1710108D01*
G03X1710170Y245378I-66J1501D01*
G01X1710204Y245382D01*
G03X1710286Y245394I-176J1492D01*
G01X1710287D01*
G03X1710395Y245418I-272J1477D01*
G01X1710451Y245432D01*
X1710558Y245398D01*
X1710866Y245040D01*
X1710883Y244930D01*
X1710861Y244876D01*
G03X1710755Y244474I1387J-581D01*
G01X1710750Y244419D01*
G03X1710745Y244297I1498J-122D01*
G01Y244295D01*
G03X1710791Y243927I1503J1D01*
G01X1710803Y243881D01*
X1710784Y243792D01*
X1710562Y243507D01*
G02X1710404Y243430I-158J123D01*
G01X1706552D01*
G03X1706353Y243413I2J-1201D01*
G01X1706336Y243410D01*
X1705389D01*
X1705343Y243422D01*
X1705324Y243431D01*
X1705322Y243432D01*
G03X1704671Y243580I-650J-1354D01*
G01X1704640D01*
G03X1704016Y243430I31J-1502D01*
G01X1703996Y243420D01*
X1703952Y243410D01*
X1702968D01*
X1702951Y243413D01*
G03X1702752Y243430I-201J-1184D01*
G01X1698283D01*
G02X1698116Y243520I0J200D01*
G01X1697945Y243781D01*
G02X1697929Y243971I167J110D01*
G03X1698054Y244571I-1378J600D01*
G01Y244590D01*
G03X1695050I-1502J-19D01*
G01Y244570D01*
G03X1695175Y243971I1502J1D01*
G01X1695194Y243928D01*
X1695190Y243838D01*
X1695169Y243797D01*
G02X1695159Y243781I-175J98D01*
G01X1694989Y243521D01*
X1694961Y243478D01*
X1694873Y243430D01*
X1684891D01*
G02X1684749Y243489I0J200D01*
G01X1683160Y245078D01*
X1683131Y245106D01*
X1683101Y245180D01*
Y275400D01*
G02X1683158Y275540I200J0D01*
G01X1683159Y275541D01*
X1683853Y276235D01*
G02X1683855Y276237I142J-140D01*
G02X1683995Y276294I140J-143D01*
G37*
G36*
G01X1711934Y1138611D02*
G03X1710511Y1139632I-1423J-481D01*
G03X1710241Y1139608I-3J-1502D01*
G01X1710192Y1139599D01*
X1710099Y1139628D01*
X1708849Y1140878D01*
G02X1708791Y1141035I141J141D01*
G01X1708819Y1141382D01*
X1708861Y1141458D01*
X1708897Y1141484D01*
G03X1709517Y1142700I-882J1216D01*
G03X1708015Y1144202I-1502J0D01*
G03X1706799Y1143582I0J-1502D01*
G01X1706773Y1143546D01*
X1706697Y1143504D01*
X1706350Y1143476D01*
G02X1706193Y1143534I-16J199D01*
G01X1705086Y1144641D01*
G02X1705027Y1144783I141J142D01*
G01Y1145065D01*
G03X1704968Y1145207I-200J0D01*
G01X1702515Y1147660D01*
G02X1702456Y1147802I141J142D01*
G01Y1172577D01*
G02X1702537Y1172738I200J0D01*
G01X1702832Y1172958D01*
X1702925Y1172974D01*
X1702970Y1172961D01*
G03X1703400Y1172898I430J1439D01*
G03X1704313Y1173207I0J1503D01*
G01X1704357Y1173241D01*
X1704464Y1173254D01*
X1704886Y1173069D01*
X1704949Y1172981D01*
X1704954Y1172927D01*
G03X1706450Y1171563I1496J138D01*
G03Y1174567I0J1502D01*
G03X1705537Y1174258I0J-1503D01*
G01X1705493Y1174224D01*
X1705386Y1174211D01*
X1704964Y1174396D01*
X1704901Y1174484D01*
X1704896Y1174538D01*
G03X1703400Y1175902I-1496J-138D01*
G03X1702970Y1175839I0J-1502D01*
G01X1702925Y1175826D01*
X1702832Y1175842D01*
X1702537Y1176062D01*
G02X1702456Y1176223I119J161D01*
G01Y1287184D01*
G02X1702513Y1287324I200J0D01*
G01X1702514Y1287325D01*
X1723180Y1307991D01*
G02X1723182Y1307993I142J-140D01*
G02X1723322Y1308050I140J-143D01*
G01X1820849D01*
G02X1820882Y1308047I-2J-200D01*
G02X1820989Y1307993I-32J-197D01*
G01X1825569Y1303413D01*
G02X1825628Y1303271I-141J-142D01*
G01Y1284045D01*
G02X1825569Y1283903I-200J0D01*
G01X1822291Y1280624D01*
G02X1822149Y1280565I-142J141D01*
G01X1774718D01*
G03X1774576Y1280506I0J-200D01*
G01X1763966Y1269896D01*
G03X1763907Y1269754I141J-142D01*
G01Y1228571D01*
G02X1763838Y1228420I-200J0D01*
G01X1763610Y1228222D01*
G02X1763451Y1228175I-131J151D01*
G03X1761614Y1228302I-1834J-13175D01*
G03Y1201698I0J-13302D01*
G03X1763451Y1201825I3J13302D01*
G01X1763495Y1201832D01*
X1763577Y1201807D01*
X1763838Y1201580D01*
G02X1763842Y1201576I-139J-143D01*
G01X1763843D01*
G02X1763907Y1201429I-136J-147D01*
G01Y1154056D01*
G02X1763848Y1153914I-200J0D01*
G01X1745181Y1135247D01*
G02X1745039Y1135188I-142J141D01*
G01X1736455D01*
G02X1736313Y1135247I0J200D01*
G01X1734810Y1136750D01*
G03X1734668Y1136809I-142J-141D01*
G01X1715757D01*
G02X1715673Y1136827I-1J200D01*
G01X1712003Y1138510D01*
X1711975Y1138541D01*
X1711947Y1138572D01*
X1711934Y1138611D01*
G37*
G36*
G01X1838607Y1205382D02*
X1838780Y1205209D01*
G02X1838833Y1205107I-143J-139D01*
G02X1838837Y1205069I-196J-40D01*
G01Y970376D01*
G02X1838792Y970250I-200J0D01*
G02X1838779Y970235I-157J123D01*
G01X1837188Y968644D01*
G03X1837129Y968502I141J-142D01*
G01Y966534D01*
G02X1837084Y966408I-200J0D01*
G02X1837071Y966393I-157J123D01*
G01X1823793Y953115D01*
G03X1823734Y952973I141J-142D01*
G01Y340822D01*
G03X1823793Y340680I200J0D01*
G01X1835738Y328735D01*
G02X1835795Y328595I-143J-140D01*
G01Y328572D01*
X1837441Y326926D01*
G02X1837494Y326824I-143J-139D01*
G02X1837498Y326786I-196J-40D01*
G01Y325999D01*
G03X1837557Y325857I200J0D01*
G01X1838437Y324977D01*
G02X1838490Y324875I-143J-139D01*
G02X1838494Y324837I-196J-40D01*
G01Y35585D01*
G02X1838449Y35459I-200J0D01*
G02X1838436Y35444I-157J123D01*
G01X1837504Y34512D01*
G02X1837454Y34476I-140J142D01*
G02X1837363Y34454I-91J178D01*
G01X1829871D01*
G03X1829795Y34439I0J-200D01*
G01X1829721Y34409D01*
G02X1829653Y34396I-71J187D01*
G01X1814979D01*
G02X1814853Y34441I0J200D01*
G02X1814838Y34454I123J157D01*
G01X1795887Y53405D01*
G02X1795851Y53455I142J140D01*
G02X1795829Y53546I178J91D01*
G01Y58752D01*
G03X1795770Y58894I-200J0D01*
G01X1795146Y59518D01*
X1788704Y65961D01*
G02X1788667Y66012I141J142D01*
G02X1788646Y66102I179J89D01*
G01Y93301D01*
Y93312D01*
G02X1788760Y93482I200J-11D01*
G01X1788874Y93530D01*
X1789088Y93620D01*
G02X1789165Y93636I78J-184D01*
G01X1789204D01*
X1789242Y93620D01*
X1789276Y93606D01*
G02X1789310Y93588I-76J-185D01*
G01X1789349Y93563D01*
X1789361Y93552D01*
G03X1790372Y93161I1011J1113D01*
G01X1790373D01*
G03Y96165I0J1502D01*
G01X1790372D01*
G03X1789361Y95774I0J-1504D01*
G01X1789349Y95763D01*
X1789297Y95729D01*
G02X1789289Y95725I-94J177D01*
G01X1789190Y95681D01*
G02X1789159Y95671I-77J185D01*
G02X1789134Y95666I-52J193D01*
G01X1789086Y95660D01*
X1789042Y95675D01*
G02X1788968Y95721I66J189D01*
G01X1788932Y95756D01*
G03X1788869Y95798I-140J-142D01*
G01X1788868D01*
X1788755Y95847D01*
G02X1788681Y95912I91J178D01*
G01X1788678Y95916D01*
G02X1788646Y96036I168J109D01*
G01Y290480D01*
G02X1788650Y290518I200J-2D01*
G02X1788703Y290620I196J-37D01*
G01X1794430Y296347D01*
G03X1794489Y296489I-141J142D01*
G01Y302104D01*
G02X1794490Y302128I200J4D01*
G02X1794540Y302237I199J-25D01*
G03Y304449I-1016J1106D01*
G02X1794490Y304558I149J134D01*
G02X1794489Y304582I199J20D01*
G01Y423696D01*
G02X1794492Y423726I200J-5D01*
G01X1794493Y423735D01*
G02X1794494Y423738I189J-61D01*
G01X1794502Y423779D01*
G02X1794516Y423819I195J-46D01*
G01X1794546Y423885D01*
X1794567Y423908D01*
X1794569Y423910D01*
G03X1794977Y424939I-1094J1029D01*
G03X1794550Y425988I-1502J0D01*
G01X1794549Y425989D01*
X1794531Y426008D01*
X1794514Y426036D01*
G02X1794489Y426128I175J97D01*
G01Y426245D01*
Y426250D01*
G02X1794514Y426342I200J-5D01*
G01X1794531Y426370D01*
X1794549Y426389D01*
X1794550Y426390D01*
G03X1794977Y427439I-1075J1049D01*
G03X1794569Y428468I-1502J0D01*
G01X1794567Y428470D01*
X1794546Y428493D01*
X1794507Y428578D01*
X1794489Y428618D01*
Y433082D01*
G02X1794502Y433153I200J0D01*
G01X1794513Y433182D01*
G02X1794520Y433199I189J-68D01*
G03X1794561Y433255I-1036J801D01*
G02X1794612Y433291I139J-143D01*
G01X1794680Y433324D01*
G02X1794768Y433345I89J-179D01*
G01X1795000D01*
G02X1795095Y433321I0J-200D01*
G01X1795172Y433280D01*
G02X1795209Y433254I-96J-176D01*
G01X1795216Y433248D01*
X1795224Y433241D01*
X1795227Y433237D01*
X1795237Y433223D01*
X1795239Y433221D01*
G03X1796283Y432697I1044J778D01*
G03Y435301I0J1302D01*
G03X1795239Y434777I0J-1302D01*
G01X1795237Y434775D01*
X1795227Y434761D01*
X1795224Y434757D01*
X1795217Y434751D01*
X1795209Y434744D01*
G02X1795173Y434719I-131J151D01*
G01X1795086Y434673D01*
G02X1795000Y434653I-87J180D01*
G01X1794790D01*
G02X1794747Y434658I1J200D01*
G01X1794701Y434669D01*
G02X1794659Y434684I46J195D01*
G01X1794604Y434711D01*
G02X1794562Y434742I97J175D01*
G03X1794520Y434800I-1082J-739D01*
G02X1794516Y434808I177J93D01*
G01X1794513Y434816D01*
X1794502Y434845D01*
G02X1794489Y434916I187J71D01*
G01Y436626D01*
G02X1794502Y436697I200J0D01*
G01X1794513Y436726D01*
G02X1794520Y436743I189J-68D01*
G03X1794561Y436799I-1036J801D01*
G02X1794612Y436835I139J-143D01*
G01X1794680Y436868D01*
G02X1794768Y436889I89J-179D01*
G01X1795000D01*
G02X1795095Y436865I0J-200D01*
G01X1795172Y436824D01*
G02X1795209Y436798I-96J-176D01*
G01X1795216Y436792D01*
X1795224Y436785D01*
X1795227Y436781D01*
X1795237Y436767D01*
X1795239Y436765D01*
G03X1796283Y436241I1044J778D01*
G03Y438845I0J1302D01*
G03X1795239Y438321I0J-1302D01*
G01X1795237Y438319D01*
X1795227Y438305D01*
X1795224Y438301D01*
X1795217Y438295D01*
X1795209Y438288D01*
G02X1795173Y438263I-131J151D01*
G01X1795086Y438217D01*
G02X1795000Y438197I-87J180D01*
G01X1794790D01*
G02X1794747Y438202I1J200D01*
G01X1794701Y438213D01*
G02X1794659Y438228I46J195D01*
G01X1794604Y438255D01*
G02X1794562Y438286I97J175D01*
G03X1794520Y438344I-1082J-739D01*
G02X1794516Y438352I177J93D01*
G01X1794513Y438360D01*
X1794502Y438389D01*
G02X1794489Y438460I187J71D01*
G01Y440169D01*
G02X1794502Y440240I200J0D01*
G01X1794513Y440269D01*
G02X1794520Y440286I189J-68D01*
G03X1794561Y440342I-1036J801D01*
G02X1794612Y440378I139J-143D01*
G01X1794680Y440411D01*
G02X1794768Y440432I89J-179D01*
G01X1795000D01*
G02X1795095Y440408I0J-200D01*
G01X1795172Y440367D01*
G02X1795209Y440341I-96J-176D01*
G01X1795216Y440334D01*
X1795224Y440328D01*
X1795227Y440324D01*
X1795237Y440310D01*
X1795239Y440308D01*
G03X1796283Y439784I1044J778D01*
G03Y442388I0J1302D01*
G03X1795239Y441864I0J-1302D01*
G01X1795237Y441862D01*
X1795227Y441848D01*
X1795224Y441844D01*
X1795217Y441838D01*
X1795209Y441831D01*
G02X1795173Y441806I-131J151D01*
G01X1795086Y441760D01*
G02X1795000Y441740I-87J180D01*
G01X1794790D01*
G02X1794747Y441745I1J200D01*
G01X1794701Y441756D01*
G02X1794659Y441771I46J195D01*
G01X1794604Y441798D01*
G02X1794562Y441829I97J175D01*
G03X1794520Y441887I-1082J-739D01*
G02X1794516Y441895I177J93D01*
G01X1794513Y441903D01*
X1794502Y441932D01*
G02X1794489Y442003I187J71D01*
G01Y443712D01*
G02X1794502Y443783I200J0D01*
G01X1794513Y443812D01*
G02X1794520Y443829I189J-68D01*
G03X1794561Y443885I-1036J801D01*
G02X1794612Y443921I139J-143D01*
G01X1794680Y443954D01*
G02X1794768Y443975I89J-179D01*
G01X1795000D01*
G02X1795095Y443951I0J-200D01*
G01X1795172Y443910D01*
G02X1795209Y443884I-96J-176D01*
G01X1795216Y443878D01*
X1795224Y443871D01*
X1795227Y443867D01*
X1795237Y443853D01*
X1795239Y443851D01*
G03X1796283Y443327I1044J778D01*
G03Y445931I0J1302D01*
G03X1795239Y445407I0J-1302D01*
G01X1795237Y445405D01*
X1795227Y445391D01*
X1795224Y445387D01*
X1795217Y445381D01*
X1795209Y445374D01*
G02X1795173Y445349I-131J151D01*
G01X1795086Y445303D01*
G02X1795000Y445283I-87J180D01*
G01X1794790D01*
G02X1794747Y445288I1J200D01*
G01X1794701Y445299D01*
G02X1794659Y445314I46J195D01*
G01X1794604Y445341D01*
G02X1794562Y445372I97J175D01*
G03X1794520Y445430I-1082J-739D01*
G02X1794516Y445438I177J93D01*
G01X1794513Y445446D01*
X1794502Y445475D01*
G02X1794489Y445546I187J71D01*
G01Y469897D01*
G02X1794606Y470079I200J0D01*
G01X1794697Y470120D01*
X1794939Y470230D01*
G02X1795031Y470239I65J-189D01*
G01X1795056Y470234D01*
G02X1795067Y470231I-47J-194D01*
G01X1795151Y470199D01*
X1795177Y470178D01*
X1795178Y470177D01*
G03X1796136Y469832I958J1158D01*
G03X1797638Y471334I0J1502D01*
G03X1796169Y472836I-1502J0D01*
G01X1796134D01*
G03X1795180Y472493I1J-1502D01*
G01X1795177Y472491D01*
X1795132Y472465D01*
G02X1795103Y472451I-101J173D01*
G01X1795071Y472439D01*
G02X1794965Y472431I-68J189D01*
G02X1794920Y472446I40J196D01*
G01X1794860Y472473D01*
X1794858D01*
X1794593Y472595D01*
G02X1794579Y472603I92J178D01*
G02X1794490Y472748I110J167D01*
G02X1794489Y472765I199J20D01*
G01Y485466D01*
G03X1794430Y485608I-200J0D01*
G01X1787492Y492546D01*
G03X1787350Y492605I-142J-141D01*
G01X1749361D01*
G02X1749287Y492619I0J200D01*
G01X1749255Y492632D01*
X1749221Y492662D01*
G02X1749219Y492664I140J142D01*
G01X1749026Y492841D01*
G02X1748983Y492899I136J146D01*
G01X1748966Y492932D01*
X1748963Y492970D01*
G03X1748512Y493916I-1496J-133D01*
G01X1748483Y493943D01*
X1748434Y494056D01*
G02X1748419Y494130I185J76D01*
G01Y494323D01*
G02X1748422Y494353I199J-5D01*
G01X1748429Y494394D01*
X1748433Y494419D01*
X1748460Y494478D01*
G02X1748471Y494498I180J-86D01*
G01X1748509Y494553D01*
X1748523Y494567D01*
G03X1748970Y495634I-1055J1069D01*
G01Y495638D01*
G03X1748969Y495668I-1502J-35D01*
G01X1748968Y495686D01*
G03X1747467Y497138I-1501J-50D01*
G03X1745965Y495636I0J-1502D01*
G01Y495635D01*
G03X1746423Y494555I1502J0D01*
G02X1746467Y494492I-139J-144D01*
G01X1746498Y494423D01*
G02X1746515Y494343I-183J-81D01*
G01Y494130D01*
G02X1746500Y494056I-200J2D01*
G01X1746451Y493943D01*
X1746422Y493916D01*
G03X1745971Y492970I1045J-1079D01*
G01X1745968Y492932D01*
X1745951Y492899D01*
G02X1745908Y492841I-179J88D01*
G01X1745715Y492664D01*
G02X1745713Y492662I-142J140D01*
G01X1745705Y492655D01*
G02X1745646Y492619I-132J150D01*
G01X1745611Y492605D01*
X1733402D01*
G02X1733276Y492650I0J200D01*
G02X1733261Y492663I123J157D01*
G01X1729206Y496718D01*
G02X1729170Y496768I142J140D01*
G02X1729148Y496859I178J91D01*
G01Y501422D01*
G02X1729163Y501499I200J1D01*
G01X1733753Y512578D01*
G02X1733796Y512643I185J-76D01*
G01X1734457Y513305D01*
G03X1735309Y514578I-2774J2778D01*
G01X1769264Y596550D01*
G03X1769562Y598048I-3629J1500D01*
G01Y629791D01*
G03X1769429Y630804I-3926J0D01*
G01X1768050Y635966D01*
G03X1767658Y636915I-3794J-1012D01*
G01X1734176Y694939D01*
G02X1734156Y694986I172J101D01*
G01X1731055Y706354D01*
G02X1731048Y706389I192J57D01*
G01X1716457Y873156D01*
G02Y873190I199J17D01*
G01X1725759Y979786D01*
G02X1725791Y979878I199J-18D01*
G01X1737555Y997719D01*
Y997721D01*
X1763696Y1036838D01*
G03X1764059Y1037517I-3265J2182D01*
G01X1764493Y1038566D01*
G02X1764511Y1038600I185J-76D01*
G01X1766081Y1040982D01*
G03X1766530Y1041911I-3248J2143D01*
G01X1769002Y1049450D01*
G02X1769007Y1049464I191J-60D01*
G01X1769462Y1050560D01*
G03X1769743Y1051694I-3628J1501D01*
G01X1769745Y1051715D01*
X1772153Y1059059D01*
G03X1772346Y1060230I-3698J1211D01*
G01X1772519Y1076345D01*
Y1076363D01*
G03X1772522Y1076467I-3888J164D01*
G01Y1076469D01*
G03X1772520Y1076572I-3892J-24D01*
G01Y1076751D01*
G03X1772090Y1078528I-3891J-1D01*
G01X1763587Y1095066D01*
G03X1762815Y1096100I-3461J-1779D01*
G01X1743152Y1114895D01*
G02X1743114Y1114955I147J135D01*
G01X1743108Y1114970D01*
G02X1743099Y1115031I191J59D01*
G01Y1115032D01*
G02X1743299Y1115232I200J0D01*
G01X1743342D01*
X1743447Y1115189D01*
X1743462Y1115179D01*
X1743505Y1115152D01*
X1743518Y1115140D01*
G03X1744529Y1114749I1011J1112D01*
G03Y1117753I0J1502D01*
G01X1744527D01*
G03X1743636Y1117458I3J-1501D01*
G01X1743634D01*
G03X1743585Y1117420I896J-1206D01*
G02X1743583Y1117418I-140J138D01*
G01X1743564Y1117407D01*
G02X1743470Y1117383I-95J176D01*
G01X1743384D01*
G03X1743301Y1117365I0J-200D01*
G01X1743245Y1117339D01*
G02X1743108Y1117328I-84J182D01*
G03X1742029Y1117776I-1079J-1075D01*
G03X1740925Y1117302I1J-1524D01*
G02X1740757Y1117241I-145J138D01*
G02X1740642Y1117295I23J199D01*
G01X1724860Y1132381D01*
G03X1724807Y1132431I-2697J-2806D01*
G01X1724777Y1132459D01*
X1724761Y1132496D01*
G02X1724743Y1132574I182J83D01*
G01X1724741Y1132708D01*
X1724738Y1132862D01*
G02X1724758Y1132953I200J4D01*
G01X1724773Y1132984D01*
X1724865Y1133076D01*
G02X1724930Y1133119I141J-142D01*
G01X1724966Y1133134D01*
X1725006D01*
G03X1726127Y1133634I2J1502D01*
G02X1726273Y1133698I147J-136D01*
G01X1727833D01*
G02X1727965Y1133649I1J-200D01*
G03X1730051I1043J1079D01*
G02X1730183Y1133698I131J-151D01*
G01X1731706D01*
G02X1731838Y1133649I1J-200D01*
G03X1733924I1043J1079D01*
G02X1734056Y1133698I131J-151D01*
G01X1746112D01*
G03X1746254Y1133757I0J200D01*
G01X1767052Y1154555D01*
G03X1767111Y1154697I-141J142D01*
G01Y1202697D01*
G02X1767119Y1202752I200J-1D01*
G01X1767126Y1202777D01*
X1767195Y1202889D01*
G02X1767232Y1202933I170J-105D01*
G01X1767250Y1202950D01*
X1767279Y1202964D01*
G03X1767278Y1227036I-5665J12036D01*
G01X1767252Y1227049D01*
X1767229Y1227069D01*
G02X1767195Y1227108I133J150D01*
G01X1767141Y1227197D01*
G02X1767111Y1227302I170J105D01*
G01Y1269357D01*
G02X1767115Y1269396I200J-1D01*
G02X1767168Y1269497I196J-39D01*
G01X1776551Y1278880D01*
G02X1776653Y1278933I139J-143D01*
G02X1776691Y1278937I40J-196D01*
G01X1837510D01*
G02X1837549Y1278933I-1J-200D01*
G02X1837650Y1278880I-39J-196D01*
G01X1838491Y1278039D01*
G02X1838544Y1277937I-143J-139D01*
G02X1838548Y1277899I-196J-40D01*
G01Y1205524D01*
G03X1838607Y1205382I200J0D01*
G37*
G36*
G01X1778860Y202336D02*
X1782371D01*
G02X1782512Y202278I0J-200D01*
G01X1784552Y200238D01*
X1784567Y200207D01*
G03X1784606Y200132I1352J655D01*
G01X1784619Y200109D01*
G03X1784622Y200104I1290J770D01*
G01X1784635Y200082D01*
X1784656Y200008D01*
G02X1784664Y199953I-192J-56D01*
G01Y197600D01*
G02X1784631Y197490I-200J0D01*
G03Y195840I1254J-825D01*
G02X1784664Y195730I-167J-110D01*
G01Y193746D01*
G02X1784619Y193619I-200J-1D01*
G03Y191711I1160J-954D01*
G02X1784664Y191584I-155J-126D01*
G01Y187537D01*
G02X1784659Y187492I-200J-1D01*
G01X1784649Y187447D01*
G02X1784635Y187408I-194J48D01*
G03X1784507Y186954I1364J-630D01*
G03X1784497Y186778I1492J-173D01*
G03X1784638Y186142I1502J-1D01*
G01X1784639Y186140D01*
X1784644Y186129D01*
X1784652Y186106D01*
G02X1784664Y186038I-188J-68D01*
G01Y181600D01*
G02X1784631Y181490I-200J0D01*
G03Y179840I1254J-825D01*
G02X1784664Y179730I-167J-110D01*
G01Y177600D01*
G02X1784631Y177490I-200J0D01*
G03Y175840I1254J-825D01*
G02X1784664Y175730I-167J-110D01*
G01Y173600D01*
G02X1784631Y173490I-200J0D01*
G03Y171840I1254J-825D01*
G02X1784664Y171730I-167J-110D01*
G01Y169600D01*
G02X1784631Y169490I-200J0D01*
G03Y167840I1254J-825D01*
G02X1784664Y167730I-167J-110D01*
G01Y117195D01*
G02X1784634Y117089I-200J-1D01*
G01X1784582Y117007D01*
G03X1784552Y116901I170J-105D01*
G01Y111688D01*
G03X1784582Y111583I200J0D01*
G01X1784633Y111504D01*
G02X1784664Y111396I-169J-107D01*
G01Y109734D01*
G02X1784605Y109592I-200J0D01*
G01X1783662Y108649D01*
X1783634Y108620D01*
X1783560Y108590D01*
X1746848D01*
G02X1746683Y108676I-1J200D01*
G03X1745202Y109452I-1482J-1027D01*
G03X1743721Y108676I1J-1803D01*
G02X1743556Y108590I-164J114D01*
G01X1727275D01*
G02X1727133Y108649I0J200D01*
G01X1726074Y109708D01*
X1726049Y109753D01*
X1726042Y109780D01*
G03X1724956Y110866I-1456J-370D01*
G01X1724929Y110873D01*
X1724884Y110898D01*
X1724822Y110960D01*
X1724793Y110988D01*
X1724763Y111062D01*
Y114907D01*
X1724850Y115016D01*
X1724919Y115031D01*
G03Y117961I-333J1465D01*
G01X1724850Y117976D01*
X1724763Y118085D01*
Y122963D01*
X1724863Y123076D01*
X1724939Y123085D01*
G03Y126067I-181J1491D01*
G01X1724863Y126076D01*
X1724763Y126189D01*
Y159263D01*
G02X1724822Y159405I200J0D01*
G01X1725685Y160268D01*
G02X1725827Y160327I142J-141D01*
G01X1761344D01*
G03X1761486Y160386I0J200D01*
G01X1765191Y164091D01*
G03X1765250Y164233I-141J142D01*
G01Y201567D01*
G02X1765307Y201707I200J0D01*
G01X1765308Y201708D01*
X1765877Y202277D01*
G02X1766019Y202336I142J-141D01*
G01X1775718D01*
G02X1775895Y202230I0J-200D01*
G01X1776060Y201918D01*
G02X1776048Y201711I-177J-94D01*
G01Y201710D01*
G03X1775787Y200864I1241J-846D01*
G01Y200837D01*
G03X1778791I1502J27D01*
G01Y200864D01*
G03X1778530Y201710I-1502J0D01*
G01Y201711D01*
G02X1778518Y201918I165J113D01*
G01X1778683Y202230D01*
G02X1778860Y202336I177J-94D01*
G37*
G36*
G01X1836948Y1225604D02*
X1838945D01*
Y970426D01*
G02X1837225Y966273I-5874J0D01*
G01X1826876Y955925D01*
G03X1823984Y948944I6982J-6982D01*
G01Y344836D01*
G03X1826876Y337855I9873J0D01*
G01X1837225Y327506D01*
G02X1838945Y323354I-4153J-4153D01*
G01Y7874D01*
G02X1833071Y2000I-5874J0D01*
G01X1756949D01*
G02X1751075Y7874I0J5874D01*
G01Y46654D01*
G03X1749600Y50571I-5938J0D01*
G01Y50666D01*
X1749606Y50672D01*
X1751979D01*
G02X1753072Y46654I-6841J-4019D01*
G01Y7874D01*
G03X1756947Y3998I3876J0D01*
G01X1833071D01*
G03X1836948Y7874I0J3877D01*
G01Y323354D01*
G03X1835813Y326094I-3876J0D01*
G01X1825464Y336443D01*
G02X1821987Y344836I8393J8394D01*
G01X1821986D01*
Y948944D01*
X1821987D01*
G02X1825464Y957337I11871J-1D01*
G01X1835813Y967685D01*
G03X1836948Y970426I-2742J2741D01*
G01Y1225604D01*
G37*
G36*
G01X1761656Y275932D02*
X1783551D01*
G02X1783693Y275873I0J-200D01*
G01X1784304Y275262D01*
G02X1784363Y275120I-141J-142D01*
G01Y205060D01*
G02X1784304Y204918I-200J0D01*
G01X1782783Y203397D01*
G02X1782641Y203338I-142J141D01*
G01X1761814D01*
G02X1761672Y203397I0J200D01*
G01X1761514Y203555D01*
G02X1761456Y203696I142J141D01*
G01Y204859D01*
G02X1761516Y205001I200J-1D01*
G01X1761750Y205230D01*
X1761823Y205259D01*
X1761864Y205258D01*
X1761898D01*
G03Y208262I0J1502D01*
G01X1761864D01*
X1761823Y208261D01*
X1761750Y208290D01*
X1761516Y208519D01*
G02X1761456Y208661I140J143D01*
G01Y255107D01*
G02X1761573Y255289I200J0D01*
G01X1761959Y255464D01*
X1762075Y255446D01*
X1762120Y255407D01*
G03X1763112Y255033I992J1129D01*
G03Y258037I0J1502D01*
G03X1762120Y257663I0J-1503D01*
G01X1762075Y257624D01*
X1761959Y257606D01*
X1761573Y257781D01*
G02X1761456Y257963I83J182D01*
G01Y275732D01*
G02X1761656Y275932I200J0D01*
G37*
%LPC*%
G75*
G36*
G01X895451Y272012D02*
G02X898455I1502J0D01*
G01Y272011D01*
G02X898306Y271359I-1502J0D01*
G01X898288Y271321D01*
X898285Y271236D01*
X898417Y270919D01*
G03X898535Y270807I185J77D01*
G01X898536D01*
G02X899550Y269387I-487J-1420D01*
G02X896546I-1502J0D01*
G01Y269388D01*
G02X896695Y270040I1502J0D01*
G01X896713Y270078D01*
X896716Y270163D01*
X896584Y270480D01*
G03X896466Y270592I-185J-77D01*
G01X896465D01*
G02X895451Y272012I487J1420D01*
G37*
G36*
G01X870548Y302644D02*
G02X873552I1502J0D01*
G02X873418Y302024I-1501J0D01*
G01X873400Y301985D01*
Y301897D01*
X873565Y301543D01*
X873630Y301487D01*
X873673Y301475D01*
G02X874764Y300030I-411J-1445D01*
G02X871760I-1502J0D01*
G02X871894Y300650I1501J0D01*
G01X871912Y300689D01*
Y300777D01*
X871747Y301131D01*
X871682Y301187D01*
X871639Y301199D01*
G02X870548Y302644I411J1445D01*
G37*
G36*
G01X905899Y304150D02*
X909299D01*
G02Y300544I0J-1803D01*
G01X905899D01*
G02Y304150I0J1803D01*
G37*
G36*
G01X415777Y306272D02*
X419177D01*
G02Y302668I0J-1802D01*
G01X415777D01*
G02Y306272I0J1802D01*
G37*
G36*
G01X431525D02*
X434925D01*
G02Y302668I0J-1802D01*
G01X431525D01*
G02Y306272I0J1802D01*
G37*
G36*
G01X876475Y305368D02*
G02X879479I1502J0D01*
G02X879181Y304470I-1502J0D01*
G03X879420Y303839I320J-239D01*
G02X880614Y302369I-308J-1470D01*
G02X877610I-1502J0D01*
G02X877908Y303267I1502J0D01*
G03X877669Y303898I-320J239D01*
G02X876475Y305368I308J1470D01*
G37*
G36*
G01X423651Y309272D02*
X427051D01*
G02Y305668I0J-1802D01*
G01X423651D01*
G02Y309272I0J1802D01*
G37*
G36*
G01X1020933Y312865D02*
G02X1023937I1502J0D01*
G02X1023292Y311631I-1503J0D01*
G01X1023262Y311611D01*
X1023220Y311549D01*
X1023150Y311253D01*
G03X1023168Y311112I194J-47D01*
G02X1023350Y310396I-1320J-717D01*
G02X1020346I-1502J0D01*
G02X1020991Y311630I1503J0D01*
G01X1021021Y311650D01*
X1021063Y311712D01*
X1021133Y312008D01*
G03X1021115Y312149I-194J47D01*
G02X1020933Y312865I1320J717D01*
G37*
G36*
G01X511790Y312302D02*
G02Y315306I0J1502D01*
G02X513206Y314306I0J-1503D01*
G03X513832Y314127I377J134D01*
G02X514769Y314455I937J-1174D01*
G02Y311451I0J-1502D01*
G02X513353Y312451I0J1503D01*
G03X512727Y312630I-377J-134D01*
G02X511790Y312302I-937J1174D01*
G37*
G36*
G01X807987Y313830D02*
G02X810991I1502J0D01*
G02X810276Y312551I-1501J0D01*
G03X810271Y311872I209J-341D01*
G02X810968Y310604I-805J-1268D01*
G02X807964I-1502J0D01*
G02X808679Y311883I1501J0D01*
G03X808684Y312562I-209J341D01*
G02X807987Y313830I805J1268D01*
G37*
G36*
G01X313577Y314890D02*
G02X316581I1502J0D01*
G02X315826Y313587I-1502J0D01*
G03X315779Y312924I199J-347D01*
G02X316357Y311740I-924J-1184D01*
G02X313353I-1502J0D01*
G02X314108Y313043I1502J0D01*
G03X314155Y313706I-199J347D01*
G02X313577Y314890I924J1184D01*
G37*
G36*
G01X770663D02*
G02X773667I1502J0D01*
G02X772912Y313587I-1502J0D01*
G03X772865Y312924I199J-347D01*
G02X773443Y311740I-924J-1184D01*
G02X770439I-1502J0D01*
G02X771194Y313043I1502J0D01*
G03X771241Y313706I-199J347D01*
G02X770663Y314890I924J1184D01*
G37*
G36*
G01X405843Y316660D02*
G02Y313656I0J-1502D01*
G02X404856Y314026I0J1501D01*
G01X404855D01*
Y314027D01*
G03X404725Y314075I-130J-152D01*
G01X404461D01*
G03X404331Y314027I0J-200D01*
G01X404330Y314026D01*
G02X403343Y313656I-987J1131D01*
G02Y316660I0J1502D01*
G02X404330Y316290I0J-1501D01*
G01X404331D01*
Y316289D01*
G03X404461Y316241I130J152D01*
G01X404725D01*
G03X404855Y316289I0J200D01*
G01X404856Y316290D01*
G02X405843Y316660I987J-1131D01*
G37*
G36*
G01X807988Y333368D02*
G02X810992I1502J0D01*
G01Y333367D01*
G02X810445Y332208I-1502J0D01*
G01X810410Y332179D01*
X810372Y332101D01*
X810368Y331706D01*
X810404Y331625D01*
X810438Y331597D01*
G02X810959Y330459I-982J-1138D01*
G02X807955I-1502J0D01*
G01Y330460D01*
G02X808502Y331619I1502J0D01*
G01X808537Y331648D01*
X808575Y331726D01*
X808579Y332121D01*
X808543Y332202D01*
X808509Y332230D01*
G02X807988Y333368I982J1138D01*
G37*
G36*
G01X916228Y338136D02*
X919628D01*
G02Y334530I0J-1803D01*
G01X916228D01*
G02Y338136I0J1803D01*
G37*
G36*
G01X445299Y338724D02*
G02X446566Y339419I1267J-807D01*
G02Y336415I0J-1502D01*
G02X445418Y336949I0J1501D01*
G03X444775Y336906I-306J-258D01*
G02X443508Y336211I-1267J807D01*
G02Y339215I0J1502D01*
G02X444656Y338681I0J-1501D01*
G03X445299Y338724I306J258D01*
G37*
G36*
G01X988918Y340454D02*
G02X991922I1502J0D01*
G02X991552Y339467I-1501J0D01*
G01Y339466D01*
X991551D01*
G03X991503Y339336I152J-130D01*
G01Y339072D01*
G03X991551Y338942I200J0D01*
G01X991552Y338941D01*
G02X991922Y337954I-1131J-987D01*
G02X988918I-1502J0D01*
G02X989288Y338941I1501J0D01*
G01Y338942D01*
X989289D01*
G03X989337Y339072I-152J130D01*
G01Y339336D01*
G03X989289Y339466I-200J0D01*
G01X989288Y339467D01*
G02X988918Y340454I1131J987D01*
G37*
G36*
G01X924563Y345844D02*
X927963D01*
G02Y342238I0J-1803D01*
G01X924563D01*
G02Y345844I0J1803D01*
G37*
G36*
G01X915953Y345952D02*
X919353D01*
G02Y342348I0J-1802D01*
G01X915953D01*
G02Y345952I0J1802D01*
G37*
G36*
G01X426138Y353577D02*
G02Y356581I0J1502D01*
G02X427614Y355360I0J-1503D01*
G01X427621Y355320D01*
X427666Y355253D01*
X427975Y355050D01*
X428053Y355035D01*
X428093Y355044D01*
G02X428420Y355080I327J-1467D01*
G02Y352076I0J-1502D01*
G02X426944Y353297I0J1503D01*
G01X426937Y353337D01*
X426892Y353404D01*
X426583Y353607D01*
X426505Y353622D01*
X426465Y353613D01*
G02X426138Y353577I-327J1467D01*
G37*
G36*
G01X308952Y355373D02*
G02Y358377I0J1502D01*
G02X310307Y357523I0J-1502D01*
G01X310331Y357473D01*
X310424Y357412D01*
X310890Y357394D01*
X310986Y357447D01*
X311014Y357496D01*
G02X312316Y358249I1302J-749D01*
G02X313509Y357660I0J-1503D01*
G01X313537Y357623D01*
X313619Y357581D01*
X313981Y357577D01*
G03X314139Y357652I2J200D01*
G02X315310Y358214I1171J-939D01*
G02X316619Y357449I0J-1502D01*
G01X316644Y357405D01*
X316730Y357351D01*
X317117Y357327D01*
G03X317290Y357407I13J200D01*
G01Y357408D01*
G02X318500Y358021I1210J-888D01*
G02X320002Y356519I0J-1502D01*
G02X318759Y355040I-1501J0D01*
G01X318758D01*
G03X318607Y354914I36J-197D01*
G01X318484Y354593D01*
G03X318513Y354399I187J-71D01*
G01X318514Y354398D01*
G02X318835Y353470I-1181J-928D01*
G02X315831I-1502J0D01*
G02X317074Y354949I1501J0D01*
G01X317075D01*
G03X317226Y355075I-36J197D01*
G01X317349Y355396D01*
G03X317320Y355590I-187J71D01*
G01X317319Y355591D01*
G02X317191Y355782I1180J929D01*
G01X317166Y355826D01*
X317080Y355880D01*
X316693Y355904D01*
G03X316520Y355824I-13J-200D01*
G01Y355823D01*
G02X315310Y355210I-1210J888D01*
G02X314117Y355799I0J1503D01*
G01X314089Y355836D01*
X314007Y355878D01*
X313645Y355882D01*
G03X313487Y355807I-2J-200D01*
G02X312316Y355245I-1171J939D01*
G02X310961Y356099I0J1502D01*
G01X310937Y356149D01*
X310844Y356210D01*
X310378Y356228D01*
X310282Y356175D01*
X310254Y356126D01*
G02X308952Y355373I-1302J749D01*
G37*
G36*
G01X907123Y359317D02*
G02X910127I1502J0D01*
G02X909675Y358243I-1502J0D01*
G01X909648Y358216D01*
X909617Y358148D01*
X909604Y357834D01*
G03X909653Y357695I200J-8D01*
G02X910023Y356708I-1131J-987D01*
G02X908521Y355206I-1502J0D01*
G02X907623Y355504I0J1502D01*
G01X907622D01*
G03X907417Y355524I-119J-160D01*
G01X907098Y355373D01*
G03X906984Y355200I86J-181D01*
G02X905483Y353760I-1501J62D01*
G02Y356764I0J1502D01*
G02X906381Y356466I0J-1502D01*
G01X906382D01*
G03X906587Y356446I119J160D01*
G01X906906Y356597D01*
G03X907020Y356770I-86J181D01*
G02X907471Y357782I1501J-62D01*
G01X907498Y357809D01*
X907529Y357877D01*
X907542Y358191D01*
G03X907493Y358330I-200J8D01*
G02X907123Y359317I1131J987D01*
G37*
G36*
G01X431524Y372112D02*
X434924D01*
G02Y368506I0J-1803D01*
G01X431524D01*
G02Y372112I0J1803D01*
G37*
G36*
G01X394237Y378089D02*
X394236D01*
G02X393756Y378168I1J1502D01*
G03X393230Y377746I-128J-379D01*
G02X393239Y377583I-1493J-164D01*
G01Y377581D01*
G02X391737Y379083I-1502J0D01*
G01X391738D01*
G02X392218Y379004I-1J-1502D01*
G03X392744Y379426I128J379D01*
G02X392735Y379589I1493J164D01*
G01Y379591D01*
G02X394237Y378089I1502J0D01*
G37*
G36*
G01X446889Y382641D02*
G02X449893I1502J0D01*
G02X449288Y381436I-1503J0D01*
G01X449251Y381408D01*
X449209Y381327D01*
X449200Y380966D01*
G03X449274Y380806I200J-5D01*
G02X449825Y379643I-952J-1163D01*
G02X446821I-1502J0D01*
G02X447426Y380848I1503J0D01*
G01X447463Y380876D01*
X447505Y380957D01*
X447514Y381318D01*
G03X447440Y381478I-200J5D01*
G02X446889Y382641I952J1163D01*
G37*
G36*
G01X362486Y386625D02*
G02Y383621I0J-1502D01*
G02X361301Y384200I0J1502D01*
G03X361143Y384277I-158J-123D01*
G01X360829D01*
G03X360671Y384200I0J-200D01*
G02X359486Y383621I-1185J923D01*
G02Y386625I0J1502D01*
G02X360671Y386046I0J-1502D01*
G03X360829Y385969I158J123D01*
G01X361143D01*
G03X361301Y386046I0J200D01*
G02X362486Y386625I1185J-923D01*
G37*
G36*
G01X1276659D02*
G02Y383621I0J-1502D01*
G02X1275474Y384200I0J1502D01*
G03X1275316Y384277I-158J-123D01*
G01X1275002D01*
G03X1274844Y384200I0J-200D01*
G02X1273659Y383621I-1185J923D01*
G02Y386625I0J1502D01*
G02X1274844Y386046I0J-1502D01*
G03X1275002Y385969I158J123D01*
G01X1275316D01*
G03X1275474Y386046I0J200D01*
G02X1276659Y386625I1185J-923D01*
G37*
G36*
G01X1334285Y388069D02*
G02Y385065I0J-1502D01*
G02X1333227Y385501I0J1502D01*
G01X1333199Y385529D01*
X1333126Y385559D01*
X1332765D01*
X1332692Y385529D01*
X1332664Y385501D01*
G02X1331606Y385065I-1058J1066D01*
G02X1330536Y385513I0J1502D01*
G03X1330393Y385573I-143J-140D01*
G01X1330109D01*
G03X1329966Y385513I0J-200D01*
G02X1328896Y385065I-1070J1054D01*
G02Y388069I0J1502D01*
G02X1329966Y387621I0J-1502D01*
G03X1330109Y387561I143J140D01*
G01X1330393D01*
G03X1330536Y387621I0J200D01*
G02X1331606Y388069I1070J-1054D01*
G02X1332664Y387633I0J-1502D01*
G01X1332692Y387605D01*
X1332765Y387575D01*
X1333126D01*
X1333199Y387605D01*
X1333227Y387633D01*
G02X1334285Y388069I1058J-1066D01*
G37*
G36*
G01X404919Y387151D02*
G02X407923I1502J0D01*
G02X407553Y386164I-1501J0D01*
G01Y386163D01*
X407552D01*
G03X407504Y386033I152J-130D01*
G01Y385769D01*
G03X407552Y385639I200J0D01*
G01X407553Y385638D01*
G02Y383664I-1131J-987D01*
G01Y383663D01*
X407552D01*
G03X407504Y383533I152J-130D01*
G01Y383269D01*
G03X407552Y383139I200J0D01*
G01X407553Y383138D01*
G02X407923Y382151I-1131J-987D01*
G02X404919I-1502J0D01*
G02X405289Y383138I1501J0D01*
G01Y383139D01*
X405290D01*
G03X405338Y383269I-152J130D01*
G01Y383533D01*
G03X405290Y383663I-200J0D01*
G01X405289Y383664D01*
G02Y385638I1131J987D01*
G01Y385639D01*
X405290D01*
G03X405338Y385769I-152J130D01*
G01Y386033D01*
G03X405290Y386163I-200J0D01*
G01X405289Y386164D01*
G02X404919Y387151I1131J987D01*
G37*
G36*
G01X1319092D02*
G02X1322096I1502J0D01*
G02X1321726Y386164I-1501J0D01*
G01Y386163D01*
X1321725D01*
G03X1321677Y386033I152J-130D01*
G01Y385769D01*
G03X1321725Y385639I200J0D01*
G01X1321726Y385638D01*
G02Y383664I-1131J-987D01*
G01Y383663D01*
X1321725D01*
G03X1321677Y383533I152J-130D01*
G01Y383269D01*
G03X1321725Y383139I200J0D01*
G01X1321726Y383138D01*
G02X1322096Y382151I-1131J-987D01*
G02X1319092I-1502J0D01*
G02X1319462Y383138I1501J0D01*
G01Y383139D01*
X1319463D01*
G03X1319511Y383269I-152J130D01*
G01Y383533D01*
G03X1319463Y383663I-200J0D01*
G01X1319462Y383664D01*
G02Y385638I1131J987D01*
G01Y385639D01*
X1319463D01*
G03X1319511Y385769I-152J130D01*
G01Y386033D01*
G03X1319463Y386163I-200J0D01*
G01X1319462Y386164D01*
G02X1319092Y387151I1131J987D01*
G37*
G36*
G01X417495Y387210D02*
G02X420499I1502J0D01*
G02X420129Y386223I-1501J0D01*
G01Y386222D01*
X420128D01*
G03X420080Y386092I152J-130D01*
G01Y385828D01*
G03X420128Y385698I200J0D01*
G01X420129Y385697D01*
G02Y383723I-1131J-987D01*
G01Y383722D01*
X420128D01*
G03X420080Y383592I152J-130D01*
G01Y383328D01*
G03X420128Y383198I200J0D01*
G01X420129Y383197D01*
G02X420499Y382210I-1131J-987D01*
G02X417495I-1502J0D01*
G02X417865Y383197I1501J0D01*
G01Y383198D01*
X417866D01*
G03X417914Y383328I-152J130D01*
G01Y383592D01*
G03X417866Y383722I-200J0D01*
G01X417865Y383723D01*
G02Y385697I1131J987D01*
G01Y385698D01*
X417866D01*
G03X417914Y385828I-152J130D01*
G01Y386092D01*
G03X417866Y386222I-200J0D01*
G01X417865Y386223D01*
G02X417495Y387210I1131J987D01*
G37*
G36*
G01X401253Y389204D02*
G02Y386200I0J-1502D01*
G02X400147Y386685I0J1504D01*
G03X400000Y386750I-148J-135D01*
G01X399706D01*
G03X399559Y386685I1J-200D01*
G02X398453Y386200I-1106J1019D01*
G02Y389204I0J1502D01*
G02X399559Y388719I0J-1504D01*
G03X399706Y388654I148J135D01*
G01X400000D01*
G03X400147Y388719I-1J200D01*
G02X401253Y389204I1106J-1019D01*
G37*
G36*
G01X1315426D02*
G02Y386200I0J-1502D01*
G02X1314320Y386685I0J1504D01*
G03X1314173Y386750I-148J-135D01*
G01X1313879D01*
G03X1313732Y386685I1J-200D01*
G02X1312626Y386200I-1106J1019D01*
G02Y389204I0J1502D01*
G02X1313732Y388719I0J-1504D01*
G03X1313879Y388654I148J135D01*
G01X1314173D01*
G03X1314320Y388719I-1J200D01*
G02X1315426Y389204I1106J-1019D01*
G37*
G36*
G01X394653Y390904D02*
G02Y387900I0J-1502D01*
G02X393798Y388167I0J1502D01*
G01X393764Y388190D01*
X393683Y388207D01*
X393316Y388127D01*
X393249Y388079D01*
X393228Y388044D01*
G02X393072Y387831I-1285J777D01*
G03X393071Y387829I173J-88D01*
G03X393023Y387699I152J-130D01*
G01Y387435D01*
G03X393071Y387305I200J0D01*
G01X393072Y387304D01*
G02Y385330I-1131J-987D01*
G01Y385329D01*
X393071D01*
G03X393023Y385199I152J-130D01*
G01Y384935D01*
G03X393071Y384805I200J0D01*
G01X393072Y384804D01*
G02X393442Y383817I-1131J-987D01*
G02X390438I-1502J0D01*
G02X390808Y384804I1501J0D01*
G01Y384805D01*
X390809D01*
G03X390857Y384935I-152J130D01*
G01Y385199D01*
G03X390809Y385329I-200J0D01*
G01X390808Y385330D01*
G02Y387304I1131J987D01*
G01Y387305D01*
X390809D01*
G03X390857Y387435I-152J130D01*
G01Y387699D01*
G03X390809Y387829I-200J0D01*
G01X390808Y387830D01*
G02X390438Y388817I1131J987D01*
G02X391940Y390319I1502J0D01*
G02X392795Y390052I0J-1502D01*
G01X392829Y390029D01*
X392910Y390012D01*
X393277Y390092D01*
X393344Y390140D01*
X393365Y390175D01*
G02X394653Y390904I1288J-773D01*
G37*
G36*
G01X1308826D02*
G02Y387900I0J-1502D01*
G02X1307971Y388167I0J1502D01*
G01X1307937Y388190D01*
X1307856Y388207D01*
X1307489Y388127D01*
X1307422Y388079D01*
X1307401Y388044D01*
G02X1307245Y387831I-1285J777D01*
G03X1307244Y387829I173J-88D01*
G03X1307196Y387699I152J-130D01*
G01Y387435D01*
G03X1307244Y387305I200J0D01*
G01X1307245Y387304D01*
G02Y385330I-1131J-987D01*
G01Y385329D01*
X1307244D01*
G03X1307196Y385199I152J-130D01*
G01Y384935D01*
G03X1307244Y384805I200J0D01*
G01X1307245Y384804D01*
G02X1307615Y383817I-1131J-987D01*
G02X1304611I-1502J0D01*
G02X1304981Y384804I1501J0D01*
G01Y384805D01*
X1304982D01*
G03X1305030Y384935I-152J130D01*
G01Y385199D01*
G03X1304982Y385329I-200J0D01*
G01X1304981Y385330D01*
G02Y387304I1131J987D01*
G01Y387305D01*
X1304982D01*
G03X1305030Y387435I-152J130D01*
G01Y387699D01*
G03X1304982Y387829I-200J0D01*
G01X1304981Y387830D01*
G02X1304611Y388817I1131J987D01*
G02X1306113Y390319I1502J0D01*
G02X1306968Y390052I0J-1502D01*
G01X1307002Y390029D01*
X1307083Y390012D01*
X1307450Y390092D01*
X1307517Y390140D01*
X1307538Y390175D01*
G02X1308826Y390904I1288J-773D01*
G37*
G36*
G01X385864Y399780D02*
G02Y396776I0J-1502D01*
G02X384877Y397146I0J1501D01*
G01X384876D01*
Y397147D01*
G03X384746Y397195I-130J-152D01*
G01X384482D01*
G03X384352Y397147I0J-200D01*
G01X384351Y397146D01*
G02X383364Y396776I-987J1131D01*
G02Y399780I0J1502D01*
G02X384351Y399410I0J-1501D01*
G01X384352D01*
Y399409D01*
G03X384482Y399361I130J152D01*
G01X384746D01*
G03X384876Y399409I0J200D01*
G01X384877Y399410D01*
G02X385864Y399780I987J-1131D01*
G37*
G36*
G01X1300037D02*
G02Y396776I0J-1502D01*
G02X1299050Y397146I0J1501D01*
G01X1299049D01*
Y397147D01*
G03X1298919Y397195I-130J-152D01*
G01X1298655D01*
G03X1298525Y397147I0J-200D01*
G01X1298524Y397146D01*
G02X1297537Y396776I-987J1131D01*
G02Y399780I0J1502D01*
G02X1298524Y399410I0J-1501D01*
G01X1298525D01*
Y399409D01*
G03X1298655Y399361I130J152D01*
G01X1298919D01*
G03X1299049Y399409I0J200D01*
G01X1299050Y399410D01*
G02X1300037Y399780I987J-1131D01*
G37*
G36*
G01X384091Y403483D02*
G02Y400479I0J-1502D01*
G02X383104Y400849I0J1501D01*
G01X383103D01*
Y400850D01*
G03X382973Y400898I-130J-152D01*
G01X382709D01*
G03X382579Y400850I0J-200D01*
G01X382578Y400849D01*
G02X381591Y400479I-987J1131D01*
G02Y403483I0J1502D01*
G02X382578Y403113I0J-1501D01*
G01X382579D01*
Y403112D01*
G03X382709Y403064I130J152D01*
G01X382973D01*
G03X383103Y403112I0J200D01*
G01X383104Y403113D01*
G02X384091Y403483I987J-1131D01*
G37*
G36*
G01X1298264D02*
G02Y400479I0J-1502D01*
G02X1297277Y400849I0J1501D01*
G01X1297276D01*
Y400850D01*
G03X1297146Y400898I-130J-152D01*
G01X1296882D01*
G03X1296752Y400850I0J-200D01*
G01X1296751Y400849D01*
G02X1295764Y400479I-987J1131D01*
G02Y403483I0J1502D01*
G02X1296751Y403113I0J-1501D01*
G01X1296752D01*
Y403112D01*
G03X1296882Y403064I130J152D01*
G01X1297146D01*
G03X1297276Y403112I0J200D01*
G01X1297277Y403113D01*
G02X1298264Y403483I987J-1131D01*
G37*
G36*
G01X900245Y403492D02*
G02X903249I1502J0D01*
G02X902879Y402505I-1501J0D01*
G01Y402504D01*
X902878D01*
G03X902830Y402374I152J-130D01*
G01Y402110D01*
G03X902878Y401980I200J0D01*
G01X902879Y401979D01*
G02Y400005I-1131J-987D01*
G01Y400004D01*
X902878D01*
G03X902830Y399874I152J-130D01*
G01Y399610D01*
G03X902878Y399480I200J0D01*
G01X902879Y399479D01*
G02X903249Y398492I-1131J-987D01*
G02X900245I-1502J0D01*
G02X900615Y399479I1501J0D01*
G01Y399480D01*
X900616D01*
G03X900664Y399610I-152J130D01*
G01Y399874D01*
G03X900616Y400004I-200J0D01*
G01X900615Y400005D01*
G02Y401979I1131J987D01*
G01Y401980D01*
X900616D01*
G03X900664Y402110I-152J130D01*
G01Y402374D01*
G03X900616Y402504I-200J0D01*
G01X900615Y402505D01*
G02X900245Y403492I1131J987D01*
G37*
G36*
G01X912821Y403551D02*
G02X915825I1502J0D01*
G02X915455Y402564I-1501J0D01*
G01Y402563D01*
X915454D01*
G03X915406Y402433I152J-130D01*
G01Y402169D01*
G03X915454Y402039I200J0D01*
G01X915455Y402038D01*
G02Y400064I-1131J-987D01*
G01Y400063D01*
X915454D01*
G03X915406Y399933I152J-130D01*
G01Y399669D01*
G03X915454Y399539I200J0D01*
G01X915455Y399538D01*
G02X915825Y398551I-1131J-987D01*
G02X912821I-1502J0D01*
G02X913191Y399538I1501J0D01*
G01Y399539D01*
X913192D01*
G03X913240Y399669I-152J130D01*
G01Y399933D01*
G03X913192Y400063I-200J0D01*
G01X913191Y400064D01*
G02Y402038I1131J987D01*
G01Y402039D01*
X913192D01*
G03X913240Y402169I-152J130D01*
G01Y402433D01*
G03X913192Y402563I-200J0D01*
G01X913191Y402564D01*
G02X912821Y403551I1131J987D01*
G37*
G36*
G01X896579Y405545D02*
G02Y402541I0J-1502D01*
G02X895473Y403026I0J1504D01*
G03X895326Y403091I-148J-135D01*
G01X895032D01*
G03X894885Y403026I1J-200D01*
G02X893779Y402541I-1106J1019D01*
G02Y405545I0J1502D01*
G02X894885Y405060I0J-1504D01*
G03X895032Y404995I148J135D01*
G01X895326D01*
G03X895473Y405060I-1J200D01*
G02X896579Y405545I1106J-1019D01*
G37*
G36*
G01X889979Y407245D02*
G02Y404241I0J-1502D01*
G02X889124Y404508I0J1502D01*
G01X889090Y404531D01*
X889009Y404548D01*
X888642Y404468D01*
X888575Y404420D01*
X888554Y404385D01*
G02X888398Y404172I-1285J777D01*
G03X888397Y404170I173J-88D01*
G03X888349Y404040I152J-130D01*
G01Y403776D01*
G03X888397Y403646I200J0D01*
G01X888398Y403645D01*
G02Y401671I-1131J-987D01*
G01Y401670D01*
X888397D01*
G03X888349Y401540I152J-130D01*
G01Y401276D01*
G03X888397Y401146I200J0D01*
G01X888398Y401145D01*
G02X888768Y400158I-1131J-987D01*
G02X885764I-1502J0D01*
G02X886134Y401145I1501J0D01*
G01Y401146D01*
X886135D01*
G03X886183Y401276I-152J130D01*
G01Y401540D01*
G03X886135Y401670I-200J0D01*
G01X886134Y401671D01*
G02Y403645I1131J987D01*
G01Y403646D01*
X886135D01*
G03X886183Y403776I-152J130D01*
G01Y404040D01*
G03X886135Y404170I-200J0D01*
G01X886134Y404171D01*
G02X885764Y405158I1131J987D01*
G02X887266Y406660I1502J0D01*
G02X888121Y406393I0J-1502D01*
G01X888155Y406370D01*
X888236Y406353D01*
X888603Y406433D01*
X888670Y406481D01*
X888691Y406516D01*
G02X889979Y407245I1288J-773D01*
G37*
G36*
G01X434237Y409606D02*
G02Y406602I0J-1502D01*
G02X433131Y407087I0J1504D01*
G03X432984Y407152I-148J-135D01*
G01X432690D01*
G03X432543Y407087I1J-200D01*
G02X430331I-1106J1017D01*
G03X430184Y407152I-148J-135D01*
G01X429890D01*
G03X429743Y407087I1J-200D01*
G02X428637Y406602I-1106J1019D01*
G02Y409606I0J1502D01*
G02X429743Y409121I0J-1504D01*
G03X429890Y409056I148J135D01*
G01X430184D01*
G03X430331Y409121I-1J200D01*
G02X432543I1106J-1017D01*
G03X432690Y409056I148J135D01*
G01X432984D01*
G03X433131Y409121I-1J200D01*
G02X434237Y409606I1106J-1019D01*
G37*
G36*
G01X1348410D02*
G02Y406602I0J-1502D01*
G02X1347304Y407087I0J1504D01*
G03X1347157Y407152I-148J-135D01*
G01X1346863D01*
G03X1346716Y407087I1J-200D01*
G02X1344504I-1106J1017D01*
G03X1344357Y407152I-148J-135D01*
G01X1344063D01*
G03X1343916Y407087I1J-200D01*
G02X1342810Y406602I-1106J1019D01*
G02Y409606I0J1502D01*
G02X1343916Y409121I0J-1504D01*
G03X1344063Y409056I148J135D01*
G01X1344357D01*
G03X1344504Y409121I-1J200D01*
G02X1346716I1106J-1017D01*
G03X1346863Y409056I148J135D01*
G01X1347157D01*
G03X1347304Y409121I-1J200D01*
G02X1348410Y409606I1106J-1019D01*
G37*
G36*
G01X381927Y411041D02*
G02X383429Y409539I0J-1502D01*
G02X383059Y408552I-1501J0D01*
G01Y408551D01*
X383058D01*
G03X383010Y408421I152J-130D01*
G01Y408157D01*
G03X383058Y408027I200J0D01*
G01X383059Y408026D01*
G02X383429Y407039I-1131J-987D01*
G02X381927Y405537I-1502J0D01*
G02X380834Y406009I0J1502D01*
G01X380833Y406010D01*
G03X380668Y406071I-145J-138D01*
G01X380353Y406040D01*
G03X380203Y405946I20J-199D01*
G02X378927Y405237I-1276J794D01*
G02X377425Y406739I0J1502D01*
G02X377910Y407845I1504J0D01*
G03X377975Y407992I-135J148D01*
G01Y408286D01*
G03X377910Y408433I-200J-1D01*
G02X377425Y409539I1019J1106D01*
G02X378927Y411041I1502J0D01*
G02X380112Y410462I0J-1502D01*
G03X380270Y410385I158J123D01*
G01X380584D01*
G03X380742Y410462I0J200D01*
G02X381927Y411041I1185J-923D01*
G37*
G36*
G01X1296100D02*
G02X1297602Y409539I0J-1502D01*
G02X1297232Y408552I-1501J0D01*
G01Y408551D01*
X1297231D01*
G03X1297183Y408421I152J-130D01*
G01Y408157D01*
G03X1297231Y408027I200J0D01*
G01X1297232Y408026D01*
G02X1297602Y407039I-1131J-987D01*
G02X1296100Y405537I-1502J0D01*
G02X1295007Y406009I0J1502D01*
G01X1295006Y406010D01*
G03X1294841Y406071I-145J-138D01*
G01X1294526Y406040D01*
G03X1294376Y405946I20J-199D01*
G02X1293100Y405237I-1276J794D01*
G02X1291598Y406739I0J1502D01*
G02X1292083Y407845I1504J0D01*
G03X1292148Y407992I-135J148D01*
G01Y408286D01*
G03X1292083Y408433I-200J-1D01*
G02X1291598Y409539I1019J1106D01*
G02X1293100Y411041I1502J0D01*
G02X1294285Y410462I0J-1502D01*
G03X1294443Y410385I158J123D01*
G01X1294757D01*
G03X1294915Y410462I0J200D01*
G02X1296100Y411041I1185J-923D01*
G37*
G36*
G01X881190Y413121D02*
G02Y410117I0J-1502D01*
G02X880203Y410487I0J1501D01*
G01X880202D01*
Y410488D01*
G03X880072Y410536I-130J-152D01*
G01X879808D01*
G03X879678Y410488I0J-200D01*
G01X879677Y410487D01*
G02X878690Y410117I-987J1131D01*
G02Y413121I0J1502D01*
G02X879677Y412751I0J-1501D01*
G01X879678D01*
Y412750D01*
G03X879808Y412702I130J152D01*
G01X880072D01*
G03X880202Y412750I0J200D01*
G01X880203Y412751D01*
G02X881190Y413121I987J-1131D01*
G37*
G36*
G01X385945Y415113D02*
G02Y412109I0J-1502D01*
G02X384958Y412479I0J1501D01*
G01X384957D01*
Y412480D01*
G03X384827Y412528I-130J-152D01*
G01X384563D01*
G03X384433Y412480I0J-200D01*
G01X384432Y412479D01*
G02X382458I-987J1131D01*
G01X382457D01*
Y412480D01*
G03X382327Y412528I-130J-152D01*
G01X382063D01*
G03X381933Y412480I0J-200D01*
G01X381932Y412479D01*
G02X379958I-987J1131D01*
G01X379957D01*
Y412480D01*
G03X379827Y412528I-130J-152D01*
G01X379563D01*
G03X379433Y412480I0J-200D01*
G01X379432Y412479D01*
G02X378445Y412109I-987J1131D01*
G02Y415113I0J1502D01*
G02X379432Y414743I0J-1501D01*
G01X379433D01*
Y414742D01*
G03X379563Y414694I130J152D01*
G01X379827D01*
G03X379957Y414742I0J200D01*
G01X379958Y414743D01*
G02X381932I987J-1131D01*
G01X381933D01*
Y414742D01*
G03X382063Y414694I130J152D01*
G01X382327D01*
G03X382457Y414742I0J200D01*
G01X382458Y414743D01*
G02X384432I987J-1131D01*
G01X384433D01*
Y414742D01*
G03X384563Y414694I130J152D01*
G01X384827D01*
G03X384957Y414742I0J200D01*
G01X384958Y414743D01*
G02X385945Y415113I987J-1131D01*
G37*
G36*
G01X1300118D02*
G02Y412109I0J-1502D01*
G02X1299131Y412479I0J1501D01*
G01X1299130D01*
Y412480D01*
G03X1299000Y412528I-130J-152D01*
G01X1298736D01*
G03X1298606Y412480I0J-200D01*
G01X1298605Y412479D01*
G02X1296631I-987J1131D01*
G01X1296630D01*
Y412480D01*
G03X1296500Y412528I-130J-152D01*
G01X1296236D01*
G03X1296106Y412480I0J-200D01*
G01X1296105Y412479D01*
G02X1294131I-987J1131D01*
G01X1294130D01*
Y412480D01*
G03X1294000Y412528I-130J-152D01*
G01X1293736D01*
G03X1293606Y412480I0J-200D01*
G01X1293605Y412479D01*
G02X1292618Y412109I-987J1131D01*
G02Y415113I0J1502D01*
G02X1293605Y414743I0J-1501D01*
G01X1293606D01*
Y414742D01*
G03X1293736Y414694I130J152D01*
G01X1294000D01*
G03X1294130Y414742I0J200D01*
G01X1294131Y414743D01*
G02X1296105I987J-1131D01*
G01X1296106D01*
Y414742D01*
G03X1296236Y414694I130J152D01*
G01X1296500D01*
G03X1296630Y414742I0J200D01*
G01X1296631Y414743D01*
G02X1298605I987J-1131D01*
G01X1298606D01*
Y414742D01*
G03X1298736Y414694I130J152D01*
G01X1299000D01*
G03X1299130Y414742I0J200D01*
G01X1299131Y414743D01*
G02X1300118Y415113I987J-1131D01*
G37*
G36*
G01X879417Y416824D02*
G02Y413820I0J-1502D01*
G02X878430Y414190I0J1501D01*
G01X878429D01*
Y414191D01*
G03X878299Y414239I-130J-152D01*
G01X878035D01*
G03X877905Y414191I0J-200D01*
G01X877904Y414190D01*
G02X876917Y413820I-987J1131D01*
G02Y416824I0J1502D01*
G02X877904Y416454I0J-1501D01*
G01X877905D01*
Y416453D01*
G03X878035Y416405I130J152D01*
G01X878299D01*
G03X878429Y416453I0J200D01*
G01X878430Y416454D01*
G02X879417Y416824I987J-1131D01*
G37*
G36*
G01X857325Y419896D02*
G02X858827Y421398I1502J0D01*
G02X860006Y420827I0J-1503D01*
G01X860032Y420794D01*
X860106Y420755D01*
X860485Y420726D01*
X860563Y420754D01*
X860594Y420783D01*
G02X861622Y421190I1028J-1095D01*
G02X863124Y419688I0J-1502D01*
G02X862623Y418568I-1502J0D01*
G01X862594Y418543D01*
X862560Y418473D01*
X862535Y418159D01*
G03X862579Y418018I199J-15D01*
G02X862915Y417071I-1167J-947D01*
G02X861413Y415569I-1502J0D01*
G02X860522Y415862I0J1501D01*
G01X860521D01*
X860490Y415885D01*
X860414Y415904D01*
X860058Y415852D01*
X859989Y415811D01*
X859966Y415780D01*
G02X859627Y415454I-1198J906D01*
G03X859543Y415315I114J-164D01*
G01X859500Y414979D01*
X859524Y414898D01*
X859552Y414866D01*
G02X859912Y413890I-1143J-976D01*
G02X856908I-1502J0D01*
G02X857550Y415121I1501J0D01*
G03X857634Y415260I-114J164D01*
G01X857677Y415596D01*
X857653Y415677D01*
X857625Y415709D01*
G02X857265Y416685I1143J976D01*
G02X857986Y417968I1502J0D01*
G01X858030Y417995D01*
X858081Y418083D01*
X858089Y418525D01*
X858042Y418615D01*
X857999Y418643D01*
G02X857325Y419896I828J1253D01*
G37*
G36*
G01X433954Y421877D02*
G02Y418873I0J-1502D01*
G02X432848Y419358I0J1504D01*
G03X432701Y419423I-148J-135D01*
G01X432407D01*
G03X432260Y419358I1J-200D01*
G02X430048I-1106J1017D01*
G03X429901Y419423I-148J-135D01*
G01X429607D01*
G03X429460Y419358I1J-200D01*
G02X428354Y418873I-1106J1019D01*
G02Y421877I0J1502D01*
G02X429460Y421392I0J-1504D01*
G03X429607Y421327I148J135D01*
G01X429901D01*
G03X430048Y421392I-1J200D01*
G02X432260I1106J-1017D01*
G03X432407Y421327I148J135D01*
G01X432701D01*
G03X432848Y421392I-1J200D01*
G02X433954Y421877I1106J-1019D01*
G37*
G36*
G01X1348127D02*
G02Y418873I0J-1502D01*
G02X1347021Y419358I0J1504D01*
G03X1346874Y419423I-148J-135D01*
G01X1346580D01*
G03X1346433Y419358I1J-200D01*
G02X1344221I-1106J1017D01*
G03X1344074Y419423I-148J-135D01*
G01X1343780D01*
G03X1343633Y419358I1J-200D01*
G02X1342527Y418873I-1106J1019D01*
G02Y421877I0J1502D01*
G02X1343633Y421392I0J-1504D01*
G03X1343780Y421327I148J135D01*
G01X1344074D01*
G03X1344221Y421392I-1J200D01*
G02X1346433I1106J-1017D01*
G03X1346580Y421327I148J135D01*
G01X1346874D01*
G03X1347021Y421392I-1J200D01*
G02X1348127Y421877I1106J-1019D01*
G37*
G36*
G01X352653Y421489D02*
G02X355657I1502J0D01*
G02X355251Y420462I-1502J0D01*
G01X355225Y420435D01*
X355197Y420364D01*
Y420014D01*
X355225Y419943D01*
X355251Y419916D01*
G02Y417862I-1096J-1027D01*
G01X355225Y417835D01*
X355197Y417764D01*
Y417414D01*
X355225Y417343D01*
X355251Y417316D01*
G02X355657Y416289I-1096J-1027D01*
G02X352653I-1502J0D01*
G02X353059Y417316I1502J0D01*
G01X353085Y417343D01*
X353113Y417414D01*
Y417764D01*
X353085Y417835D01*
X353059Y417862D01*
G02Y419916I1096J1027D01*
G01X353085Y419943D01*
X353113Y420014D01*
Y420364D01*
X353085Y420435D01*
X353059Y420462D01*
G02X352653Y421489I1096J1027D01*
G37*
G36*
G01X1266826D02*
G02X1269830I1502J0D01*
G02X1269424Y420462I-1502J0D01*
G01X1269398Y420435D01*
X1269370Y420364D01*
Y420014D01*
X1269398Y419943D01*
X1269424Y419916D01*
G02Y417862I-1096J-1027D01*
G01X1269398Y417835D01*
X1269370Y417764D01*
Y417414D01*
X1269398Y417343D01*
X1269424Y417316D01*
G02X1269830Y416289I-1096J-1027D01*
G02X1266826I-1502J0D01*
G02X1267232Y417316I1502J0D01*
G01X1267258Y417343D01*
X1267286Y417414D01*
Y417764D01*
X1267258Y417835D01*
X1267232Y417862D01*
G02Y419916I1096J1027D01*
G01X1267258Y419943D01*
X1267286Y420014D01*
Y420364D01*
X1267258Y420435D01*
X1267232Y420462D01*
G02X1266826Y421489I1096J1027D01*
G37*
G36*
G01X337570Y422088D02*
G02X340574I1502J0D01*
G02X340168Y421061I-1502J0D01*
G01X340142Y421034D01*
X340114Y420963D01*
Y420613D01*
X340142Y420542D01*
X340168Y420515D01*
G02Y418461I-1096J-1027D01*
G01X340142Y418434D01*
X340114Y418363D01*
Y418013D01*
X340142Y417942D01*
X340168Y417915D01*
G02X340574Y416888I-1096J-1027D01*
G02X337570I-1502J0D01*
G02X337976Y417915I1502J0D01*
G01X338002Y417942D01*
X338030Y418013D01*
Y418363D01*
X338002Y418434D01*
X337976Y418461D01*
G02Y420515I1096J1027D01*
G01X338002Y420542D01*
X338030Y420613D01*
Y420963D01*
X338002Y421034D01*
X337976Y421061D01*
G02X337570Y422088I1096J1027D01*
G37*
G36*
G01X1251743D02*
G02X1254747I1502J0D01*
G02X1254341Y421061I-1502J0D01*
G01X1254315Y421034D01*
X1254287Y420963D01*
Y420613D01*
X1254315Y420542D01*
X1254341Y420515D01*
G02Y418461I-1096J-1027D01*
G01X1254315Y418434D01*
X1254287Y418363D01*
Y418013D01*
X1254315Y417942D01*
X1254341Y417915D01*
G02X1254747Y416888I-1096J-1027D01*
G02X1251743I-1502J0D01*
G02X1252149Y417915I1502J0D01*
G01X1252175Y417942D01*
X1252203Y418013D01*
Y418363D01*
X1252175Y418434D01*
X1252149Y418461D01*
G02Y420515I1096J1027D01*
G01X1252175Y420542D01*
X1252203Y420613D01*
Y420963D01*
X1252175Y421034D01*
X1252149Y421061D01*
G02X1251743Y422088I1096J1027D01*
G37*
G36*
G01X877253Y424382D02*
G02X878755Y422880I0J-1502D01*
G02X878385Y421893I-1501J0D01*
G01Y421892D01*
X878384D01*
G03X878336Y421762I152J-130D01*
G01Y421498D01*
G03X878384Y421368I200J0D01*
G01X878385Y421367D01*
G02X878755Y420380I-1131J-987D01*
G02X877253Y418878I-1502J0D01*
G02X876160Y419350I0J1502D01*
G01X876159Y419351D01*
G03X875994Y419412I-145J-138D01*
G01X875679Y419381D01*
G03X875529Y419287I20J-199D01*
G02X874253Y418578I-1276J794D01*
G02X872751Y420080I0J1502D01*
G02X873236Y421186I1504J0D01*
G03X873301Y421333I-135J148D01*
G01Y421627D01*
G03X873236Y421774I-200J-1D01*
G02X872751Y422880I1019J1106D01*
G02X874253Y424382I1502J0D01*
G02X875438Y423803I0J-1502D01*
G03X875596Y423726I158J123D01*
G01X875910D01*
G03X876068Y423803I0J200D01*
G02X877253Y424382I1185J-923D01*
G37*
G36*
G01X385710Y425569D02*
G02Y422565I0J-1502D01*
G02X384723Y422935I0J1501D01*
G01X384722D01*
Y422936D01*
G03X384592Y422984I-130J-152D01*
G01X384328D01*
G03X384198Y422936I0J-200D01*
G01X384197Y422935D01*
G02X382223I-987J1131D01*
G01X382222D01*
Y422936D01*
G03X382092Y422984I-130J-152D01*
G01X381828D01*
G03X381698Y422936I0J-200D01*
G01X381697Y422935D01*
G02X379723I-987J1131D01*
G01X379722D01*
Y422936D01*
G03X379592Y422984I-130J-152D01*
G01X379328D01*
G03X379198Y422936I0J-200D01*
G01X379197Y422935D01*
G02X378210Y422565I-987J1131D01*
G02Y425569I0J1502D01*
G02X379197Y425199I0J-1501D01*
G01X379198D01*
Y425198D01*
G03X379328Y425150I130J152D01*
G01X379592D01*
G03X379722Y425198I0J200D01*
G01X379723Y425199D01*
G02X381697I987J-1131D01*
G01X381698D01*
Y425198D01*
G03X381828Y425150I130J152D01*
G01X382092D01*
G03X382222Y425198I0J200D01*
G01X382223Y425199D01*
G02X384197I987J-1131D01*
G01X384198D01*
Y425198D01*
G03X384328Y425150I130J152D01*
G01X384592D01*
G03X384722Y425198I0J200D01*
G01X384723Y425199D01*
G02X385710Y425569I987J-1131D01*
G37*
G36*
G01X1299883D02*
G02Y422565I0J-1502D01*
G02X1298896Y422935I0J1501D01*
G01X1298895D01*
Y422936D01*
G03X1298765Y422984I-130J-152D01*
G01X1298501D01*
G03X1298371Y422936I0J-200D01*
G01X1298370Y422935D01*
G02X1296396I-987J1131D01*
G01X1296395D01*
Y422936D01*
G03X1296265Y422984I-130J-152D01*
G01X1296001D01*
G03X1295871Y422936I0J-200D01*
G01X1295870Y422935D01*
G02X1293896I-987J1131D01*
G01X1293895D01*
Y422936D01*
G03X1293765Y422984I-130J-152D01*
G01X1293501D01*
G03X1293371Y422936I0J-200D01*
G01X1293370Y422935D01*
G02X1292383Y422565I-987J1131D01*
G02Y425569I0J1502D01*
G02X1293370Y425199I0J-1501D01*
G01X1293371D01*
Y425198D01*
G03X1293501Y425150I130J152D01*
G01X1293765D01*
G03X1293895Y425198I0J200D01*
G01X1293896Y425199D01*
G02X1295870I987J-1131D01*
G01X1295871D01*
Y425198D01*
G03X1296001Y425150I130J152D01*
G01X1296265D01*
G03X1296395Y425198I0J200D01*
G01X1296396Y425199D01*
G02X1298370I987J-1131D01*
G01X1298371D01*
Y425198D01*
G03X1298501Y425150I130J152D01*
G01X1298765D01*
G03X1298895Y425198I0J200D01*
G01X1298896Y425199D01*
G02X1299883Y425569I987J-1131D01*
G37*
G36*
G01X927563Y425947D02*
G02Y422943I0J-1502D01*
G02X926457Y423428I0J1504D01*
G03X926310Y423493I-148J-135D01*
G01X926016D01*
G03X925869Y423428I1J-200D01*
G02X923657I-1106J1017D01*
G03X923510Y423493I-148J-135D01*
G01X923216D01*
G03X923069Y423428I1J-200D01*
G02X921963Y422943I-1106J1019D01*
G02Y425947I0J1502D01*
G02X923069Y425462I0J-1504D01*
G03X923216Y425397I148J135D01*
G01X923510D01*
G03X923657Y425462I-1J200D01*
G02X925869I1106J-1017D01*
G03X926016Y425397I148J135D01*
G01X926310D01*
G03X926457Y425462I-1J200D01*
G02X927563Y425947I1106J-1019D01*
G37*
G36*
G01X356153Y426689D02*
G02X359157I1502J0D01*
G02X358751Y425662I-1502J0D01*
G01X358725Y425635D01*
X358697Y425564D01*
Y425214D01*
X358725Y425143D01*
X358751Y425116D01*
G02Y423062I-1096J-1027D01*
G01X358725Y423035D01*
X358697Y422964D01*
Y422614D01*
X358725Y422543D01*
X358751Y422516D01*
G02Y420462I-1096J-1027D01*
G01X358725Y420435D01*
X358697Y420364D01*
Y420014D01*
X358725Y419943D01*
X358751Y419916D01*
G02Y417862I-1096J-1027D01*
G01X358725Y417835D01*
X358697Y417764D01*
Y417414D01*
X358725Y417343D01*
X358751Y417316D01*
G02Y415262I-1096J-1027D01*
G01X358725Y415235D01*
X358697Y415164D01*
Y414814D01*
X358725Y414743D01*
X358751Y414716D01*
G02Y412662I-1096J-1027D01*
G01X358725Y412635D01*
X358697Y412564D01*
Y412214D01*
X358725Y412143D01*
X358751Y412116D01*
G02Y410062I-1096J-1027D01*
G01X358725Y410035D01*
X358697Y409964D01*
Y409614D01*
X358725Y409543D01*
X358751Y409516D01*
G02Y407462I-1096J-1027D01*
G01X358725Y407435D01*
X358697Y407364D01*
Y407014D01*
X358725Y406943D01*
X358751Y406916D01*
G02X359157Y405889I-1096J-1027D01*
G02X358937Y405108I-1502J2D01*
G01Y405106D01*
X358936D01*
G03X358913Y404958I172J-103D01*
G01X358985Y404647D01*
X359029Y404583D01*
X359062Y404562D01*
G02X359750Y403300I-813J-1262D01*
G02X356746I-1502J0D01*
G02X356966Y404081I1502J-2D01*
G01Y404083D01*
X356967D01*
G03X356990Y404231I-172J103D01*
G01X356918Y404542D01*
X356874Y404606D01*
X356841Y404627D01*
G02X356153Y405889I813J1262D01*
G02X356559Y406916I1502J0D01*
G01X356585Y406943D01*
X356613Y407014D01*
Y407364D01*
X356585Y407435D01*
X356559Y407462D01*
G02Y409516I1096J1027D01*
G01X356585Y409543D01*
X356613Y409614D01*
Y409964D01*
X356585Y410035D01*
X356559Y410062D01*
G02Y412116I1096J1027D01*
G01X356585Y412143D01*
X356613Y412214D01*
Y412564D01*
X356585Y412635D01*
X356559Y412662D01*
G02Y414716I1096J1027D01*
G01X356585Y414743D01*
X356613Y414814D01*
Y415164D01*
X356585Y415235D01*
X356559Y415262D01*
G02Y417316I1096J1027D01*
G01X356585Y417343D01*
X356613Y417414D01*
Y417764D01*
X356585Y417835D01*
X356559Y417862D01*
G02Y419916I1096J1027D01*
G01X356585Y419943D01*
X356613Y420014D01*
Y420364D01*
X356585Y420435D01*
X356559Y420462D01*
G02Y422516I1096J1027D01*
G01X356585Y422543D01*
X356613Y422614D01*
Y422964D01*
X356585Y423035D01*
X356559Y423062D01*
G02Y425116I1096J1027D01*
G01X356585Y425143D01*
X356613Y425214D01*
Y425564D01*
X356585Y425635D01*
X356559Y425662D01*
G02X356153Y426689I1096J1027D01*
G37*
G36*
G01X1270326D02*
G02X1273330I1502J0D01*
G02X1272924Y425662I-1502J0D01*
G01X1272898Y425635D01*
X1272870Y425564D01*
Y425214D01*
X1272898Y425143D01*
X1272924Y425116D01*
G02Y423062I-1096J-1027D01*
G01X1272898Y423035D01*
X1272870Y422964D01*
Y422614D01*
X1272898Y422543D01*
X1272924Y422516D01*
G02Y420462I-1096J-1027D01*
G01X1272898Y420435D01*
X1272870Y420364D01*
Y420014D01*
X1272898Y419943D01*
X1272924Y419916D01*
G02Y417862I-1096J-1027D01*
G01X1272898Y417835D01*
X1272870Y417764D01*
Y417414D01*
X1272898Y417343D01*
X1272924Y417316D01*
G02Y415262I-1096J-1027D01*
G01X1272898Y415235D01*
X1272870Y415164D01*
Y414814D01*
X1272898Y414743D01*
X1272924Y414716D01*
G02Y412662I-1096J-1027D01*
G01X1272898Y412635D01*
X1272870Y412564D01*
Y412214D01*
X1272898Y412143D01*
X1272924Y412116D01*
G02Y410062I-1096J-1027D01*
G01X1272898Y410035D01*
X1272870Y409964D01*
Y409614D01*
X1272898Y409543D01*
X1272924Y409516D01*
G02Y407462I-1096J-1027D01*
G01X1272898Y407435D01*
X1272870Y407364D01*
Y407014D01*
X1272898Y406943D01*
X1272924Y406916D01*
G02X1273330Y405889I-1096J-1027D01*
G02X1273110Y405108I-1502J2D01*
G01Y405106D01*
X1273109D01*
G03X1273086Y404958I172J-103D01*
G01X1273158Y404647D01*
X1273202Y404583D01*
X1273235Y404562D01*
G02X1273923Y403300I-813J-1262D01*
G02X1270919I-1502J0D01*
G02X1271139Y404081I1502J-2D01*
G01Y404083D01*
X1271140D01*
G03X1271163Y404231I-172J103D01*
G01X1271091Y404542D01*
X1271047Y404606D01*
X1271014Y404627D01*
G02X1270326Y405889I813J1262D01*
G02X1270732Y406916I1502J0D01*
G01X1270758Y406943D01*
X1270786Y407014D01*
Y407364D01*
X1270758Y407435D01*
X1270732Y407462D01*
G02Y409516I1096J1027D01*
G01X1270758Y409543D01*
X1270786Y409614D01*
Y409964D01*
X1270758Y410035D01*
X1270732Y410062D01*
G02Y412116I1096J1027D01*
G01X1270758Y412143D01*
X1270786Y412214D01*
Y412564D01*
X1270758Y412635D01*
X1270732Y412662D01*
G02Y414716I1096J1027D01*
G01X1270758Y414743D01*
X1270786Y414814D01*
Y415164D01*
X1270758Y415235D01*
X1270732Y415262D01*
G02Y417316I1096J1027D01*
G01X1270758Y417343D01*
X1270786Y417414D01*
Y417764D01*
X1270758Y417835D01*
X1270732Y417862D01*
G02Y419916I1096J1027D01*
G01X1270758Y419943D01*
X1270786Y420014D01*
Y420364D01*
X1270758Y420435D01*
X1270732Y420462D01*
G02Y422516I1096J1027D01*
G01X1270758Y422543D01*
X1270786Y422614D01*
Y422964D01*
X1270758Y423035D01*
X1270732Y423062D01*
G02Y425116I1096J1027D01*
G01X1270758Y425143D01*
X1270786Y425214D01*
Y425564D01*
X1270758Y425635D01*
X1270732Y425662D01*
G02X1270326Y426689I1096J1027D01*
G37*
G36*
G01X881271Y428454D02*
G02Y425450I0J-1502D01*
G02X880284Y425820I0J1501D01*
G01X880283D01*
Y425821D01*
G03X880153Y425869I-130J-152D01*
G01X879889D01*
G03X879759Y425821I0J-200D01*
G01X879758Y425820D01*
G02X877784I-987J1131D01*
G01X877783D01*
Y425821D01*
G03X877653Y425869I-130J-152D01*
G01X877389D01*
G03X877259Y425821I0J-200D01*
G01X877258Y425820D01*
G02X875284I-987J1131D01*
G01X875283D01*
Y425821D01*
G03X875153Y425869I-130J-152D01*
G01X874889D01*
G03X874759Y425821I0J-200D01*
G01X874758Y425820D01*
G02X873771Y425450I-987J1131D01*
G02Y428454I0J1502D01*
G02X874758Y428084I0J-1501D01*
G01X874759D01*
Y428083D01*
G03X874889Y428035I130J152D01*
G01X875153D01*
G03X875283Y428083I0J200D01*
G01X875284Y428084D01*
G02X877258I987J-1131D01*
G01X877259D01*
Y428083D01*
G03X877389Y428035I130J152D01*
G01X877653D01*
G03X877783Y428083I0J200D01*
G01X877784Y428084D01*
G02X879758I987J-1131D01*
G01X879759D01*
Y428083D01*
G03X879889Y428035I130J152D01*
G01X880153D01*
G03X880283Y428083I0J200D01*
G01X880284Y428084D01*
G02X881271Y428454I987J-1131D01*
G37*
G36*
G01X420713Y427439D02*
G02X423717I1502J0D01*
G02X423347Y426452I-1501J0D01*
G01Y426451D01*
X423346D01*
G03X423298Y426321I152J-130D01*
G01Y426057D01*
G03X423346Y425927I200J0D01*
G01X423347Y425926D01*
G02X423717Y424939I-1131J-987D01*
G02X420713I-1502J0D01*
G02X421083Y425926I1501J0D01*
G01Y425927D01*
X421084D01*
G03X421132Y426057I-152J130D01*
G01Y426321D01*
G03X421084Y426451I-200J0D01*
G01X421083Y426452D01*
G02X420713Y427439I1131J987D01*
G37*
G36*
G01X1334886D02*
G02X1337890I1502J0D01*
G02X1337520Y426452I-1501J0D01*
G01Y426451D01*
X1337519D01*
G03X1337471Y426321I152J-130D01*
G01Y426057D01*
G03X1337519Y425927I200J0D01*
G01X1337520Y425926D01*
G02X1337890Y424939I-1131J-987D01*
G02X1334886I-1502J0D01*
G02X1335256Y425926I1501J0D01*
G01Y425927D01*
X1335257D01*
G03X1335305Y426057I-152J130D01*
G01Y426321D01*
G03X1335257Y426451I-200J0D01*
G01X1335256Y426452D01*
G02X1334886Y427439I1131J987D01*
G37*
G36*
G01X783400Y428653D02*
G02X786404I1502J0D01*
G02X785621Y427334I-1502J0D01*
G03X785601Y426644I192J-351D01*
G02X786306Y425371I-797J-1273D01*
G02X783302I-1502J0D01*
G02X784085Y426690I1502J0D01*
G03X784105Y427380I-192J351D01*
G02X783400Y428653I797J1273D01*
G37*
G36*
G01X966963Y429470D02*
G02X968462Y430870I1499J-103D01*
G02X969964Y429368I0J-1502D01*
G02X968564Y427869I-1503J0D01*
G03X968193Y427497I28J-399D01*
G02X966694Y426097I-1499J103D01*
G02X965192Y427599I0J1502D01*
G02X966592Y429098I1503J0D01*
G03X966963Y429470I-28J399D01*
G37*
G36*
G01X423952Y434739D02*
G02X425023Y435301I1071J-739D01*
G02Y432697I0J-1302D01*
G02X423952Y433259I0J1301D01*
G03X423294I-329J-228D01*
G02X422223Y432697I-1071J739D01*
G02Y435301I0J1302D01*
G02X423294Y434739I0J-1301D01*
G03X423952I329J228D01*
G37*
G36*
G01X1338125D02*
G02X1339196Y435301I1071J-739D01*
G02Y432697I0J-1302D01*
G02X1338125Y433259I0J1301D01*
G03X1337467I-329J-228D01*
G02X1336396Y432697I-1071J739D01*
G02Y435301I0J1302D01*
G02X1337467Y434739I0J-1301D01*
G03X1338125I329J228D01*
G37*
G36*
G01X356540Y435518D02*
G02X359544I1502J0D01*
G02X359059Y434412I-1504J0D01*
G03X358994Y434265I135J-148D01*
G01Y433971D01*
G03X359059Y433824I200J1D01*
G02X359544Y432718I-1019J-1106D01*
G02X356540I-1502J0D01*
G02X357025Y433824I1504J0D01*
G03X357090Y433971I-135J148D01*
G01Y434265D01*
G03X357025Y434412I-200J-1D01*
G02X356540Y435518I1019J1106D01*
G37*
G36*
G01X1270713D02*
G02X1273717I1502J0D01*
G02X1273232Y434412I-1504J0D01*
G03X1273167Y434265I135J-148D01*
G01Y433971D01*
G03X1273232Y433824I200J1D01*
G02X1273717Y432718I-1019J-1106D01*
G02X1270713I-1502J0D01*
G02X1271198Y433824I1504J0D01*
G03X1271263Y433971I-135J148D01*
G01Y434265D01*
G03X1271198Y434412I-200J-1D01*
G02X1270713Y435518I1019J1106D01*
G37*
G36*
G01X823601Y435558D02*
G02X826605I1502J0D01*
G02X826199Y434531I-1502J0D01*
G01X826173Y434504D01*
X826145Y434433D01*
Y434083D01*
X826173Y434012D01*
X826199Y433985D01*
G02Y431931I-1096J-1027D01*
G01X826173Y431904D01*
X826145Y431833D01*
Y431483D01*
X826173Y431412D01*
X826199Y431385D01*
G02X826605Y430358I-1096J-1027D01*
G02X823601I-1502J0D01*
G02X824007Y431385I1502J0D01*
G01X824033Y431412D01*
X824061Y431483D01*
Y431833D01*
X824033Y431904D01*
X824007Y431931D01*
G02Y433985I1096J1027D01*
G01X824033Y434012D01*
X824061Y434083D01*
Y434433D01*
X824033Y434504D01*
X824007Y434531D01*
G02X823601Y435558I1096J1027D01*
G37*
G36*
G01X829876Y435686D02*
G02X832880I1502J0D01*
G02X832474Y434659I-1502J0D01*
G01X832448Y434632D01*
X832420Y434561D01*
Y434211D01*
X832448Y434140D01*
X832474Y434113D01*
G02Y432059I-1096J-1027D01*
G01X832448Y432032D01*
X832420Y431961D01*
Y431611D01*
X832448Y431540D01*
X832474Y431513D01*
G02X832880Y430486I-1096J-1027D01*
G02X829876I-1502J0D01*
G02X830282Y431513I1502J0D01*
G01X830308Y431540D01*
X830336Y431611D01*
Y431961D01*
X830308Y432032D01*
X830282Y432059D01*
G02Y434113I1096J1027D01*
G01X830308Y434140D01*
X830336Y434211D01*
Y434561D01*
X830308Y434632D01*
X830282Y434659D01*
G02X829876Y435686I1096J1027D01*
G37*
G36*
G01X927280Y438218D02*
G02Y435214I0J-1502D01*
G02X926174Y435699I0J1504D01*
G03X926027Y435764I-148J-135D01*
G01X925733D01*
G03X925586Y435699I1J-200D01*
G02X923374I-1106J1017D01*
G03X923227Y435764I-148J-135D01*
G01X922933D01*
G03X922786Y435699I1J-200D01*
G02X921680Y435214I-1106J1019D01*
G02Y438218I0J1502D01*
G02X922786Y437733I0J-1504D01*
G03X922933Y437668I148J135D01*
G01X923227D01*
G03X923374Y437733I-1J200D01*
G02X925586I1106J-1017D01*
G03X925733Y437668I148J135D01*
G01X926027D01*
G03X926174Y437733I-1J200D01*
G02X927280Y438218I1106J-1019D01*
G37*
G36*
G01X423952Y438283D02*
G02X425023Y438845I1071J-739D01*
G02Y436241I0J-1302D01*
G02X423952Y436803I0J1301D01*
G03X423294I-329J-228D01*
G02X422223Y436241I-1071J739D01*
G02Y438845I0J1302D01*
G02X423294Y438283I0J-1301D01*
G03X423952I329J228D01*
G37*
G36*
G01X1338125D02*
G02X1339196Y438845I1071J-739D01*
G02Y436241I0J-1302D01*
G02X1338125Y436803I0J1301D01*
G03X1337467I-329J-228D01*
G02X1336396Y436241I-1071J739D01*
G02Y438845I0J1302D01*
G02X1337467Y438283I0J-1301D01*
G03X1338125I329J228D01*
G37*
G36*
G01X881036Y438910D02*
G02Y435906I0J-1502D01*
G02X880049Y436276I0J1501D01*
G01X880048D01*
Y436277D01*
G03X879918Y436325I-130J-152D01*
G01X879654D01*
G03X879524Y436277I0J-200D01*
G01X879523Y436276D01*
G02X877549I-987J1131D01*
G01X877548D01*
Y436277D01*
G03X877418Y436325I-130J-152D01*
G01X877154D01*
G03X877024Y436277I0J-200D01*
G01X877023Y436276D01*
G02X875049I-987J1131D01*
G01X875048D01*
Y436277D01*
G03X874918Y436325I-130J-152D01*
G01X874654D01*
G03X874524Y436277I0J-200D01*
G01X874523Y436276D01*
G02X873536Y435906I-987J1131D01*
G02Y438910I0J1502D01*
G02X874523Y438540I0J-1501D01*
G01X874524D01*
Y438539D01*
G03X874654Y438491I130J152D01*
G01X874918D01*
G03X875048Y438539I0J200D01*
G01X875049Y438540D01*
G02X877023I987J-1131D01*
G01X877024D01*
Y438539D01*
G03X877154Y438491I130J152D01*
G01X877418D01*
G03X877548Y438539I0J200D01*
G01X877549Y438540D01*
G02X879523I987J-1131D01*
G01X879524D01*
Y438539D01*
G03X879654Y438491I130J152D01*
G01X879918D01*
G03X880048Y438539I0J200D01*
G01X880049Y438540D01*
G02X881036Y438910I987J-1131D01*
G37*
G36*
G01X295253Y442371D02*
G02X296755Y440869I0J-1502D01*
G02X296349Y439842I-1502J0D01*
G01X296323Y439815D01*
X296295Y439744D01*
Y439394D01*
X296323Y439323D01*
X296349Y439296D01*
G02Y437242I-1096J-1027D01*
G01X296323Y437215D01*
X296295Y437144D01*
Y436794D01*
X296323Y436723D01*
X296349Y436696D01*
G02Y434642I-1096J-1027D01*
G01X296323Y434615D01*
X296295Y434544D01*
Y434194D01*
X296323Y434123D01*
X296349Y434096D01*
G02Y432042I-1096J-1027D01*
G01X296323Y432015D01*
X296295Y431944D01*
Y431594D01*
X296323Y431523D01*
X296349Y431496D01*
G02X296755Y430469I-1096J-1027D01*
G02X295253Y428967I-1502J0D01*
G02X294147Y429452I0J1504D01*
G03X294000Y429517I-148J-135D01*
G01X293706D01*
G03X293559Y429452I1J-200D01*
G02X292453Y428967I-1106J1019D01*
G02X290951Y430469I0J1502D01*
G02X291357Y431496I1502J0D01*
G01X291383Y431523D01*
X291411Y431594D01*
Y431944D01*
X291383Y432015D01*
X291357Y432042D01*
G02Y434096I1096J1027D01*
G01X291383Y434123D01*
X291411Y434194D01*
Y434544D01*
X291383Y434615D01*
X291357Y434642D01*
G02Y436696I1096J1027D01*
G01X291383Y436723D01*
X291411Y436794D01*
Y437144D01*
X291383Y437215D01*
X291357Y437242D01*
G02Y439296I1096J1027D01*
G01X291383Y439323D01*
X291411Y439394D01*
Y439744D01*
X291383Y439815D01*
X291357Y439842D01*
G02X290951Y440869I1096J1027D01*
G02X292453Y442371I1502J0D01*
G02X293559Y441886I0J-1504D01*
G03X293706Y441821I148J135D01*
G01X294000D01*
G03X294147Y441886I-1J200D01*
G02X295253Y442371I1106J-1019D01*
G37*
G36*
G01X752339D02*
G02X753841Y440869I0J-1502D01*
G02X753435Y439842I-1502J0D01*
G01X753409Y439815D01*
X753381Y439744D01*
Y439394D01*
X753409Y439323D01*
X753435Y439296D01*
G02Y437242I-1096J-1027D01*
G01X753409Y437215D01*
X753381Y437144D01*
Y436794D01*
X753409Y436723D01*
X753435Y436696D01*
G02Y434642I-1096J-1027D01*
G01X753409Y434615D01*
X753381Y434544D01*
Y434194D01*
X753409Y434123D01*
X753435Y434096D01*
G02Y432042I-1096J-1027D01*
G01X753409Y432015D01*
X753381Y431944D01*
Y431594D01*
X753409Y431523D01*
X753435Y431496D01*
G02X753841Y430469I-1096J-1027D01*
G02X752339Y428967I-1502J0D01*
G02X751233Y429452I0J1504D01*
G03X751086Y429517I-148J-135D01*
G01X750792D01*
G03X750645Y429452I1J-200D01*
G02X749539Y428967I-1106J1019D01*
G02X748037Y430469I0J1502D01*
G02X748443Y431496I1502J0D01*
G01X748469Y431523D01*
X748497Y431594D01*
Y431944D01*
X748469Y432015D01*
X748443Y432042D01*
G02Y434096I1096J1027D01*
G01X748469Y434123D01*
X748497Y434194D01*
Y434544D01*
X748469Y434615D01*
X748443Y434642D01*
G02Y436696I1096J1027D01*
G01X748469Y436723D01*
X748497Y436794D01*
Y437144D01*
X748469Y437215D01*
X748443Y437242D01*
G02Y439296I1096J1027D01*
G01X748469Y439323D01*
X748497Y439394D01*
Y439744D01*
X748469Y439815D01*
X748443Y439842D01*
G02X748037Y440869I1096J1027D01*
G02X749539Y442371I1502J0D01*
G02X750645Y441886I0J-1504D01*
G03X750792Y441821I148J135D01*
G01X751086D01*
G03X751233Y441886I-1J200D01*
G02X752339Y442371I1106J-1019D01*
G37*
G36*
G01X1209426D02*
G02X1210928Y440869I0J-1502D01*
G02X1210522Y439842I-1502J0D01*
G01X1210496Y439815D01*
X1210468Y439744D01*
Y439394D01*
X1210496Y439323D01*
X1210522Y439296D01*
G02Y437242I-1096J-1027D01*
G01X1210496Y437215D01*
X1210468Y437144D01*
Y436794D01*
X1210496Y436723D01*
X1210522Y436696D01*
G02Y434642I-1096J-1027D01*
G01X1210496Y434615D01*
X1210468Y434544D01*
Y434194D01*
X1210496Y434123D01*
X1210522Y434096D01*
G02Y432042I-1096J-1027D01*
G01X1210496Y432015D01*
X1210468Y431944D01*
Y431594D01*
X1210496Y431523D01*
X1210522Y431496D01*
G02X1210928Y430469I-1096J-1027D01*
G02X1209426Y428967I-1502J0D01*
G02X1208320Y429452I0J1504D01*
G03X1208173Y429517I-148J-135D01*
G01X1207879D01*
G03X1207732Y429452I1J-200D01*
G02X1206626Y428967I-1106J1019D01*
G02X1205124Y430469I0J1502D01*
G02X1205530Y431496I1502J0D01*
G01X1205556Y431523D01*
X1205584Y431594D01*
Y431944D01*
X1205556Y432015D01*
X1205530Y432042D01*
G02Y434096I1096J1027D01*
G01X1205556Y434123D01*
X1205584Y434194D01*
Y434544D01*
X1205556Y434615D01*
X1205530Y434642D01*
G02Y436696I1096J1027D01*
G01X1205556Y436723D01*
X1205584Y436794D01*
Y437144D01*
X1205556Y437215D01*
X1205530Y437242D01*
G02Y439296I1096J1027D01*
G01X1205556Y439323D01*
X1205584Y439394D01*
Y439744D01*
X1205556Y439815D01*
X1205530Y439842D01*
G02X1205124Y440869I1096J1027D01*
G02X1206626Y442371I1502J0D01*
G02X1207732Y441886I0J-1504D01*
G03X1207879Y441821I148J135D01*
G01X1208173D01*
G03X1208320Y441886I-1J200D01*
G02X1209426Y442371I1106J-1019D01*
G37*
G36*
G01X423952Y441826D02*
G02X425023Y442388I1071J-739D01*
G02Y439784I0J-1302D01*
G02X423952Y440346I0J1301D01*
G03X423294I-329J-228D01*
G02X422223Y439784I-1071J739D01*
G02Y442388I0J1302D01*
G02X423294Y441826I0J-1301D01*
G03X423952I329J228D01*
G37*
G36*
G01X1338125D02*
G02X1339196Y442388I1071J-739D01*
G02Y439784I0J-1302D01*
G02X1338125Y440346I0J1301D01*
G03X1337467I-329J-228D01*
G02X1336396Y439784I-1071J739D01*
G02Y442388I0J1302D01*
G02X1337467Y441826I0J-1301D01*
G03X1338125I329J228D01*
G37*
G36*
G01X366417Y442118D02*
G02X369421I1502J0D01*
G02X368936Y441012I-1504J0D01*
G03X368871Y440865I135J-148D01*
G01Y440571D01*
G03X368936Y440424I200J1D01*
G02X369421Y439318I-1019J-1106D01*
G02X366417I-1502J0D01*
G02X366902Y440424I1504J0D01*
G03X366967Y440571I-135J148D01*
G01Y440865D01*
G03X366902Y441012I-200J-1D01*
G02X366417Y442118I1019J1106D01*
G37*
G36*
G01X374417D02*
G02X377421I1502J0D01*
G02X376936Y441012I-1504J0D01*
G03X376871Y440865I135J-148D01*
G01Y440571D01*
G03X376936Y440424I200J1D01*
G02X377421Y439318I-1019J-1106D01*
G02X374417I-1502J0D01*
G02X374902Y440424I1504J0D01*
G03X374967Y440571I-135J148D01*
G01Y440865D01*
G03X374902Y441012I-200J-1D01*
G02X374417Y442118I1019J1106D01*
G37*
G36*
G01X1280590D02*
G02X1283594I1502J0D01*
G02X1283109Y441012I-1504J0D01*
G03X1283044Y440865I135J-148D01*
G01Y440571D01*
G03X1283109Y440424I200J1D01*
G02X1283594Y439318I-1019J-1106D01*
G02X1280590I-1502J0D01*
G02X1281075Y440424I1504J0D01*
G03X1281140Y440571I-135J148D01*
G01Y440865D01*
G03X1281075Y441012I-200J-1D01*
G02X1280590Y442118I1019J1106D01*
G37*
G36*
G01X1288590D02*
G02X1291594I1502J0D01*
G02X1291109Y441012I-1504J0D01*
G03X1291044Y440865I135J-148D01*
G01Y440571D01*
G03X1291109Y440424I200J1D01*
G02X1291594Y439318I-1019J-1106D01*
G02X1288590I-1502J0D01*
G02X1289075Y440424I1504J0D01*
G03X1289140Y440571I-135J148D01*
G01Y440865D01*
G03X1289075Y441012I-200J-1D01*
G02X1288590Y442118I1019J1106D01*
G37*
G36*
G01X414924Y445223D02*
G02X416426Y443721I0J-1502D01*
G02X415941Y442615I-1504J0D01*
G03X415876Y442468I135J-148D01*
G01Y442174D01*
G03X415941Y442027I200J1D01*
G02Y439815I-1017J-1106D01*
G03X415876Y439668I135J-148D01*
G01Y439374D01*
G03X415941Y439227I200J1D01*
G02Y437015I-1017J-1106D01*
G03X415876Y436868I135J-148D01*
G01Y436574D01*
G03X415941Y436427I200J1D01*
G02X416426Y435321I-1019J-1106D01*
G02X414924Y433819I-1502J0D01*
G02X413818Y434304I0J1504D01*
G03X413671Y434369I-148J-135D01*
G01X413377D01*
G03X413230Y434304I1J-200D01*
G02X412124Y433819I-1106J1019D01*
G02X410622Y435321I0J1502D01*
G02X411107Y436427I1504J0D01*
G03X411172Y436574I-135J148D01*
G01Y436868D01*
G03X411107Y437015I-200J-1D01*
G02Y439227I1017J1106D01*
G03X411172Y439374I-135J148D01*
G01Y439668D01*
G03X411107Y439815I-200J-1D01*
G02Y442027I1017J1106D01*
G03X411172Y442174I-135J148D01*
G01Y442468D01*
G03X411107Y442615I-200J-1D01*
G02X410622Y443721I1019J1106D01*
G02X412124Y445223I1502J0D01*
G02X413230Y444738I0J-1504D01*
G03X413377Y444673I148J135D01*
G01X413671D01*
G03X413818Y444738I-1J200D01*
G02X414924Y445223I1106J-1019D01*
G37*
G36*
G01X1329097D02*
G02X1330599Y443721I0J-1502D01*
G02X1330114Y442615I-1504J0D01*
G03X1330049Y442468I135J-148D01*
G01Y442174D01*
G03X1330114Y442027I200J1D01*
G02Y439815I-1017J-1106D01*
G03X1330049Y439668I135J-148D01*
G01Y439374D01*
G03X1330114Y439227I200J1D01*
G02Y437015I-1017J-1106D01*
G03X1330049Y436868I135J-148D01*
G01Y436574D01*
G03X1330114Y436427I200J1D01*
G02X1330599Y435321I-1019J-1106D01*
G02X1329097Y433819I-1502J0D01*
G02X1327991Y434304I0J1504D01*
G03X1327844Y434369I-148J-135D01*
G01X1327550D01*
G03X1327403Y434304I1J-200D01*
G02X1326297Y433819I-1106J1019D01*
G02X1324795Y435321I0J1502D01*
G02X1325280Y436427I1504J0D01*
G03X1325345Y436574I-135J148D01*
G01Y436868D01*
G03X1325280Y437015I-200J-1D01*
G02Y439227I1017J1106D01*
G03X1325345Y439374I-135J148D01*
G01Y439668D01*
G03X1325280Y439815I-200J-1D01*
G02Y442027I1017J1106D01*
G03X1325345Y442174I-135J148D01*
G01Y442468D01*
G03X1325280Y442615I-200J-1D01*
G02X1324795Y443721I1019J1106D01*
G02X1326297Y445223I1502J0D01*
G02X1327403Y444738I0J-1504D01*
G03X1327550Y444673I148J135D01*
G01X1327844D01*
G03X1327991Y444738I-1J200D01*
G02X1329097Y445223I1106J-1019D01*
G37*
G36*
G01X916039Y443780D02*
G02X919043I1502J0D01*
G02X918673Y442793I-1501J0D01*
G01Y442792D01*
X918672D01*
G03X918624Y442662I152J-130D01*
G01Y442398D01*
G03X918672Y442268I200J0D01*
G01X918673Y442267D01*
G02X919043Y441280I-1131J-987D01*
G02X916039I-1502J0D01*
G02X916409Y442267I1501J0D01*
G01Y442268D01*
X916410D01*
G03X916458Y442398I-152J130D01*
G01Y442662D01*
G03X916410Y442792I-200J0D01*
G01X916409Y442793D01*
G02X916039Y443780I1131J987D01*
G37*
G36*
G01X384082Y443893D02*
G02X387086I1502J0D01*
G02X386601Y442787I-1504J0D01*
G03X386536Y442640I135J-148D01*
G01Y442346D01*
G03X386601Y442199I200J1D01*
G02Y439987I-1017J-1106D01*
G03X386536Y439840I135J-148D01*
G01Y439546D01*
G03X386601Y439399I200J1D01*
G02X387086Y438293I-1019J-1106D01*
G02X384082I-1502J0D01*
G02X384567Y439399I1504J0D01*
G03X384632Y439546I-135J148D01*
G01Y439840D01*
G03X384567Y439987I-200J-1D01*
G02Y442199I1017J1106D01*
G03X384632Y442346I-135J148D01*
G01Y442640D01*
G03X384567Y442787I-200J-1D01*
G02X384082Y443893I1019J1106D01*
G37*
G36*
G01X394075D02*
G02X397079I1502J0D01*
G02X396594Y442787I-1504J0D01*
G03X396529Y442640I135J-148D01*
G01Y442346D01*
G03X396594Y442199I200J1D01*
G02Y439987I-1017J-1106D01*
G03X396529Y439840I135J-148D01*
G01Y439546D01*
G03X396594Y439399I200J1D01*
G02X397079Y438293I-1019J-1106D01*
G02X394075I-1502J0D01*
G02X394560Y439399I1504J0D01*
G03X394625Y439546I-135J148D01*
G01Y439840D01*
G03X394560Y439987I-200J-1D01*
G02Y442199I1017J1106D01*
G03X394625Y442346I-135J148D01*
G01Y442640D01*
G03X394560Y442787I-200J-1D01*
G02X394075Y443893I1019J1106D01*
G37*
G36*
G01X1298255D02*
G02X1301259I1502J0D01*
G02X1300774Y442787I-1504J0D01*
G03X1300709Y442640I135J-148D01*
G01Y442346D01*
G03X1300774Y442199I200J1D01*
G02Y439987I-1017J-1106D01*
G03X1300709Y439840I135J-148D01*
G01Y439546D01*
G03X1300774Y439399I200J1D01*
G02X1301259Y438293I-1019J-1106D01*
G02X1298255I-1502J0D01*
G02X1298740Y439399I1504J0D01*
G03X1298805Y439546I-135J148D01*
G01Y439840D01*
G03X1298740Y439987I-200J-1D01*
G02Y442199I1017J1106D01*
G03X1298805Y442346I-135J148D01*
G01Y442640D01*
G03X1298740Y442787I-200J-1D01*
G02X1298255Y443893I1019J1106D01*
G37*
G36*
G01X1308248D02*
G02X1311252I1502J0D01*
G02X1310767Y442787I-1504J0D01*
G03X1310702Y442640I135J-148D01*
G01Y442346D01*
G03X1310767Y442199I200J1D01*
G02Y439987I-1017J-1106D01*
G03X1310702Y439840I135J-148D01*
G01Y439546D01*
G03X1310767Y439399I200J1D01*
G02X1311252Y438293I-1019J-1106D01*
G02X1308248I-1502J0D01*
G02X1308733Y439399I1504J0D01*
G03X1308798Y439546I-135J148D01*
G01Y439840D01*
G03X1308733Y439987I-200J-1D01*
G02Y442199I1017J1106D01*
G03X1308798Y442346I-135J148D01*
G01Y442640D01*
G03X1308733Y442787I-200J-1D01*
G02X1308248Y443893I1019J1106D01*
G37*
G36*
G01X423952Y445369D02*
G02X425023Y445931I1071J-739D01*
G02Y443327I0J-1302D01*
G02X423952Y443889I0J1301D01*
G03X423294I-329J-228D01*
G02X422223Y443327I-1071J739D01*
G02Y445931I0J1302D01*
G02X423294Y445369I0J-1301D01*
G03X423952I329J228D01*
G37*
G36*
G01X1338125D02*
G02X1339196Y445931I1071J-739D01*
G02Y443327I0J-1302D01*
G02X1338125Y443889I0J1301D01*
G03X1337467I-329J-228D01*
G02X1336396Y443327I-1071J739D01*
G02Y445931I0J1302D01*
G02X1337467Y445369I0J-1301D01*
G03X1338125I329J228D01*
G37*
G36*
G01X263509Y446595D02*
G02X266513I1502J0D01*
G02X265117Y445097I-1502J0D01*
G03X264757Y444600I28J-399D01*
G02X264803Y444232I-1456J-369D01*
G02X261799I-1502J0D01*
G02X263195Y445730I1502J0D01*
G03X263555Y446227I-28J399D01*
G02X263509Y446595I1456J369D01*
G37*
G36*
G01X361754Y451593D02*
G02Y448589I0J-1502D01*
G02X360569Y449168I0J1502D01*
G03X360411Y449245I-158J-123D01*
G01X360096D01*
G03X359939Y449168I1J-200D01*
G02X359790Y449004I-1183J925D01*
G01X359755Y448970D01*
X359723Y448878D01*
X359782Y448504D01*
G03X359892Y448354I198J30D01*
G01X359893D01*
G02X360743Y447001I-652J-1353D01*
G02X359241Y445499I-1502J0D01*
G02X358056Y446078I0J1502D01*
G03X357898Y446155I-158J-123D01*
G01X357584D01*
G03X357426Y446078I0J-200D01*
G02X356241Y445499I-1185J923D01*
G02X354739Y447001I0J1502D01*
G02X354755Y447216I1502J-4D01*
G01Y447218D01*
G03X354681Y447402I-198J27D01*
G01X354368Y447651D01*
X354263Y447667D01*
X354213Y447647D01*
G02X353665Y447543I-549J1398D01*
G01X353663D01*
G02X355165Y449045I0J1502D01*
G02X355149Y448830I-1502J4D01*
G01Y448828D01*
G03X355223Y448644I198J-27D01*
G01X355536Y448395D01*
X355641Y448379D01*
X355691Y448399D01*
G02X356239Y448503I549J-1398D01*
G01X356241D01*
G02X357426Y447924I0J-1502D01*
G03X357584Y447847I158J123D01*
G01X357899D01*
G03X358056Y447924I-1J200D01*
G02X358205Y448088I1183J-925D01*
G01X358240Y448122D01*
X358272Y448214D01*
X358213Y448588D01*
G03X358103Y448738I-198J-30D01*
G01X358102D01*
G02X357252Y450091I652J1353D01*
G02X358754Y451593I1502J0D01*
G02X359939Y451014I0J-1502D01*
G03X360097Y450937I158J123D01*
G01X360411D01*
G03X360569Y451014I0J200D01*
G02X361754Y451593I1185J-923D01*
G37*
G36*
G01X1275927D02*
G02Y448589I0J-1502D01*
G02X1274742Y449168I0J1502D01*
G03X1274584Y449245I-158J-123D01*
G01X1274270D01*
G03X1274112Y449168I0J-200D01*
G02X1274001Y449041I-1185J923D01*
G01X1273968Y449008D01*
X1273939Y448918D01*
X1273997Y448553D01*
G03X1274100Y448408I197J31D01*
G02X1274899Y447081I-702J-1327D01*
G02X1273397Y445579I-1502J0D01*
G02X1272212Y446158I0J1502D01*
G03X1272054Y446235I-158J-123D01*
G01X1271740D01*
G03X1271582Y446158I0J-200D01*
G02X1270397Y445579I-1185J923D01*
G02X1268895Y447081I0J1502D01*
G02X1268902Y447226I1502J0D01*
G01X1268907Y447277D01*
X1268866Y447372D01*
X1268555Y447610D01*
G03X1268363Y447639I-122J-158D01*
G02X1267836Y447543I-528J1406D01*
G02X1269338Y449045I0J1502D01*
G02X1269331Y448900I-1502J0D01*
G01X1269326Y448849D01*
X1269367Y448754D01*
X1269678Y448516D01*
G03X1269870Y448487I122J158D01*
G02X1270397Y448583I528J-1406D01*
G02X1271582Y448004I0J-1502D01*
G03X1271740Y447927I158J123D01*
G01X1272054D01*
G03X1272212Y448004I0J200D01*
G02X1272323Y448131I1185J-923D01*
G01X1272356Y448164D01*
X1272385Y448254D01*
X1272327Y448619D01*
G03X1272224Y448764I-197J-31D01*
G02X1271425Y450091I702J1327D01*
G02X1272927Y451593I1502J0D01*
G02X1274112Y451014I0J-1502D01*
G03X1274270Y450937I158J123D01*
G01X1274584D01*
G03X1274742Y451014I0J200D01*
G02X1275927Y451593I1185J-923D01*
G37*
G36*
G01X919278Y451080D02*
G02X920349Y451642I1071J-739D01*
G02Y449038I0J-1302D01*
G02X919278Y449600I0J1301D01*
G03X918620I-329J-228D01*
G02X917549Y449038I-1071J739D01*
G02Y451642I0J1302D01*
G02X918620Y451080I0J-1301D01*
G03X919278I329J228D01*
G37*
G36*
G01Y454624D02*
G02X920349Y455186I1071J-739D01*
G02Y452582I0J-1302D01*
G02X919278Y453144I0J1301D01*
G03X918620I-329J-228D01*
G02X917549Y452582I-1071J739D01*
G02Y455186I0J1302D01*
G02X918620Y454624I0J-1301D01*
G03X919278I329J228D01*
G37*
G36*
G01X295807Y455679D02*
G02X297309Y454177I0J-1502D01*
G02X296939Y453190I-1501J0D01*
G01Y453189D01*
X296938D01*
G03X296890Y453059I152J-130D01*
G01Y452795D01*
G03X296938Y452665I200J0D01*
G01X296939Y452664D01*
G02X297309Y451677I-1131J-987D01*
G02X295807Y450175I-1502J0D01*
G02X294820Y450545I0J1501D01*
G01X294819D01*
Y450546D01*
G03X294689Y450594I-130J-152D01*
G01X294425D01*
G03X294295Y450546I0J-200D01*
G01X294294Y450545D01*
G02X293307Y450175I-987J1131D01*
G02X291805Y451677I0J1502D01*
G02X292175Y452664I1501J0D01*
G01Y452665D01*
X292176D01*
G03X292224Y452795I-152J130D01*
G01Y453059D01*
G03X292176Y453189I-200J0D01*
G01X292175Y453190D01*
G02X291805Y454177I1131J987D01*
G02X293307Y455679I1502J0D01*
G02X294294Y455309I0J-1501D01*
G01X294295D01*
Y455308D01*
G03X294425Y455260I130J152D01*
G01X294689D01*
G03X294819Y455308I0J200D01*
G01X294820Y455309D01*
G02X295807Y455679I987J-1131D01*
G37*
G36*
G01X752893D02*
G02X754395Y454177I0J-1502D01*
G02X754025Y453190I-1501J0D01*
G01Y453189D01*
X754024D01*
G03X753976Y453059I152J-130D01*
G01Y452795D01*
G03X754024Y452665I200J0D01*
G01X754025Y452664D01*
G02X754395Y451677I-1131J-987D01*
G02X752893Y450175I-1502J0D01*
G02X751906Y450545I0J1501D01*
G01X751905D01*
Y450546D01*
G03X751775Y450594I-130J-152D01*
G01X751511D01*
G03X751381Y450546I0J-200D01*
G01X751380Y450545D01*
G02X750393Y450175I-987J1131D01*
G02X748891Y451677I0J1502D01*
G02X749261Y452664I1501J0D01*
G01Y452665D01*
X749262D01*
G03X749310Y452795I-152J130D01*
G01Y453059D01*
G03X749262Y453189I-200J0D01*
G01X749261Y453190D01*
G02X748891Y454177I1131J987D01*
G02X750393Y455679I1502J0D01*
G02X751380Y455309I0J-1501D01*
G01X751381D01*
Y455308D01*
G03X751511Y455260I130J152D01*
G01X751775D01*
G03X751905Y455308I0J200D01*
G01X751906Y455309D01*
G02X752893Y455679I987J-1131D01*
G37*
G36*
G01X1209980D02*
G02X1211482Y454177I0J-1502D01*
G02X1211112Y453190I-1501J0D01*
G01Y453189D01*
X1211111D01*
G03X1211063Y453059I152J-130D01*
G01Y452795D01*
G03X1211111Y452665I200J0D01*
G01X1211112Y452664D01*
G02X1211482Y451677I-1131J-987D01*
G02X1209980Y450175I-1502J0D01*
G02X1208993Y450545I0J1501D01*
G01X1208992D01*
Y450546D01*
G03X1208862Y450594I-130J-152D01*
G01X1208598D01*
G03X1208468Y450546I0J-200D01*
G01X1208467Y450545D01*
G02X1207480Y450175I-987J1131D01*
G02X1205978Y451677I0J1502D01*
G02X1206348Y452664I1501J0D01*
G01Y452665D01*
X1206349D01*
G03X1206397Y452795I-152J130D01*
G01Y453059D01*
G03X1206349Y453189I-200J0D01*
G01X1206348Y453190D01*
G02X1205978Y454177I1131J987D01*
G02X1207480Y455679I1502J0D01*
G02X1208467Y455309I0J-1501D01*
G01X1208468D01*
Y455308D01*
G03X1208598Y455260I130J152D01*
G01X1208862D01*
G03X1208992Y455308I0J200D01*
G01X1208993Y455309D01*
G02X1209980Y455679I987J-1131D01*
G37*
G36*
G01X818840Y457562D02*
G02Y454558I0J-1502D01*
G02X817655Y455137I0J1502D01*
G03X817497Y455214I-158J-123D01*
G01X817183D01*
G03X817025Y455137I0J-200D01*
G02X815840Y454558I-1185J923D01*
G02Y457562I0J1502D01*
G02X817025Y456983I0J-1502D01*
G03X817183Y456906I158J123D01*
G01X817497D01*
G03X817655Y456983I0J200D01*
G02X818840Y457562I1185J-923D01*
G37*
G36*
G01X919278Y458167D02*
G02X920349Y458729I1071J-739D01*
G02Y456125I0J-1302D01*
G02X919278Y456687I0J1301D01*
G03X918620I-329J-228D01*
G02X917549Y456125I-1071J739D01*
G02Y458729I0J1302D01*
G02X918620Y458167I0J-1301D01*
G03X919278I329J228D01*
G37*
G36*
G01X910250Y461564D02*
G02X911752Y460062I0J-1502D01*
G02X911267Y458956I-1504J0D01*
G03X911202Y458809I135J-148D01*
G01Y458515D01*
G03X911267Y458368I200J1D01*
G02Y456156I-1017J-1106D01*
G03X911202Y456009I135J-148D01*
G01Y455715D01*
G03X911267Y455568I200J1D01*
G02Y453356I-1017J-1106D01*
G03X911202Y453209I135J-148D01*
G01Y452915D01*
G03X911267Y452768I200J1D01*
G02X911752Y451662I-1019J-1106D01*
G02X910250Y450160I-1502J0D01*
G02X909144Y450645I0J1504D01*
G03X908997Y450710I-148J-135D01*
G01X908703D01*
G03X908556Y450645I1J-200D01*
G02X907450Y450160I-1106J1019D01*
G02X905948Y451662I0J1502D01*
G02X906433Y452768I1504J0D01*
G03X906498Y452915I-135J148D01*
G01Y453209D01*
G03X906433Y453356I-200J-1D01*
G02Y455568I1017J1106D01*
G03X906498Y455715I-135J148D01*
G01Y456009D01*
G03X906433Y456156I-200J-1D01*
G02Y458368I1017J1106D01*
G03X906498Y458515I-135J148D01*
G01Y458809D01*
G03X906433Y458956I-200J-1D01*
G02X905948Y460062I1019J1106D01*
G02X907450Y461564I1502J0D01*
G02X908556Y461079I0J-1504D01*
G03X908703Y461014I148J135D01*
G01X908997D01*
G03X909144Y461079I-1J200D01*
G02X910250Y461564I1106J-1019D01*
G37*
G36*
G01X879408Y460234D02*
G02X882412I1502J0D01*
G02X881927Y459128I-1504J0D01*
G03X881862Y458981I135J-148D01*
G01Y458687D01*
G03X881927Y458540I200J1D01*
G02Y456328I-1017J-1106D01*
G03X881862Y456181I135J-148D01*
G01Y455887D01*
G03X881927Y455740I200J1D01*
G02X882412Y454634I-1019J-1106D01*
G02X879408I-1502J0D01*
G02X879893Y455740I1504J0D01*
G03X879958Y455887I-135J148D01*
G01Y456181D01*
G03X879893Y456328I-200J-1D01*
G02Y458540I1017J1106D01*
G03X879958Y458687I-135J148D01*
G01Y458981D01*
G03X879893Y459128I-200J-1D01*
G02X879408Y460234I1019J1106D01*
G37*
G36*
G01X889401D02*
G02X892405I1502J0D01*
G02X891920Y459128I-1504J0D01*
G03X891855Y458981I135J-148D01*
G01Y458687D01*
G03X891920Y458540I200J1D01*
G02Y456328I-1017J-1106D01*
G03X891855Y456181I135J-148D01*
G01Y455887D01*
G03X891920Y455740I200J1D01*
G02X892405Y454634I-1019J-1106D01*
G02X889401I-1502J0D01*
G02X889886Y455740I1504J0D01*
G03X889951Y455887I-135J148D01*
G01Y456181D01*
G03X889886Y456328I-200J-1D01*
G02Y458540I1017J1106D01*
G03X889951Y458687I-135J148D01*
G01Y458981D01*
G03X889886Y459128I-200J-1D01*
G02X889401Y460234I1019J1106D01*
G37*
G36*
G01X465126Y461937D02*
G02Y458933I0J-1502D01*
G02X463941Y459512I0J1502D01*
G03X463783Y459589I-158J-123D01*
G01X463469D01*
G03X463311Y459512I0J-200D01*
G02X462126Y458933I-1185J923D01*
G02Y461937I0J1502D01*
G02X463311Y461358I0J-1502D01*
G03X463469Y461281I158J123D01*
G01X463783D01*
G03X463941Y461358I0J200D01*
G02X465126Y461937I1185J-923D01*
G37*
G36*
G01X919278Y461710D02*
G02X920349Y462272I1071J-739D01*
G02Y459668I0J-1302D01*
G02X919278Y460230I0J1301D01*
G03X918620I-329J-228D01*
G02X917549Y459668I-1071J739D01*
G02Y462272I0J1302D01*
G02X918620Y461710I0J-1301D01*
G03X919278I329J228D01*
G37*
G36*
G01X528716Y463154D02*
G02X530218Y461652I0J-1502D01*
G02X529848Y460665I-1501J0D01*
G01Y460664D01*
X529847D01*
G03X529799Y460534I152J-130D01*
G01Y460270D01*
G03X529847Y460140I200J0D01*
G01X529848Y460139D01*
G02Y458165I-1131J-987D01*
G01Y458164D01*
X529847D01*
G03X529799Y458034I152J-130D01*
G01Y457770D01*
G03X529847Y457640I200J0D01*
G01X529848Y457639D01*
G02X530218Y456652I-1131J-987D01*
G02X528716Y455150I-1502J0D01*
G02X527729Y455520I0J1501D01*
G01X527728D01*
Y455521D01*
G03X527598Y455569I-130J-152D01*
G01X527334D01*
G03X527204Y455521I0J-200D01*
G01X527203Y455520D01*
G02X526216Y455150I-987J1131D01*
G02X524714Y456652I0J1502D01*
G02X525084Y457639I1501J0D01*
G01Y457640D01*
X525085D01*
G03X525133Y457770I-152J130D01*
G01Y458034D01*
G03X525085Y458164I-200J0D01*
G01X525084Y458165D01*
G02Y460139I1131J987D01*
G01Y460140D01*
X525085D01*
G03X525133Y460270I-152J130D01*
G01Y460534D01*
G03X525085Y460664I-200J0D01*
G01X525084Y460665D01*
G02X524714Y461652I1131J987D01*
G02X526216Y463154I1502J0D01*
G02X527203Y462784I0J-1501D01*
G01X527204D01*
Y462783D01*
G03X527334Y462735I130J152D01*
G01X527598D01*
G03X527728Y462783I0J200D01*
G01X527729Y462784D01*
G02X528716Y463154I987J-1131D01*
G37*
G36*
G01X853380Y461791D02*
G02X856384I1502J0D01*
G02X855899Y460685I-1504J0D01*
G03X855834Y460538I135J-148D01*
G01Y460244D01*
G03X855899Y460097I200J1D01*
G02X856384Y458991I-1019J-1106D01*
G02X853380I-1502J0D01*
G02X853865Y460097I1504J0D01*
G03X853930Y460244I-135J148D01*
G01Y460538D01*
G03X853865Y460685I-200J-1D01*
G02X853380Y461791I1019J1106D01*
G37*
G36*
G01X861380D02*
G02X864384I1502J0D01*
G02X863899Y460685I-1504J0D01*
G03X863834Y460538I135J-148D01*
G01Y460244D01*
G03X863899Y460097I200J1D01*
G02X864384Y458991I-1019J-1106D01*
G02X861380I-1502J0D01*
G02X861865Y460097I1504J0D01*
G03X861930Y460244I-135J148D01*
G01Y460538D01*
G03X861865Y460685I-200J-1D01*
G02X861380Y461791I1019J1106D01*
G37*
G36*
G01X869380D02*
G02X872384I1502J0D01*
G02X871899Y460685I-1504J0D01*
G03X871834Y460538I135J-148D01*
G01Y460244D01*
G03X871899Y460097I200J1D01*
G02X872384Y458991I-1019J-1106D01*
G02X869380I-1502J0D01*
G02X869865Y460097I1504J0D01*
G03X869930Y460244I-135J148D01*
G01Y460538D01*
G03X869865Y460685I-200J-1D01*
G02X869380Y461791I1019J1106D01*
G37*
G36*
G01X511808Y462004D02*
G02X514812I1502J0D01*
G02X513453Y460509I-1502J0D01*
G03X513299Y460411I19J-199D01*
G01X513136Y460131D01*
G03X513126Y459948I173J-101D01*
G02X513255Y459339I-1373J-609D01*
G02X512885Y458352I-1501J0D01*
G01Y458351D01*
X512884D01*
G03X512836Y458221I152J-130D01*
G01Y457957D01*
G03X512884Y457827I200J0D01*
G01X512885Y457826D01*
G02Y455852I-1131J-987D01*
G01Y455851D01*
X512884D01*
G03X512836Y455721I152J-130D01*
G01Y455457D01*
G03X512884Y455327I200J0D01*
G01X512885Y455326D01*
G02X513255Y454339I-1131J-987D01*
G02X511753Y452837I-1502J0D01*
G02X510766Y453207I0J1501D01*
G01X510765D01*
Y453208D01*
G03X510635Y453256I-130J-152D01*
G01X510371D01*
G03X510241Y453208I0J-200D01*
G01X510240Y453207D01*
G02X509253Y452837I-987J1131D01*
G02X507751Y454339I0J1502D01*
G02X508121Y455326I1501J0D01*
G01Y455327D01*
X508122D01*
G03X508170Y455457I-152J130D01*
G01Y455721D01*
G03X508122Y455851I-200J0D01*
G01X508121Y455852D01*
G02Y457826I1131J987D01*
G01Y457827D01*
X508122D01*
G03X508170Y457957I-152J130D01*
G01Y458221D01*
G03X508122Y458351I-200J0D01*
G01X508121Y458352D01*
G02X507751Y459339I1131J987D01*
G02X509253Y460841I1502J0D01*
G02X510240Y460471I0J-1501D01*
G01X510241D01*
Y460470D01*
G03X510371Y460422I130J152D01*
G01X510635D01*
G03X510765Y460470I0J200D01*
G01X510766Y460471D01*
G02X511610Y460834I987J-1132D01*
G03X511764Y460932I-19J199D01*
G01X511927Y461212D01*
G03X511937Y461395I-173J101D01*
G02X511808Y462004I1373J609D01*
G37*
G36*
G01X361754Y463562D02*
G02Y460558I0J-1502D01*
G02X360569Y461137I0J1502D01*
G03X360411Y461214I-158J-123D01*
G01X360097D01*
G03X359939Y461137I0J-200D01*
G02X358754Y460558I-1185J923D01*
G02Y463562I0J1502D01*
G02X359939Y462983I0J-1502D01*
G03X360097Y462906I158J123D01*
G01X360411D01*
G03X360569Y462983I0J200D01*
G02X361754Y463562I1185J-923D01*
G37*
G36*
G01X1275927D02*
G02Y460558I0J-1502D01*
G02X1274742Y461137I0J1502D01*
G03X1274584Y461214I-158J-123D01*
G01X1274270D01*
G03X1274112Y461137I0J-200D01*
G02X1272927Y460558I-1185J923D01*
G02Y463562I0J1502D01*
G02X1274112Y462983I0J-1502D01*
G03X1274270Y462906I158J123D01*
G01X1274584D01*
G03X1274742Y462983I0J200D01*
G02X1275927Y463562I1185J-923D01*
G37*
G36*
G01X467848Y466068D02*
G02Y463064I0J-1502D01*
G02X466663Y463643I0J1502D01*
G03X466505Y463720I-158J-123D01*
G01X466191D01*
G03X466033Y463643I0J-200D01*
G02X464848Y463064I-1185J923D01*
G02Y466068I0J1502D01*
G02X466033Y465489I0J-1502D01*
G03X466191Y465412I158J123D01*
G01X466505D01*
G03X466663Y465489I0J200D01*
G02X467848Y466068I1185J-923D01*
G37*
G36*
G01X73630Y466154D02*
G02X75132Y464652I0J-1502D01*
G02X74762Y463665I-1501J0D01*
G01Y463664D01*
X74761D01*
G03X74713Y463534I152J-130D01*
G01Y463270D01*
G03X74761Y463140I200J0D01*
G01X74762Y463139D01*
G02Y461165I-1131J-987D01*
G01Y461164D01*
X74761D01*
G03X74713Y461034I152J-130D01*
G01Y460770D01*
G03X74761Y460640I200J0D01*
G01X74762Y460639D01*
G02X75132Y459652I-1131J-987D01*
G02X73630Y458150I-1502J0D01*
G02X72643Y458520I0J1501D01*
G01X72642D01*
Y458521D01*
G03X72512Y458569I-130J-152D01*
G01X72248D01*
G03X72118Y458521I0J-200D01*
G01X72117Y458520D01*
G02X71130Y458150I-987J1131D01*
G02X69628Y459652I0J1502D01*
G02X69998Y460639I1501J0D01*
G01Y460640D01*
X69999D01*
G03X70047Y460770I-152J130D01*
G01Y461034D01*
G03X69999Y461164I-200J0D01*
G01X69998Y461165D01*
G02Y463139I1131J987D01*
G01Y463140D01*
X69999D01*
G03X70047Y463270I-152J130D01*
G01Y463534D01*
G03X69999Y463664I-200J0D01*
G01X69998Y463665D01*
G02X69628Y464652I1131J987D01*
G02X71130Y466154I1502J0D01*
G02X72117Y465784I0J-1501D01*
G01X72118D01*
Y465783D01*
G03X72248Y465735I130J152D01*
G01X72512D01*
G03X72642Y465783I0J200D01*
G01X72643Y465784D01*
G02X73630Y466154I987J-1131D01*
G37*
G36*
G01X987803D02*
G02X989305Y464652I0J-1502D01*
G02X988935Y463665I-1501J0D01*
G01Y463664D01*
X988934D01*
G03X988886Y463534I152J-130D01*
G01Y463270D01*
G03X988934Y463140I200J0D01*
G01X988935Y463139D01*
G02Y461165I-1131J-987D01*
G01Y461164D01*
X988934D01*
G03X988886Y461034I152J-130D01*
G01Y460770D01*
G03X988934Y460640I200J0D01*
G01X988935Y460639D01*
G02X989305Y459652I-1131J-987D01*
G02X987803Y458150I-1502J0D01*
G02X986816Y458520I0J1501D01*
G01X986815D01*
Y458521D01*
G03X986685Y458569I-130J-152D01*
G01X986421D01*
G03X986291Y458521I0J-200D01*
G01X986290Y458520D01*
G02X985303Y458150I-987J1131D01*
G02X983801Y459652I0J1502D01*
G02X984171Y460639I1501J0D01*
G01Y460640D01*
X984172D01*
G03X984220Y460770I-152J130D01*
G01Y461034D01*
G03X984172Y461164I-200J0D01*
G01X984171Y461165D01*
G02Y463139I1131J987D01*
G01Y463140D01*
X984172D01*
G03X984220Y463270I-152J130D01*
G01Y463534D01*
G03X984172Y463664I-200J0D01*
G01X984171Y463665D01*
G02X983801Y464652I1131J987D01*
G02X985303Y466154I1502J0D01*
G02X986290Y465784I0J-1501D01*
G01X986291D01*
Y465783D01*
G03X986421Y465735I130J152D01*
G01X986685D01*
G03X986815Y465783I0J200D01*
G01X986816Y465784D01*
G02X987803Y466154I987J-1131D01*
G37*
G36*
G01X56722Y465004D02*
G02X59726I1502J0D01*
G02X58367Y463509I-1502J0D01*
G03X58213Y463411I19J-199D01*
G01X58050Y463131D01*
G03X58040Y462948I173J-101D01*
G02X58169Y462339I-1373J-609D01*
G02X57799Y461352I-1501J0D01*
G01Y461351D01*
X57798D01*
G03X57750Y461221I152J-130D01*
G01Y460957D01*
G03X57798Y460827I200J0D01*
G01X57799Y460826D01*
G02Y458852I-1131J-987D01*
G01Y458851D01*
X57798D01*
G03X57750Y458721I152J-130D01*
G01Y458457D01*
G03X57798Y458327I200J0D01*
G01X57799Y458326D01*
G02X58169Y457339I-1131J-987D01*
G02X56667Y455837I-1502J0D01*
G02X55680Y456207I0J1501D01*
G01X55679D01*
Y456208D01*
G03X55549Y456256I-130J-152D01*
G01X55285D01*
G03X55155Y456208I0J-200D01*
G01X55154Y456207D01*
G02X54167Y455837I-987J1131D01*
G02X52665Y457339I0J1502D01*
G02X53035Y458326I1501J0D01*
G01Y458327D01*
X53036D01*
G03X53084Y458457I-152J130D01*
G01Y458721D01*
G03X53036Y458851I-200J0D01*
G01X53035Y458852D01*
G02Y460826I1131J987D01*
G01Y460827D01*
X53036D01*
G03X53084Y460957I-152J130D01*
G01Y461221D01*
G03X53036Y461351I-200J0D01*
G01X53035Y461352D01*
G02X52665Y462339I1131J987D01*
G02X54167Y463841I1502J0D01*
G02X55154Y463471I0J-1501D01*
G01X55155D01*
Y463470D01*
G03X55285Y463422I130J152D01*
G01X55549D01*
G03X55679Y463470I0J200D01*
G01X55680Y463471D01*
G02X56524Y463834I987J-1132D01*
G03X56678Y463932I-19J199D01*
G01X56841Y464212D01*
G03X56851Y464395I-173J101D01*
G02X56722Y465004I1373J609D01*
G37*
G36*
G01X970895D02*
G02X973899I1502J0D01*
G02X972540Y463509I-1502J0D01*
G03X972386Y463411I19J-199D01*
G01X972223Y463131D01*
G03X972213Y462948I173J-101D01*
G02X972342Y462339I-1373J-609D01*
G02X971972Y461352I-1501J0D01*
G01Y461351D01*
X971971D01*
G03X971923Y461221I152J-130D01*
G01Y460957D01*
G03X971971Y460827I200J0D01*
G01X971972Y460826D01*
G02Y458852I-1131J-987D01*
G01Y458851D01*
X971971D01*
G03X971923Y458721I152J-130D01*
G01Y458457D01*
G03X971971Y458327I200J0D01*
G01X971972Y458326D01*
G02X972342Y457339I-1131J-987D01*
G02X970840Y455837I-1502J0D01*
G02X969853Y456207I0J1501D01*
G01X969852D01*
Y456208D01*
G03X969722Y456256I-130J-152D01*
G01X969458D01*
G03X969328Y456208I0J-200D01*
G01X969327Y456207D01*
G02X968340Y455837I-987J1131D01*
G02X966838Y457339I0J1502D01*
G02X967208Y458326I1501J0D01*
G01Y458327D01*
X967209D01*
G03X967257Y458457I-152J130D01*
G01Y458721D01*
G03X967209Y458851I-200J0D01*
G01X967208Y458852D01*
G02Y460826I1131J987D01*
G01Y460827D01*
X967209D01*
G03X967257Y460957I-152J130D01*
G01Y461221D01*
G03X967209Y461351I-200J0D01*
G01X967208Y461352D01*
G02X966838Y462339I1131J987D01*
G02X968340Y463841I1502J0D01*
G02X969327Y463471I0J-1501D01*
G01X969328D01*
Y463470D01*
G03X969458Y463422I130J152D01*
G01X969722D01*
G03X969852Y463470I0J200D01*
G01X969853Y463471D01*
G02X970697Y463834I987J-1132D01*
G03X970851Y463932I-19J199D01*
G01X971014Y464212D01*
G03X971024Y464395I-173J101D01*
G02X970895Y465004I1373J609D01*
G37*
G36*
G01X376046Y471503D02*
G02Y468499I0J-1502D01*
G02X375059Y468869I0J1501D01*
G01X375058D01*
Y468870D01*
G03X374928Y468918I-130J-152D01*
G01X374664D01*
G03X374534Y468870I0J-200D01*
G01X374533Y468869D01*
G02X373546Y468499I-987J1131D01*
G02Y471503I0J1502D01*
G02X374533Y471133I0J-1501D01*
G01X374534D01*
Y471132D01*
G03X374664Y471084I130J152D01*
G01X374928D01*
G03X375058Y471132I0J200D01*
G01X375059Y471133D01*
G02X376046Y471503I987J-1131D01*
G37*
G36*
G01X1290219D02*
G02Y468499I0J-1502D01*
G02X1289232Y468869I0J1501D01*
G01X1289231D01*
Y468870D01*
G03X1289101Y468918I-130J-152D01*
G01X1288837D01*
G03X1288707Y468870I0J-200D01*
G01X1288706Y468869D01*
G02X1287719Y468499I-987J1131D01*
G02Y471503I0J1502D01*
G02X1288706Y471133I0J-1501D01*
G01X1288707D01*
Y471132D01*
G03X1288837Y471084I130J152D01*
G01X1289101D01*
G03X1289231Y471132I0J200D01*
G01X1289232Y471133D01*
G02X1290219Y471503I987J-1131D01*
G37*
G36*
G01X817328Y473555D02*
G02X818830Y472053I0J-1502D01*
G02X818131Y470783I-1503J0D01*
G03X818038Y470611I107J-169D01*
G01X818043Y470270D01*
G03X818142Y470101I200J4D01*
G02X818882Y468806I-763J-1295D01*
G02X817380Y467304I-1502J0D01*
G02X816274Y467789I0J1504D01*
G03X816127Y467854I-148J-135D01*
G01X815833D01*
G03X815686Y467789I1J-200D01*
G02X814580Y467304I-1106J1019D01*
G02X813078Y468806I0J1502D01*
G02X813904Y470147I1502J0D01*
G03X814014Y470311I-90J179D01*
G01X814043Y470705D01*
X813999Y470800D01*
X813956Y470830D01*
G02X813326Y472053I872J1223D01*
G02X814828Y473555I1502J0D01*
G02X815815Y473185I0J-1501D01*
G01X815816D01*
Y473184D01*
G03X815946Y473136I130J152D01*
G01X816210D01*
G03X816340Y473184I0J200D01*
G01X816341Y473185D01*
G02X817328Y473555I987J-1131D01*
G37*
G36*
G01X823544Y476563D02*
G02X825046Y475061I0J-1502D01*
G02X824676Y474074I-1501J0D01*
G01Y474073D01*
X824675D01*
G03X824627Y473943I152J-130D01*
G01Y473679D01*
G03X824675Y473549I200J0D01*
G01X824676Y473548D01*
G02X825046Y472561I-1131J-987D01*
G02X823544Y471059I-1502J0D01*
G02X822859Y471225I1J1502D01*
G01X822857D01*
G03X822680Y471227I-91J-178D01*
G01X822349Y471068D01*
X822292Y470994D01*
X822283Y470948D01*
G02X820810Y469741I-1473J295D01*
G02X819308Y471243I0J1502D01*
G02X819678Y472230I1501J0D01*
G01Y472231D01*
X819679D01*
G03X819727Y472361I-152J130D01*
G01Y472625D01*
G03X819679Y472755I-200J0D01*
G01X819678Y472756D01*
G02X819308Y473743I1131J987D01*
G02X820810Y475245I1502J0D01*
G02X821495Y475079I-1J-1502D01*
G01X821497D01*
G03X821674Y475077I91J178D01*
G01X822005Y475236D01*
X822062Y475310D01*
X822071Y475356D01*
G02X823544Y476563I1473J-295D01*
G37*
G36*
G01X809254Y476071D02*
G02X812258I1502J0D01*
G02X811888Y475084I-1501J0D01*
G01Y475083D01*
X811887D01*
G03X811839Y474953I152J-130D01*
G01Y474689D01*
G03X811887Y474559I200J0D01*
G01X811888Y474558D01*
G02Y472584I-1131J-987D01*
G01Y472583D01*
X811887D01*
G03X811839Y472453I152J-130D01*
G01Y472189D01*
G03X811887Y472059I200J0D01*
G01X811888Y472058D01*
G02Y470084I-1131J-987D01*
G01Y470083D01*
X811887D01*
G03X811839Y469953I152J-130D01*
G01Y469689D01*
G03X811887Y469559I200J0D01*
G01X811888Y469558D01*
G02X812258Y468571I-1131J-987D01*
G02X809254I-1502J0D01*
G02X809624Y469558I1501J0D01*
G01Y469559D01*
X809625D01*
G03X809673Y469689I-152J130D01*
G01Y469953D01*
G03X809625Y470083I-200J0D01*
G01X809624Y470084D01*
G02Y472058I1131J987D01*
G01Y472059D01*
X809625D01*
G03X809673Y472189I-152J130D01*
G01Y472453D01*
G03X809625Y472583I-200J0D01*
G01X809624Y472584D01*
G02Y474558I1131J987D01*
G01Y474559D01*
X809625D01*
G03X809673Y474689I-152J130D01*
G01Y474953D01*
G03X809625Y475083I-200J0D01*
G01X809624Y475084D01*
G02X809254Y476071I1131J987D01*
G37*
G36*
G01X467848Y478037D02*
G02Y475033I0J-1502D01*
G02X466663Y475612I0J1502D01*
G03X466505Y475689I-158J-123D01*
G01X466191D01*
G03X466033Y475612I0J-200D01*
G02X464848Y475033I-1185J923D01*
G02Y478037I0J1502D01*
G02X466033Y477458I0J-1502D01*
G03X466191Y477381I158J123D01*
G01X466505D01*
G03X466663Y477458I0J200D01*
G02X467848Y478037I1185J-923D01*
G37*
G36*
G01X360242Y478555D02*
G02Y475551I0J-1502D01*
G02X359255Y475921I0J1501D01*
G01X359254D01*
Y475922D01*
G03X359124Y475970I-130J-152D01*
G01X358860D01*
G03X358730Y475922I0J-200D01*
G01X358729Y475921D01*
G02X357742Y475551I-987J1131D01*
G02Y478555I0J1502D01*
G02X358729Y478185I0J-1501D01*
G01X358730D01*
Y478184D01*
G03X358860Y478136I130J152D01*
G01X359124D01*
G03X359254Y478184I0J200D01*
G01X359255Y478185D01*
G02X360242Y478555I987J-1131D01*
G37*
G36*
G01X1274415D02*
G02Y475551I0J-1502D01*
G02X1273428Y475921I0J1501D01*
G01X1273427D01*
Y475922D01*
G03X1273297Y475970I-130J-152D01*
G01X1273033D01*
G03X1272903Y475922I0J-200D01*
G01X1272902Y475921D01*
G02X1271915Y475551I-987J1131D01*
G02Y478555I0J1502D01*
G02X1272902Y478185I0J-1501D01*
G01X1272903D01*
Y478184D01*
G03X1273033Y478136I130J152D01*
G01X1273297D01*
G03X1273427Y478184I0J200D01*
G01X1273428Y478185D01*
G02X1274415Y478555I987J-1131D01*
G37*
G36*
G01X53622Y478625D02*
G02X56626I1502J0D01*
G02X56141Y477519I-1504J0D01*
G03X56076Y477372I135J-148D01*
G01Y477078D01*
G03X56141Y476931I200J1D01*
G02X56626Y475825I-1019J-1106D01*
G02X53622I-1502J0D01*
G02X54107Y476931I1504J0D01*
G03X54172Y477078I-135J148D01*
G01Y477372D01*
G03X54107Y477519I-200J-1D01*
G02X53622Y478625I1019J1106D01*
G37*
G36*
G01X510708D02*
G02X513712I1502J0D01*
G02X513227Y477519I-1504J0D01*
G03X513162Y477372I135J-148D01*
G01Y477078D01*
G03X513227Y476931I200J1D01*
G02X513712Y475825I-1019J-1106D01*
G02X510708I-1502J0D01*
G02X511193Y476931I1504J0D01*
G03X511258Y477078I-135J148D01*
G01Y477372D01*
G03X511193Y477519I-200J-1D01*
G02X510708Y478625I1019J1106D01*
G37*
G36*
G01X967795D02*
G02X970799I1502J0D01*
G02X970314Y477519I-1504J0D01*
G03X970249Y477372I135J-148D01*
G01Y477078D01*
G03X970314Y476931I200J1D01*
G02X970799Y475825I-1019J-1106D01*
G02X967795I-1502J0D01*
G02X968280Y476931I1504J0D01*
G03X968345Y477078I-135J148D01*
G01Y477372D01*
G03X968280Y477519I-200J-1D01*
G02X967795Y478625I1019J1106D01*
G37*
G36*
G01X366420Y481488D02*
G02X367922Y479986I0J-1502D01*
G02X367552Y478999I-1501J0D01*
G01Y478998D01*
X367551D01*
G03X367503Y478868I152J-130D01*
G01Y478604D01*
G03X367551Y478474I200J0D01*
G01X367552Y478473D01*
G02X367922Y477486I-1131J-987D01*
G02X366420Y475984I-1502J0D01*
G02X365735Y476150I1J1502D01*
G01X365733D01*
G03X365556Y476152I-91J-178D01*
G01X365225Y475993D01*
X365168Y475919D01*
X365159Y475873D01*
G02X363686Y474666I-1473J295D01*
G02X362184Y476168I0J1502D01*
G02X362554Y477155I1501J0D01*
G01Y477156D01*
X362555D01*
G03X362603Y477286I-152J130D01*
G01Y477550D01*
G03X362555Y477680I-200J0D01*
G01X362554Y477681D01*
G02X362184Y478668I1131J987D01*
G02X363686Y480170I1502J0D01*
G02X364371Y480004I-1J-1502D01*
G01X364373D01*
G03X364550Y480002I91J178D01*
G01X364881Y480161D01*
X364938Y480235D01*
X364947Y480281D01*
G02X366420Y481488I1473J-295D01*
G37*
G36*
G01X1280631Y481696D02*
G02X1282133Y480194I0J-1502D01*
G02X1281763Y479207I-1501J0D01*
G01Y479206D01*
X1281762D01*
G03X1281714Y479076I152J-130D01*
G01Y478812D01*
G03X1281762Y478682I200J0D01*
G01X1281763Y478681D01*
G02X1282133Y477694I-1131J-987D01*
G02X1280631Y476192I-1502J0D01*
G02X1279946Y476358I1J1502D01*
G01X1279944D01*
G03X1279767Y476360I-91J-178D01*
G01X1279436Y476201D01*
X1279379Y476127D01*
X1279370Y476081D01*
G02X1277897Y474874I-1473J295D01*
G02X1276395Y476376I0J1502D01*
G02X1276765Y477363I1501J0D01*
G01Y477364D01*
X1276766D01*
G03X1276814Y477494I-152J130D01*
G01Y477758D01*
G03X1276766Y477888I-200J0D01*
G01X1276765Y477889D01*
G02X1276395Y478876I1131J987D01*
G02X1277897Y480378I1502J0D01*
G02X1278582Y480212I-1J-1502D01*
G01X1278584D01*
G03X1278761Y480210I91J178D01*
G01X1279092Y480369D01*
X1279149Y480443D01*
X1279158Y480489D01*
G02X1280631Y481696I1473J-295D01*
G37*
G36*
G01X833918Y482082D02*
G02Y479078I0J-1502D01*
G02X832931Y479448I0J1501D01*
G01X832930D01*
Y479449D01*
G03X832800Y479497I-130J-152D01*
G01X832536D01*
G03X832406Y479449I0J-200D01*
G01X832405Y479448D01*
G02X830431I-987J1131D01*
G01X830430D01*
Y479449D01*
G03X830300Y479497I-130J-152D01*
G01X830036D01*
G03X829906Y479449I0J-200D01*
G01X829905Y479448D01*
G02X828918Y479078I-987J1131D01*
G02Y482082I0J1502D01*
G02X829905Y481712I0J-1501D01*
G01X829906D01*
Y481711D01*
G03X830036Y481663I130J152D01*
G01X830300D01*
G03X830430Y481711I0J200D01*
G01X830431Y481712D01*
G02X832405I987J-1131D01*
G01X832406D01*
Y481711D01*
G03X832536Y481663I130J152D01*
G01X832800D01*
G03X832930Y481711I0J200D01*
G01X832931Y481712D01*
G02X833918Y482082I987J-1131D01*
G37*
G36*
G01X352168Y481071D02*
G02X355172I1502J0D01*
G02X354802Y480084I-1501J0D01*
G01Y480083D01*
X354801D01*
G03X354753Y479953I152J-130D01*
G01Y479689D01*
G03X354801Y479559I200J0D01*
G01X354802Y479558D01*
G02Y477584I-1131J-987D01*
G01Y477583D01*
X354801D01*
G03X354753Y477453I152J-130D01*
G01Y477189D01*
G03X354801Y477059I200J0D01*
G01X354802Y477058D01*
G02Y475084I-1131J-987D01*
G01Y475083D01*
X354801D01*
G03X354753Y474953I152J-130D01*
G01Y474689D01*
G03X354801Y474559I200J0D01*
G01X354802Y474558D01*
G02X355172Y473571I-1131J-987D01*
G02X352168I-1502J0D01*
G02X352538Y474558I1501J0D01*
G01Y474559D01*
X352539D01*
G03X352587Y474689I-152J130D01*
G01Y474953D01*
G03X352539Y475083I-200J0D01*
G01X352538Y475084D01*
G02Y477058I1131J987D01*
G01Y477059D01*
X352539D01*
G03X352587Y477189I-152J130D01*
G01Y477453D01*
G03X352539Y477583I-200J0D01*
G01X352538Y477584D01*
G02Y479558I1131J987D01*
G01Y479559D01*
X352539D01*
G03X352587Y479689I-152J130D01*
G01Y479953D01*
G03X352539Y480083I-200J0D01*
G01X352538Y480084D01*
G02X352168Y481071I1131J987D01*
G37*
G36*
G01X1266341D02*
G02X1269345I1502J0D01*
G02X1268975Y480084I-1501J0D01*
G01Y480083D01*
X1268974D01*
G03X1268926Y479953I152J-130D01*
G01Y479689D01*
G03X1268974Y479559I200J0D01*
G01X1268975Y479558D01*
G02Y477584I-1131J-987D01*
G01Y477583D01*
X1268974D01*
G03X1268926Y477453I152J-130D01*
G01Y477189D01*
G03X1268974Y477059I200J0D01*
G01X1268975Y477058D01*
G02Y475084I-1131J-987D01*
G01Y475083D01*
X1268974D01*
G03X1268926Y474953I152J-130D01*
G01Y474689D01*
G03X1268974Y474559I200J0D01*
G01X1268975Y474558D01*
G02X1269345Y473571I-1131J-987D01*
G02X1266341I-1502J0D01*
G02X1266711Y474558I1501J0D01*
G01Y474559D01*
X1266712D01*
G03X1266760Y474689I-152J130D01*
G01Y474953D01*
G03X1266712Y475083I-200J0D01*
G01X1266711Y475084D01*
G02Y477058I1131J987D01*
G01Y477059D01*
X1266712D01*
G03X1266760Y477189I-152J130D01*
G01Y477453D01*
G03X1266712Y477583I-200J0D01*
G01X1266711Y477584D01*
G02Y479558I1131J987D01*
G01Y479559D01*
X1266712D01*
G03X1266760Y479689I-152J130D01*
G01Y479953D01*
G03X1266712Y480083I-200J0D01*
G01X1266711Y480084D01*
G02X1266341Y481071I1131J987D01*
G37*
G36*
G01X832941Y484934D02*
G02X834215Y485640I1274J-796D01*
G02Y482636I0J-1502D01*
G02X832995Y483262I0J1502D01*
G03X832331Y483240I-325J-234D01*
G02X831057Y482534I-1274J796D01*
G02Y485538I0J1502D01*
G02X832277Y484912I0J-1502D01*
G03X832941Y484934I325J234D01*
G37*
G36*
G01X56239Y486640D02*
G02X57741Y485138I0J-1502D01*
G02X57474Y484283I-1502J0D01*
G01X57451Y484249D01*
X57434Y484168D01*
X57514Y483801D01*
X57562Y483734D01*
X57597Y483713D01*
G02X58326Y482425I-773J-1288D01*
G02X55322I-1502J0D01*
G02X55589Y483280I1502J0D01*
G01X55612Y483314D01*
X55629Y483395D01*
X55549Y483762D01*
X55501Y483829D01*
X55466Y483850D01*
G02X55253Y484006I777J1285D01*
G03X55251Y484007I-88J-173D01*
G03X55121Y484055I-130J-152D01*
G01X54857D01*
G03X54727Y484007I0J-200D01*
G01X54726Y484006D01*
G02X52752I-987J1131D01*
G01X52751D01*
Y484007D01*
G03X52621Y484055I-130J-152D01*
G01X52357D01*
G03X52227Y484007I0J-200D01*
G01X52226Y484006D01*
G02X51239Y483636I-987J1131D01*
G02X50118Y484139I0J1501D01*
G01X50089Y484172D01*
X50012Y484206D01*
X49667Y484204D01*
G03X49519Y484138I0J-200D01*
G01X49518Y484137D01*
G02X48390Y483626I-1129J991D01*
G02Y486630I0J1502D01*
G02X49511Y486127I0J-1501D01*
G01X49540Y486094D01*
X49617Y486060D01*
X49962Y486062D01*
G03X50110Y486128I0J200D01*
G01X50111Y486129D01*
G02X51239Y486640I1129J-991D01*
G02X52226Y486270I0J-1501D01*
G01X52227D01*
Y486269D01*
G03X52357Y486221I130J152D01*
G01X52621D01*
G03X52751Y486269I0J200D01*
G01X52752Y486270D01*
G02X54726I987J-1131D01*
G01X54727D01*
Y486269D01*
G03X54857Y486221I130J152D01*
G01X55121D01*
G03X55251Y486269I0J200D01*
G01X55252Y486270D01*
G02X56239Y486640I987J-1131D01*
G37*
G36*
G01X513325D02*
G02X514827Y485138I0J-1502D01*
G02X514560Y484283I-1502J0D01*
G01X514537Y484249D01*
X514520Y484168D01*
X514600Y483801D01*
X514648Y483734D01*
X514683Y483713D01*
G02X515412Y482425I-773J-1288D01*
G02X512408I-1502J0D01*
G02X512675Y483280I1502J0D01*
G01X512698Y483314D01*
X512715Y483395D01*
X512635Y483762D01*
X512587Y483829D01*
X512552Y483850D01*
G02X512339Y484006I777J1285D01*
G03X512337Y484007I-88J-173D01*
G03X512207Y484055I-130J-152D01*
G01X511943D01*
G03X511813Y484007I0J-200D01*
G01X511812Y484006D01*
G02X509838I-987J1131D01*
G01X509837D01*
Y484007D01*
G03X509707Y484055I-130J-152D01*
G01X509443D01*
G03X509313Y484007I0J-200D01*
G01X509312Y484006D01*
G02X508325Y483636I-987J1131D01*
G02X507204Y484139I0J1501D01*
G01X507175Y484172D01*
X507098Y484206D01*
X506753Y484204D01*
G03X506605Y484138I0J-200D01*
G01X506604Y484137D01*
G02X505476Y483626I-1129J991D01*
G02Y486630I0J1502D01*
G02X506597Y486127I0J-1501D01*
G01X506626Y486094D01*
X506703Y486060D01*
X507048Y486062D01*
G03X507196Y486128I0J200D01*
G01X507197Y486129D01*
G02X508325Y486640I1129J-991D01*
G02X509312Y486270I0J-1501D01*
G01X509313D01*
Y486269D01*
G03X509443Y486221I130J152D01*
G01X509707D01*
G03X509837Y486269I0J200D01*
G01X509838Y486270D01*
G02X511812I987J-1131D01*
G01X511813D01*
Y486269D01*
G03X511943Y486221I130J152D01*
G01X512207D01*
G03X512337Y486269I0J200D01*
G01X512338Y486270D01*
G02X513325Y486640I987J-1131D01*
G37*
G36*
G01X970412D02*
G02X971914Y485138I0J-1502D01*
G02X971647Y484283I-1502J0D01*
G01X971624Y484249D01*
X971607Y484168D01*
X971687Y483801D01*
X971735Y483734D01*
X971770Y483713D01*
G02X972499Y482425I-773J-1288D01*
G02X969495I-1502J0D01*
G02X969762Y483280I1502J0D01*
G01X969785Y483314D01*
X969802Y483395D01*
X969722Y483762D01*
X969674Y483829D01*
X969639Y483850D01*
G02X969426Y484006I777J1285D01*
G03X969424Y484007I-88J-173D01*
G03X969294Y484055I-130J-152D01*
G01X969030D01*
G03X968900Y484007I0J-200D01*
G01X968899Y484006D01*
G02X966925I-987J1131D01*
G01X966924D01*
Y484007D01*
G03X966794Y484055I-130J-152D01*
G01X966530D01*
G03X966400Y484007I0J-200D01*
G01X966399Y484006D01*
G02X965412Y483636I-987J1131D01*
G02X964291Y484139I0J1501D01*
G01X964262Y484172D01*
X964185Y484206D01*
X963840Y484204D01*
G03X963692Y484138I0J-200D01*
G01X963691Y484137D01*
G02X962563Y483626I-1129J991D01*
G02Y486630I0J1502D01*
G02X963684Y486127I0J-1501D01*
G01X963713Y486094D01*
X963790Y486060D01*
X964135Y486062D01*
G03X964283Y486128I0J200D01*
G01X964284Y486129D01*
G02X965412Y486640I1129J-991D01*
G02X966399Y486270I0J-1501D01*
G01X966400D01*
Y486269D01*
G03X966530Y486221I130J152D01*
G01X966794D01*
G03X966924Y486269I0J200D01*
G01X966925Y486270D01*
G02X968899I987J-1131D01*
G01X968900D01*
Y486269D01*
G03X969030Y486221I130J152D01*
G01X969294D01*
G03X969424Y486269I0J200D01*
G01X969425Y486270D01*
G02X970412Y486640I987J-1131D01*
G37*
G36*
G01X376832Y487082D02*
G02Y484078I0J-1502D01*
G02X375845Y484448I0J1501D01*
G01X375844D01*
Y484449D01*
G03X375714Y484497I-130J-152D01*
G01X375450D01*
G03X375320Y484449I0J-200D01*
G01X375319Y484448D01*
G02X373345I-987J1131D01*
G01X373344D01*
Y484449D01*
G03X373214Y484497I-130J-152D01*
G01X372950D01*
G03X372820Y484449I0J-200D01*
G01X372819Y484448D01*
G02X371832Y484078I-987J1131D01*
G02Y487082I0J1502D01*
G02X372819Y486712I0J-1501D01*
G01X372820D01*
Y486711D01*
G03X372950Y486663I130J152D01*
G01X373214D01*
G03X373344Y486711I0J200D01*
G01X373345Y486712D01*
G02X375319I987J-1131D01*
G01X375320D01*
Y486711D01*
G03X375450Y486663I130J152D01*
G01X375714D01*
G03X375844Y486711I0J200D01*
G01X375845Y486712D01*
G02X376832Y487082I987J-1131D01*
G37*
G36*
G01X1291005D02*
G02Y484078I0J-1502D01*
G02X1290018Y484448I0J1501D01*
G01X1290017D01*
Y484449D01*
G03X1289887Y484497I-130J-152D01*
G01X1289623D01*
G03X1289493Y484449I0J-200D01*
G01X1289492Y484448D01*
G02X1287518I-987J1131D01*
G01X1287517D01*
Y484449D01*
G03X1287387Y484497I-130J-152D01*
G01X1287123D01*
G03X1286993Y484449I0J-200D01*
G01X1286992Y484448D01*
G02X1286005Y484078I-987J1131D01*
G02Y487082I0J1502D01*
G02X1286992Y486712I0J-1501D01*
G01X1286993D01*
Y486711D01*
G03X1287123Y486663I130J152D01*
G01X1287387D01*
G03X1287517Y486711I0J200D01*
G01X1287518Y486712D01*
G02X1289492I987J-1131D01*
G01X1289493D01*
Y486711D01*
G03X1289623Y486663I130J152D01*
G01X1289887D01*
G03X1290017Y486711I0J200D01*
G01X1290018Y486712D01*
G02X1291005Y487082I987J-1131D01*
G37*
G36*
G01X386633Y487382D02*
Y487381D01*
G02X386554Y486901I-1502J1D01*
G03X386976Y486375I379J-128D01*
G02X387139Y486384I164J-1493D01*
G01X387141D01*
G02X385639Y484882I0J-1502D01*
G01Y484883D01*
G02X385718Y485363I1502J-1D01*
G03X385296Y485889I-379J128D01*
G02X385133Y485880I-164J1493D01*
G01X385131D01*
G02X386633Y487382I0J1502D01*
G37*
G36*
G01X1300806D02*
Y487381D01*
G02X1300727Y486901I-1502J1D01*
G03X1301149Y486375I379J-128D01*
G02X1301312Y486384I164J-1493D01*
G01X1301314D01*
G02X1299812Y484882I0J-1502D01*
G01Y484883D01*
G02X1299891Y485363I1502J-1D01*
G03X1299469Y485889I-379J128D01*
G02X1299306Y485880I-164J1493D01*
G01X1299304D01*
G02X1300806Y487382I0J1502D01*
G37*
G36*
G01X831791Y490636D02*
G02X834795I1502J0D01*
G02X834310Y489530I-1504J0D01*
G03X834245Y489383I135J-148D01*
G01Y489089D01*
G03X834310Y488942I200J1D01*
G02X834795Y487836I-1019J-1106D01*
G02X831791I-1502J0D01*
G02X832276Y488942I1504J0D01*
G03X832341Y489089I-135J148D01*
G01Y489383D01*
G03X832276Y489530I-200J-1D01*
G02X831791Y490636I1019J1106D01*
G37*
G36*
G01X61198Y493714D02*
G02X64202I1502J0D01*
G02X63832Y492727I-1501J0D01*
G01Y492726D01*
X63831D01*
G03X63783Y492596I152J-130D01*
G01Y492332D01*
G03X63831Y492202I200J0D01*
G01X63832Y492201D01*
G02X64202Y491214I-1131J-987D01*
G02X61198I-1502J0D01*
G02X61568Y492201I1501J0D01*
G01Y492202D01*
X61569D01*
G03X61617Y492332I-152J130D01*
G01Y492596D01*
G03X61569Y492726I-200J0D01*
G01X61568Y492727D01*
G02X61198Y493714I1131J987D01*
G37*
G36*
G01X518284D02*
G02X521288I1502J0D01*
G02X520918Y492727I-1501J0D01*
G01Y492726D01*
X520917D01*
G03X520869Y492596I152J-130D01*
G01Y492332D01*
G03X520917Y492202I200J0D01*
G01X520918Y492201D01*
G02X521288Y491214I-1131J-987D01*
G02X518284I-1502J0D01*
G02X518654Y492201I1501J0D01*
G01Y492202D01*
X518655D01*
G03X518703Y492332I-152J130D01*
G01Y492596D01*
G03X518655Y492726I-200J0D01*
G01X518654Y492727D01*
G02X518284Y493714I1131J987D01*
G37*
G36*
G01X975371D02*
G02X978375I1502J0D01*
G02X978005Y492727I-1501J0D01*
G01Y492726D01*
X978004D01*
G03X977956Y492596I152J-130D01*
G01Y492332D01*
G03X978004Y492202I200J0D01*
G01X978005Y492201D01*
G02X978375Y491214I-1131J-987D01*
G02X975371I-1502J0D01*
G02X975741Y492201I1501J0D01*
G01Y492202D01*
X975742D01*
G03X975790Y492332I-152J130D01*
G01Y492596D01*
G03X975742Y492726I-200J0D01*
G01X975741Y492727D01*
G02X975371Y493714I1131J987D01*
G37*
G36*
G01X64901Y495487D02*
G02X67905I1502J0D01*
G02X67535Y494500I-1501J0D01*
G01Y494499D01*
X67534D01*
G03X67486Y494369I152J-130D01*
G01Y494105D01*
G03X67534Y493975I200J0D01*
G01X67535Y493974D01*
G02X67905Y492987I-1131J-987D01*
G02X64901I-1502J0D01*
G02X65271Y493974I1501J0D01*
G01Y493975D01*
X65272D01*
G03X65320Y494105I-152J130D01*
G01Y494369D01*
G03X65272Y494499I-200J0D01*
G01X65271Y494500D01*
G02X64901Y495487I1131J987D01*
G37*
G36*
G01X521987D02*
G02X524991I1502J0D01*
G02X524621Y494500I-1501J0D01*
G01Y494499D01*
X524620D01*
G03X524572Y494369I152J-130D01*
G01Y494105D01*
G03X524620Y493975I200J0D01*
G01X524621Y493974D01*
G02X524991Y492987I-1131J-987D01*
G02X521987I-1502J0D01*
G02X522357Y493974I1501J0D01*
G01Y493975D01*
X522358D01*
G03X522406Y494105I-152J130D01*
G01Y494369D01*
G03X522358Y494499I-200J0D01*
G01X522357Y494500D01*
G02X521987Y495487I1131J987D01*
G37*
G36*
G01X979074D02*
G02X982078I1502J0D01*
G02X981708Y494500I-1501J0D01*
G01Y494499D01*
X981707D01*
G03X981659Y494369I152J-130D01*
G01Y494105D01*
G03X981707Y493975I200J0D01*
G01X981708Y493974D01*
G02X982078Y492987I-1131J-987D01*
G02X979074I-1502J0D01*
G02X979444Y493974I1501J0D01*
G01Y493975D01*
X979445D01*
G03X979493Y494105I-152J130D01*
G01Y494369D01*
G03X979445Y494499I-200J0D01*
G01X979444Y494500D01*
G02X979074Y495487I1131J987D01*
G37*
G36*
G01X374705Y495636D02*
G02X377709I1502J0D01*
G02X377224Y494530I-1504J0D01*
G03X377159Y494383I135J-148D01*
G01Y494089D01*
G03X377224Y493942I200J1D01*
G02X377709Y492836I-1019J-1106D01*
G02X374705I-1502J0D01*
G02X375190Y493942I1504J0D01*
G03X375255Y494089I-135J148D01*
G01Y494383D01*
G03X375190Y494530I-200J-1D01*
G02X374705Y495636I1019J1106D01*
G37*
G36*
G01X1288878D02*
G02X1291882I1502J0D01*
G02X1291397Y494530I-1504J0D01*
G03X1291332Y494383I135J-148D01*
G01Y494089D01*
G03X1291397Y493942I200J1D01*
G02X1291882Y492836I-1019J-1106D01*
G02X1288878I-1502J0D01*
G02X1289363Y493942I1504J0D01*
G03X1289428Y494089I-135J148D01*
G01Y494383D01*
G03X1289363Y494530I-200J-1D01*
G02X1288878Y495636I1019J1106D01*
G37*
G36*
G01X73961Y499653D02*
G02X75463Y498151I0J-1502D01*
G02X74884Y496966I-1502J0D01*
G03X74807Y496808I123J-158D01*
G01Y496494D01*
G03X74884Y496336I200J0D01*
G02X75463Y495151I-923J-1185D01*
G02X73961Y493649I-1502J0D01*
G02X72974Y494019I0J1501D01*
G01X72973D01*
Y494020D01*
G03X72843Y494068I-130J-152D01*
G01X72579D01*
G03X72449Y494020I0J-200D01*
G01X72448Y494019D01*
G02X71461Y493649I-987J1131D01*
G02X69959Y495151I0J1502D01*
G02X70538Y496336I1502J0D01*
G03X70615Y496494I-123J158D01*
G01Y496808D01*
G03X70538Y496966I-200J0D01*
G02X69959Y498151I923J1185D01*
G02X71461Y499653I1502J0D01*
G02X72448Y499283I0J-1501D01*
G01X72449D01*
Y499282D01*
G03X72579Y499234I130J152D01*
G01X72843D01*
G03X72973Y499282I0J200D01*
G01X72974Y499283D01*
G02X73961Y499653I987J-1131D01*
G37*
G36*
G01X531047D02*
G02X532549Y498151I0J-1502D01*
G02X531970Y496966I-1502J0D01*
G03X531893Y496808I123J-158D01*
G01Y496494D01*
G03X531970Y496336I200J0D01*
G02X532549Y495151I-923J-1185D01*
G02X531047Y493649I-1502J0D01*
G02X530060Y494019I0J1501D01*
G01X530059D01*
Y494020D01*
G03X529929Y494068I-130J-152D01*
G01X529665D01*
G03X529535Y494020I0J-200D01*
G01X529534Y494019D01*
G02X528547Y493649I-987J1131D01*
G02X527045Y495151I0J1502D01*
G02X527517Y496244I1502J0D01*
G01X527518Y496245D01*
G03X527579Y496410I-138J145D01*
G01X527548Y496725D01*
G03X527454Y496875I-199J-20D01*
G02X526745Y498151I794J1276D01*
G02X528247Y499653I1502J0D01*
G02X529353Y499168I0J-1504D01*
G03X529500Y499103I148J135D01*
G01X529794D01*
G03X529941Y499168I-1J200D01*
G02X531047Y499653I1106J-1019D01*
G37*
G36*
G01X988134D02*
G02X989636Y498151I0J-1502D01*
G02X989057Y496966I-1502J0D01*
G03X988980Y496808I123J-158D01*
G01Y496494D01*
G03X989057Y496336I200J0D01*
G02X989636Y495151I-923J-1185D01*
G02X988134Y493649I-1502J0D01*
G02X987147Y494019I0J1501D01*
G01X987146D01*
Y494020D01*
G03X987016Y494068I-130J-152D01*
G01X986752D01*
G03X986622Y494020I0J-200D01*
G01X986621Y494019D01*
G02X985634Y493649I-987J1131D01*
G02X984132Y495151I0J1502D01*
G02X984604Y496244I1502J0D01*
G01X984605Y496245D01*
G03X984666Y496410I-138J145D01*
G01X984635Y496725D01*
G03X984541Y496875I-199J-20D01*
G02X983832Y498151I794J1276D01*
G02X985334Y499653I1502J0D01*
G02X986440Y499168I0J-1504D01*
G03X986587Y499103I148J135D01*
G01X986881D01*
G03X987028Y499168I-1J200D01*
G02X988134Y499653I1106J-1019D01*
G37*
G36*
G01X76531Y498633D02*
G02X79535I1502J0D01*
G02X79165Y497646I-1501J0D01*
G01Y497645D01*
X79164D01*
G03X79116Y497515I152J-130D01*
G01Y497251D01*
G03X79164Y497121I200J0D01*
G01X79165Y497120D01*
G02Y495146I-1131J-987D01*
G01Y495145D01*
X79164D01*
G03X79116Y495015I152J-130D01*
G01Y494751D01*
G03X79164Y494621I200J0D01*
G01X79165Y494620D01*
G02Y492646I-1131J-987D01*
G01Y492645D01*
X79164D01*
G03X79116Y492515I152J-130D01*
G01Y492251D01*
G03X79164Y492121I200J0D01*
G01X79165Y492120D01*
G02X79535Y491133I-1131J-987D01*
G02X76531I-1502J0D01*
G02X76901Y492120I1501J0D01*
G01Y492121D01*
X76902D01*
G03X76950Y492251I-152J130D01*
G01Y492515D01*
G03X76902Y492645I-200J0D01*
G01X76901Y492646D01*
G02Y494620I1131J987D01*
G01Y494621D01*
X76902D01*
G03X76950Y494751I-152J130D01*
G01Y495015D01*
G03X76902Y495145I-200J0D01*
G01X76901Y495146D01*
G02Y497120I1131J987D01*
G01Y497121D01*
X76902D01*
G03X76950Y497251I-152J130D01*
G01Y497515D01*
G03X76902Y497645I-200J0D01*
G01X76901Y497646D01*
G02X76531Y498633I1131J987D01*
G37*
G36*
G01X533617D02*
G02X536621I1502J0D01*
G02X536251Y497646I-1501J0D01*
G01Y497645D01*
X536250D01*
G03X536202Y497515I152J-130D01*
G01Y497251D01*
G03X536250Y497121I200J0D01*
G01X536251Y497120D01*
G02Y495146I-1131J-987D01*
G01Y495145D01*
X536250D01*
G03X536202Y495015I152J-130D01*
G01Y494751D01*
G03X536250Y494621I200J0D01*
G01X536251Y494620D01*
G02Y492646I-1131J-987D01*
G01Y492645D01*
X536250D01*
G03X536202Y492515I152J-130D01*
G01Y492251D01*
G03X536250Y492121I200J0D01*
G01X536251Y492120D01*
G02X536621Y491133I-1131J-987D01*
G02X533617I-1502J0D01*
G02X533987Y492120I1501J0D01*
G01Y492121D01*
X533988D01*
G03X534036Y492251I-152J130D01*
G01Y492515D01*
G03X533988Y492645I-200J0D01*
G01X533987Y492646D01*
G02Y494620I1131J987D01*
G01Y494621D01*
X533988D01*
G03X534036Y494751I-152J130D01*
G01Y495015D01*
G03X533988Y495145I-200J0D01*
G01X533987Y495146D01*
G02Y497120I1131J987D01*
G01Y497121D01*
X533988D01*
G03X534036Y497251I-152J130D01*
G01Y497515D01*
G03X533988Y497645I-200J0D01*
G01X533987Y497646D01*
G02X533617Y498633I1131J987D01*
G37*
G36*
G01X990704D02*
G02X993708I1502J0D01*
G02X993338Y497646I-1501J0D01*
G01Y497645D01*
X993337D01*
G03X993289Y497515I152J-130D01*
G01Y497251D01*
G03X993337Y497121I200J0D01*
G01X993338Y497120D01*
G02Y495146I-1131J-987D01*
G01Y495145D01*
X993337D01*
G03X993289Y495015I152J-130D01*
G01Y494751D01*
G03X993337Y494621I200J0D01*
G01X993338Y494620D01*
G02Y492646I-1131J-987D01*
G01Y492645D01*
X993337D01*
G03X993289Y492515I152J-130D01*
G01Y492251D01*
G03X993337Y492121I200J0D01*
G01X993338Y492120D01*
G02X993708Y491133I-1131J-987D01*
G02X990704I-1502J0D01*
G02X991074Y492120I1501J0D01*
G01Y492121D01*
X991075D01*
G03X991123Y492251I-152J130D01*
G01Y492515D01*
G03X991075Y492645I-200J0D01*
G01X991074Y492646D01*
G02Y494620I1131J987D01*
G01Y494621D01*
X991075D01*
G03X991123Y494751I-152J130D01*
G01Y495015D01*
G03X991075Y495145I-200J0D01*
G01X991074Y495146D01*
G02Y497120I1131J987D01*
G01Y497121D01*
X991075D01*
G03X991123Y497251I-152J130D01*
G01Y497515D01*
G03X991075Y497645I-200J0D01*
G01X991074Y497646D01*
G02X990704Y498633I1131J987D01*
G37*
G36*
G01X412773Y499969D02*
G02X415777I1502J0D01*
G02X415407Y498982I-1501J0D01*
G01Y498981D01*
X415406D01*
G03X415358Y498851I152J-130D01*
G01Y498587D01*
G03X415406Y498457I200J0D01*
G01X415407Y498456D01*
G02Y496482I-1131J-987D01*
G01Y496481D01*
X415406D01*
G03X415358Y496351I152J-130D01*
G01Y496087D01*
G03X415406Y495957I200J0D01*
G01X415407Y495956D01*
G02Y493982I-1131J-987D01*
G01Y493981D01*
X415406D01*
G03X415358Y493851I152J-130D01*
G01Y493587D01*
G03X415406Y493457I200J0D01*
G01X415407Y493456D01*
G02X415777Y492469I-1131J-987D01*
G02X412773I-1502J0D01*
G02X413143Y493456I1501J0D01*
G01Y493457D01*
X413144D01*
G03X413192Y493587I-152J130D01*
G01Y493851D01*
G03X413144Y493981I-200J0D01*
G01X413143Y493982D01*
G02Y495956I1131J987D01*
G01Y495957D01*
X413144D01*
G03X413192Y496087I-152J130D01*
G01Y496351D01*
G03X413144Y496481I-200J0D01*
G01X413143Y496482D01*
G02Y498456I1131J987D01*
G01Y498457D01*
X413144D01*
G03X413192Y498587I-152J130D01*
G01Y498851D01*
G03X413144Y498981I-200J0D01*
G01X413143Y498982D01*
G02X412773Y499969I1131J987D01*
G37*
G36*
G01X434287Y501525D02*
G02X435789Y503027I1502J0D01*
G02X437230Y501948I0J-1502D01*
G01Y501946D01*
G03X437352Y501816I192J58D01*
G01X437653Y501705D01*
G03X437830Y501723I70J187D01*
G01X437831Y501724D01*
G02X438644Y501963I813J-1263D01*
G02Y498959I0J-1502D01*
G01X438642D01*
G02X437921Y499144I1J1502D01*
G01X437876Y499169D01*
X437774D01*
X437388Y498958D01*
X437333Y498872D01*
X437330Y498821D01*
G02X435831Y497421I-1499J103D01*
G02X434329Y498923I0J1502D01*
G02X434719Y499933I1503J0D01*
G01X434744Y499961D01*
X434771Y500032D01*
X434766Y500344D01*
G03X434710Y500480I-200J-3D01*
G02X434287Y501525I1079J1045D01*
G37*
G36*
G01X426066Y502003D02*
G02X429070I1502J0D01*
G02X428508Y500831I-1503J0D01*
G01X428470Y500801D01*
X428431Y500715D01*
X428448Y500297D01*
X428494Y500215D01*
X428534Y500188D01*
G02X429195Y498943I-842J-1245D01*
G02X427693Y497441I-1502J0D01*
G02X426834Y497711I0J1501D01*
G01X426792Y497741D01*
X426691Y497752D01*
X426331Y497600D01*
G03X426211Y497451I77J-185D01*
G01Y497450D01*
G02X425863Y496717I-1480J254D01*
G01X425862Y496716D01*
G03X425814Y496586I152J-130D01*
G01Y496322D01*
G03X425862Y496192I200J0D01*
G01X425863Y496191D01*
G02Y494217I-1131J-987D01*
G01Y494216D01*
X425862D01*
G03X425814Y494086I152J-130D01*
G01Y493822D01*
G03X425862Y493692I200J0D01*
G01X425863Y493691D01*
G02X426233Y492704I-1131J-987D01*
G02X423229I-1502J0D01*
G02X423599Y493691I1501J0D01*
G01Y493692D01*
X423600D01*
G03X423648Y493822I-152J130D01*
G01Y494086D01*
G03X423600Y494216I-200J0D01*
G01X423599Y494217D01*
G02Y496191I1131J987D01*
G01Y496192D01*
X423600D01*
G03X423648Y496322I-152J130D01*
G01Y496586D01*
G03X423600Y496716I-200J0D01*
G01X423599Y496717D01*
G02Y498691I1131J987D01*
G01Y498692D01*
X423600D01*
G03X423648Y498822I-152J130D01*
G01Y499086D01*
G03X423600Y499216I-200J0D01*
G01X423599Y499217D01*
G02X423229Y500204I1131J987D01*
G02X424731Y501706I1502J0D01*
G02X425474Y501509I-1J-1502D01*
G01X425522Y501482D01*
X425632Y501484D01*
X426025Y501733D01*
X426075Y501833D01*
X426070Y501888D01*
G02X426066Y502003I1498J110D01*
G37*
G36*
G01X44801Y506327D02*
G02Y503323I0J-1502D01*
G02X43814Y503693I0J1501D01*
G01X43813D01*
Y503694D01*
G03X43683Y503742I-130J-152D01*
G01X43419D01*
G03X43289Y503694I0J-200D01*
G01X43288Y503693D01*
G02X41314I-987J1131D01*
G01X41313D01*
Y503694D01*
G03X41183Y503742I-130J-152D01*
G01X40919D01*
G03X40789Y503694I0J-200D01*
G01X40788Y503693D01*
G02X39801Y503323I-987J1131D01*
G02Y506327I0J1502D01*
G02X40788Y505957I0J-1501D01*
G01X40789D01*
Y505956D01*
G03X40919Y505908I130J152D01*
G01X41183D01*
G03X41313Y505956I0J200D01*
G01X41314Y505957D01*
G02X43288I987J-1131D01*
G01X43289D01*
Y505956D01*
G03X43419Y505908I130J152D01*
G01X43683D01*
G03X43813Y505956I0J200D01*
G01X43814Y505957D01*
G02X44801Y506327I987J-1131D01*
G37*
G36*
G01X501887D02*
G02Y503323I0J-1502D01*
G02X500900Y503693I0J1501D01*
G01X500899D01*
Y503694D01*
G03X500769Y503742I-130J-152D01*
G01X500505D01*
G03X500375Y503694I0J-200D01*
G01X500374Y503693D01*
G02X498400I-987J1131D01*
G01X498399D01*
Y503694D01*
G03X498269Y503742I-130J-152D01*
G01X498005D01*
G03X497875Y503694I0J-200D01*
G01X497874Y503693D01*
G02X496887Y503323I-987J1131D01*
G02Y506327I0J1502D01*
G02X497874Y505957I0J-1501D01*
G01X497875D01*
Y505956D01*
G03X498005Y505908I130J152D01*
G01X498269D01*
G03X498399Y505956I0J200D01*
G01X498400Y505957D01*
G02X500374I987J-1131D01*
G01X500375D01*
Y505956D01*
G03X500505Y505908I130J152D01*
G01X500769D01*
G03X500899Y505956I0J200D01*
G01X500900Y505957D01*
G02X501887Y506327I987J-1131D01*
G37*
G36*
G01X958974D02*
G02Y503323I0J-1502D01*
G02X957987Y503693I0J1501D01*
G01X957986D01*
Y503694D01*
G03X957856Y503742I-130J-152D01*
G01X957592D01*
G03X957462Y503694I0J-200D01*
G01X957461Y503693D01*
G02X955487I-987J1131D01*
G01X955486D01*
Y503694D01*
G03X955356Y503742I-130J-152D01*
G01X955092D01*
G03X954962Y503694I0J-200D01*
G01X954961Y503693D01*
G02X953974Y503323I-987J1131D01*
G02Y506327I0J1502D01*
G02X954961Y505957I0J-1501D01*
G01X954962D01*
Y505956D01*
G03X955092Y505908I130J152D01*
G01X955356D01*
G03X955486Y505956I0J200D01*
G01X955487Y505957D01*
G02X957461I987J-1131D01*
G01X957462D01*
Y505956D01*
G03X957592Y505908I130J152D01*
G01X957856D01*
G03X957986Y505956I0J200D01*
G01X957987Y505957D01*
G02X958974Y506327I987J-1131D01*
G37*
G36*
G01X450942Y507951D02*
G02Y504947I0J-1502D01*
G02X449955Y505317I0J1501D01*
G01X449954D01*
Y505318D01*
G03X449824Y505366I-130J-152D01*
G01X449560D01*
G03X449430Y505318I0J-200D01*
G01X449429Y505317D01*
G02X447455I-987J1131D01*
G01X447454D01*
Y505318D01*
G03X447324Y505366I-130J-152D01*
G01X447060D01*
G03X446930Y505318I0J-200D01*
G01X446929Y505317D01*
G02X445942Y504947I-987J1131D01*
G02Y507951I0J1502D01*
G02X446929Y507581I0J-1501D01*
G01X446930D01*
Y507580D01*
G03X447060Y507532I130J152D01*
G01X447324D01*
G03X447454Y507580I0J200D01*
G01X447455Y507581D01*
G02X449429I987J-1131D01*
G01X449430D01*
Y507580D01*
G03X449560Y507532I130J152D01*
G01X449824D01*
G03X449954Y507580I0J200D01*
G01X449955Y507581D01*
G02X450942Y507951I987J-1131D01*
G37*
G36*
G01X459645Y510988D02*
G02X461147Y509486I0J-1502D01*
G02X460092Y508052I-1502J0D01*
G01X460090D01*
G03X460010Y508003I62J-190D01*
G01X459365Y507359D01*
G03X459306Y507217I141J-142D01*
G01Y503616D01*
G03X459400Y503446I200J0D01*
G01X459733Y503239D01*
X459834Y503233D01*
X459881Y503256D01*
G02X460537Y503407I656J-1351D01*
G02Y500403I0J-1502D01*
G02X459881Y500554I0J1502D01*
G01X459834Y500577D01*
X459733Y500571D01*
X459400Y500364D01*
G03X459306Y500194I106J-170D01*
G01Y498729D01*
G03X459374Y498578I200J-1D01*
G01X459601Y498379D01*
G03X459757Y498331I132J150D01*
G01X459758D01*
G02X459952Y498344I197J-1489D01*
G02Y495340I0J-1502D01*
G02X459759Y495353I4J1502D01*
G01X459757D01*
G03X459601Y495305I-24J-198D01*
G01X459374Y495106D01*
G03X459306Y494955I132J-150D01*
G01Y493558D01*
G03X459373Y493408I200J-1D01*
G01X459629Y493181D01*
X459711Y493156D01*
X459753Y493161D01*
G02X459929Y493171I173J-1492D01*
G02Y490167I0J-1502D01*
G02X459753Y490177I-3J1502D01*
G01X459711Y490182D01*
X459629Y490157D01*
X459373Y489930D01*
G03X459306Y489780I133J-149D01*
G01Y475665D01*
G02X459305Y475606I-1306J-7D01*
G03X459355Y475465I200J-9D01*
G01X459438Y475370D01*
G03X459573Y475303I150J133D01*
G02X460963Y473805I-112J-1498D01*
G02X459461Y472303I-1502J0D01*
G02X458103Y473163I0J1502D01*
G01Y473165D01*
X458082Y473208D01*
X458005Y473266D01*
X457634Y473331D01*
G03X457459Y473276I-34J-197D01*
G01X452627Y468444D01*
G03X452578Y468364I141J-142D01*
G01Y468363D01*
G02X451144Y467307I-1434J446D01*
G02X449642Y468809I0J1502D01*
G02X450697Y470243I1502J0D01*
G01X450699D01*
G03X450779Y470292I-62J190D01*
G01X456635Y476147D01*
G03X456694Y476289I-141J142D01*
G01Y507843D01*
G02X457076Y508765I1306J-1D01*
G01X458162Y509851D01*
G03X458211Y509931I-141J142D01*
G01Y509932D01*
G02X459645Y510988I1434J-446D01*
G37*
G36*
G01X448525Y513014D02*
G02Y510010I0J-1502D01*
G02X447538Y510380I0J1501D01*
G01X447537D01*
Y510381D01*
G03X447407Y510429I-130J-152D01*
G01X447143D01*
G03X447013Y510381I0J-200D01*
G01X447012Y510380D01*
G02X446025Y510010I-987J1131D01*
G02Y513014I0J1502D01*
G02X447012Y512644I0J-1501D01*
G01X447013D01*
Y512643D01*
G03X447143Y512595I130J152D01*
G01X447407D01*
G03X447537Y512643I0J200D01*
G01X447538Y512644D01*
G02X448525Y513014I987J-1131D01*
G37*
G36*
G01X44742Y518903D02*
G02Y515899I0J-1502D01*
G02X43755Y516269I0J1501D01*
G01X43754D01*
Y516270D01*
G03X43624Y516318I-130J-152D01*
G01X43360D01*
G03X43230Y516270I0J-200D01*
G01X43229Y516269D01*
G02X41255I-987J1131D01*
G01X41254D01*
Y516270D01*
G03X41124Y516318I-130J-152D01*
G01X40860D01*
G03X40730Y516270I0J-200D01*
G01X40729Y516269D01*
G02X39742Y515899I-987J1131D01*
G02Y518903I0J1502D01*
G02X40729Y518533I0J-1501D01*
G01X40730D01*
Y518532D01*
G03X40860Y518484I130J152D01*
G01X41124D01*
G03X41254Y518532I0J200D01*
G01X41255Y518533D01*
G02X43229I987J-1131D01*
G01X43230D01*
Y518532D01*
G03X43360Y518484I130J152D01*
G01X43624D01*
G03X43754Y518532I0J200D01*
G01X43755Y518533D01*
G02X44742Y518903I987J-1131D01*
G37*
G36*
G01X501828D02*
G02Y515899I0J-1502D01*
G02X500841Y516269I0J1501D01*
G01X500840D01*
Y516270D01*
G03X500710Y516318I-130J-152D01*
G01X500446D01*
G03X500316Y516270I0J-200D01*
G01X500315Y516269D01*
G02X498341I-987J1131D01*
G01X498340D01*
Y516270D01*
G03X498210Y516318I-130J-152D01*
G01X497946D01*
G03X497816Y516270I0J-200D01*
G01X497815Y516269D01*
G02X496828Y515899I-987J1131D01*
G02Y518903I0J1502D01*
G02X497815Y518533I0J-1501D01*
G01X497816D01*
Y518532D01*
G03X497946Y518484I130J152D01*
G01X498210D01*
G03X498340Y518532I0J200D01*
G01X498341Y518533D01*
G02X500315I987J-1131D01*
G01X500316D01*
Y518532D01*
G03X500446Y518484I130J152D01*
G01X500710D01*
G03X500840Y518532I0J200D01*
G01X500841Y518533D01*
G02X501828Y518903I987J-1131D01*
G37*
G36*
G01X958915D02*
G02Y515899I0J-1502D01*
G02X957928Y516269I0J1501D01*
G01X957927D01*
Y516270D01*
G03X957797Y516318I-130J-152D01*
G01X957533D01*
G03X957403Y516270I0J-200D01*
G01X957402Y516269D01*
G02X955428I-987J1131D01*
G01X955427D01*
Y516270D01*
G03X955297Y516318I-130J-152D01*
G01X955033D01*
G03X954903Y516270I0J-200D01*
G01X954902Y516269D01*
G02X953915Y515899I-987J1131D01*
G02Y518903I0J1502D01*
G02X954902Y518533I0J-1501D01*
G01X954903D01*
Y518532D01*
G03X955033Y518484I130J152D01*
G01X955297D01*
G03X955427Y518532I0J200D01*
G01X955428Y518533D01*
G02X957402I987J-1131D01*
G01X957403D01*
Y518532D01*
G03X957533Y518484I130J152D01*
G01X957797D01*
G03X957927Y518532I0J200D01*
G01X957928Y518533D01*
G02X958915Y518903I987J-1131D01*
G37*
G36*
G01X448525Y521201D02*
G02Y518197I0J-1502D01*
G02X447538Y518567I0J1501D01*
G01X447537D01*
Y518568D01*
G03X447407Y518616I-130J-152D01*
G01X447143D01*
G03X447013Y518568I0J-200D01*
G01X447012Y518567D01*
G02X446025Y518197I-987J1131D01*
G02Y521201I0J1502D01*
G02X447012Y520831I0J-1501D01*
G01X447013D01*
Y520830D01*
G03X447143Y520782I130J152D01*
G01X447407D01*
G03X447537Y520830I0J200D01*
G01X447538Y520831D01*
G02X448525Y521201I987J-1131D01*
G37*
G36*
G01X1321164Y524632D02*
G02X1322666Y523130I0J-1502D01*
G02X1322255Y522098I-1501J0D01*
G01X1322254Y522097D01*
G03X1322201Y521940I146J-137D01*
G01X1322235Y521596D01*
X1322279Y521521D01*
X1322315Y521496D01*
G02X1322952Y520268I-865J-1228D01*
G02X1321450Y518766I-1502J0D01*
G02X1320200Y519436I0J1501D01*
G01X1320170Y519481D01*
X1320075Y519528D01*
X1319674Y519502D01*
G03X1319508Y519390I14J-200D01*
G02X1318160Y518551I-1348J663D01*
G02X1316658Y520053I0J1502D01*
G02X1317160Y521174I1503J0D01*
G01X1317161D01*
G03X1317227Y521338I-134J149D01*
G01X1317201Y521701D01*
X1317154Y521780D01*
X1317115Y521806D01*
G02X1316443Y523058I830J1252D01*
G02X1317945Y524560I1502J0D01*
G02X1319198Y523886I0J-1502D01*
G03X1319369Y523796I167J110D01*
G01X1319708Y523804D01*
G03X1319875Y523901I-4J200D01*
G02X1321164Y524632I1289J-771D01*
G37*
G36*
G01X43791Y525369D02*
G02X46795I1502J0D01*
G02X46310Y524263I-1504J0D01*
G03X46245Y524116I135J-148D01*
G01Y523822D01*
G03X46310Y523675I200J1D01*
G02X46795Y522569I-1019J-1106D01*
G02X43791I-1502J0D01*
G02X44276Y523675I1504J0D01*
G03X44341Y523822I-135J148D01*
G01Y524116D01*
G03X44276Y524263I-200J-1D01*
G02X43791Y525369I1019J1106D01*
G37*
G36*
G01X500877D02*
G02X503881I1502J0D01*
G02X503396Y524263I-1504J0D01*
G03X503331Y524116I135J-148D01*
G01Y523822D01*
G03X503396Y523675I200J1D01*
G02X503881Y522569I-1019J-1106D01*
G02X500877I-1502J0D01*
G02X501362Y523675I1504J0D01*
G03X501427Y523822I-135J148D01*
G01Y524116D01*
G03X501362Y524263I-200J-1D01*
G02X500877Y525369I1019J1106D01*
G37*
G36*
G01X957964D02*
G02X960968I1502J0D01*
G02X960483Y524263I-1504J0D01*
G03X960418Y524116I135J-148D01*
G01Y523822D01*
G03X960483Y523675I200J1D01*
G02X960968Y522569I-1019J-1106D01*
G02X957964I-1502J0D01*
G02X958449Y523675I1504J0D01*
G03X958514Y523822I-135J148D01*
G01Y524116D01*
G03X958449Y524263I-200J-1D01*
G02X957964Y525369I1019J1106D01*
G37*
G36*
G01X1139673Y532306D02*
X1139674D01*
G02X1141304Y531631I0J-2306D01*
G01X1150731Y522204D01*
G02X1151406Y520574I-1631J-1630D01*
G01Y458946D01*
G03X1151465Y458804I200J0D01*
G01X1165990Y444279D01*
X1166119Y444260D01*
X1166177Y444290D01*
G02X1166867Y444458I690J-1334D01*
G01X1166868D01*
G02X1168370Y442956I0J-1502D01*
G01Y442955D01*
G02X1168202Y442265I-1502J0D01*
G01X1168172Y442207D01*
X1168191Y442078D01*
X1170316Y439954D01*
G02X1170992Y438323I-1631J-1632D01*
G02X1168685Y436016I-2307J0D01*
G02X1167054Y436692I1J2307D01*
G01X1147469Y456277D01*
G02X1146794Y457907I1631J1630D01*
G01Y519535D01*
G03X1146735Y519677I-200J0D01*
G01X1138042Y528369D01*
G02X1137366Y530000I1631J1632D01*
G02X1139673Y532306I2307J-1D01*
G37*
G36*
G01X38358Y530446D02*
G02Y533450I0J1502D01*
G02X39582Y532819I0J-1503D01*
G01X39609Y532780D01*
X39693Y532736D01*
X40061Y532728D01*
G03X40223Y532805I4J200D01*
G02X41408Y533384I1185J-923D01*
G02X42395Y533014I0J-1501D01*
G01X42396D01*
Y533013D01*
G03X42526Y532965I130J152D01*
G01X42790D01*
G03X42920Y533013I0J200D01*
G01X42921Y533014D01*
G02X44895I987J-1131D01*
G01X44896D01*
Y533013D01*
G03X45026Y532965I130J152D01*
G01X45290D01*
G03X45420Y533013I0J200D01*
G01X45421Y533014D01*
G02X46408Y533384I987J-1131D01*
G02X47910Y531882I0J-1502D01*
G02X47643Y531027I-1502J0D01*
G01X47620Y530993D01*
X47603Y530912D01*
X47683Y530545D01*
X47731Y530478D01*
X47766Y530457D01*
G02X48495Y529169I-773J-1288D01*
G02X45491I-1502J0D01*
G02X45758Y530024I1502J0D01*
G01X45781Y530058D01*
X45798Y530139D01*
X45718Y530506D01*
X45670Y530573D01*
X45635Y530594D01*
G02X45422Y530750I777J1285D01*
G03X45420Y530751I-88J-173D01*
G03X45290Y530799I-130J-152D01*
G01X45026D01*
G03X44896Y530751I0J-200D01*
G01X44895Y530750D01*
G02X42921I-987J1131D01*
G01X42920D01*
Y530751D01*
G03X42790Y530799I-130J-152D01*
G01X42526D01*
G03X42396Y530751I0J-200D01*
G01X42395Y530750D01*
G02X41408Y530380I-987J1131D01*
G02X40184Y531011I0J1503D01*
G01X40157Y531050D01*
X40073Y531094D01*
X39705Y531102D01*
G03X39543Y531025I-4J-200D01*
G02X38358Y530446I-1185J923D01*
G37*
G36*
G01X495444D02*
G02Y533450I0J1502D01*
G02X496668Y532819I0J-1503D01*
G01X496695Y532780D01*
X496779Y532736D01*
X497147Y532728D01*
G03X497309Y532805I4J200D01*
G02X498494Y533384I1185J-923D01*
G02X499481Y533014I0J-1501D01*
G01X499482D01*
Y533013D01*
G03X499612Y532965I130J152D01*
G01X499876D01*
G03X500006Y533013I0J200D01*
G01X500007Y533014D01*
G02X501981I987J-1131D01*
G01X501982D01*
Y533013D01*
G03X502112Y532965I130J152D01*
G01X502376D01*
G03X502506Y533013I0J200D01*
G01X502507Y533014D01*
G02X503494Y533384I987J-1131D01*
G02X504996Y531882I0J-1502D01*
G02X504729Y531027I-1502J0D01*
G01X504706Y530993D01*
X504689Y530912D01*
X504769Y530545D01*
X504817Y530478D01*
X504852Y530457D01*
G02X505581Y529169I-773J-1288D01*
G02X502577I-1502J0D01*
G02X502844Y530024I1502J0D01*
G01X502867Y530058D01*
X502884Y530139D01*
X502804Y530506D01*
X502756Y530573D01*
X502721Y530594D01*
G02X502508Y530750I777J1285D01*
G03X502506Y530751I-88J-173D01*
G03X502376Y530799I-130J-152D01*
G01X502112D01*
G03X501982Y530751I0J-200D01*
G01X501981Y530750D01*
G02X500007I-987J1131D01*
G01X500006D01*
Y530751D01*
G03X499876Y530799I-130J-152D01*
G01X499612D01*
G03X499482Y530751I0J-200D01*
G01X499481Y530750D01*
G02X498494Y530380I-987J1131D01*
G02X497270Y531011I0J1503D01*
G01X497243Y531050D01*
X497159Y531094D01*
X496791Y531102D01*
G03X496629Y531025I-4J-200D01*
G02X495444Y530446I-1185J923D01*
G37*
G36*
G01X952531D02*
G02Y533450I0J1502D01*
G02X953755Y532819I0J-1503D01*
G01X953782Y532780D01*
X953866Y532736D01*
X954234Y532728D01*
G03X954396Y532805I4J200D01*
G02X955581Y533384I1185J-923D01*
G02X956568Y533014I0J-1501D01*
G01X956569D01*
Y533013D01*
G03X956699Y532965I130J152D01*
G01X956963D01*
G03X957093Y533013I0J200D01*
G01X957094Y533014D01*
G02X959068I987J-1131D01*
G01X959069D01*
Y533013D01*
G03X959199Y532965I130J152D01*
G01X959463D01*
G03X959593Y533013I0J200D01*
G01X959594Y533014D01*
G02X960581Y533384I987J-1131D01*
G02X962083Y531882I0J-1502D01*
G02X961816Y531027I-1502J0D01*
G01X961793Y530993D01*
X961776Y530912D01*
X961856Y530545D01*
X961904Y530478D01*
X961939Y530457D01*
G02X962668Y529169I-773J-1288D01*
G02X959664I-1502J0D01*
G02X959931Y530024I1502J0D01*
G01X959954Y530058D01*
X959971Y530139D01*
X959891Y530506D01*
X959843Y530573D01*
X959808Y530594D01*
G02X959595Y530750I777J1285D01*
G03X959593Y530751I-88J-173D01*
G03X959463Y530799I-130J-152D01*
G01X959199D01*
G03X959069Y530751I0J-200D01*
G01X959068Y530750D01*
G02X957094I-987J1131D01*
G01X957093D01*
Y530751D01*
G03X956963Y530799I-130J-152D01*
G01X956699D01*
G03X956569Y530751I0J-200D01*
G01X956568Y530750D01*
G02X955581Y530380I-987J1131D01*
G02X954357Y531011I0J1503D01*
G01X954330Y531050D01*
X954246Y531094D01*
X953878Y531102D01*
G03X953716Y531025I-4J-200D01*
G02X952531Y530446I-1185J923D01*
G37*
G36*
G01X898429Y534093D02*
G02X901433I1502J0D01*
G02X900469Y532691I-1502J0D01*
G03X900385Y531988I143J-374D01*
G02X901032Y530753I-855J-1235D01*
G02X898028I-1502J0D01*
G02X898992Y532155I1502J0D01*
G03X899076Y532858I-143J374D01*
G02X898429Y534093I855J1235D01*
G37*
G36*
G01X51367Y540458D02*
G02X54371I1502J0D01*
G02X54001Y539471I-1501J0D01*
G01Y539470D01*
X54000D01*
G03X53952Y539340I152J-130D01*
G01Y539076D01*
G03X54000Y538946I200J0D01*
G01X54001Y538945D01*
G02X54371Y537958I-1131J-987D01*
G02X51367I-1502J0D01*
G02X51737Y538945I1501J0D01*
G01Y538946D01*
X51738D01*
G03X51786Y539076I-152J130D01*
G01Y539340D01*
G03X51738Y539470I-200J0D01*
G01X51737Y539471D01*
G02X51367Y540458I1131J987D01*
G37*
G36*
G01X508453D02*
G02X511457I1502J0D01*
G02X511087Y539471I-1501J0D01*
G01Y539470D01*
X511086D01*
G03X511038Y539340I152J-130D01*
G01Y539076D01*
G03X511086Y538946I200J0D01*
G01X511087Y538945D01*
G02X511457Y537958I-1131J-987D01*
G02X508453I-1502J0D01*
G02X508823Y538945I1501J0D01*
G01Y538946D01*
X508824D01*
G03X508872Y539076I-152J130D01*
G01Y539340D01*
G03X508824Y539470I-200J0D01*
G01X508823Y539471D01*
G02X508453Y540458I1131J987D01*
G37*
G36*
G01X965540D02*
G02X968544I1502J0D01*
G02X968059Y539352I-1504J0D01*
G03X967994Y539205I135J-148D01*
G01Y538911D01*
G03X968059Y538764I200J1D01*
G02X968544Y537658I-1019J-1106D01*
G02X965540I-1502J0D01*
G02X966025Y538764I1504J0D01*
G03X966090Y538911I-135J148D01*
G01Y539205D01*
G03X966025Y539352I-200J-1D01*
G02X965540Y540458I1019J1106D01*
G37*
G36*
G01X55070Y542231D02*
G02X58074I1502J0D01*
G02X57704Y541244I-1501J0D01*
G01Y541243D01*
X57703D01*
G03X57655Y541113I152J-130D01*
G01Y540849D01*
G03X57703Y540719I200J0D01*
G01X57704Y540718D01*
G02X58074Y539731I-1131J-987D01*
G02X55070I-1502J0D01*
G02X55440Y540718I1501J0D01*
G01Y540719D01*
X55441D01*
G03X55489Y540849I-152J130D01*
G01Y541113D01*
G03X55441Y541243I-200J0D01*
G01X55440Y541244D01*
G02X55070Y542231I1131J987D01*
G37*
G36*
G01X512156D02*
G02X515160I1502J0D01*
G02X514790Y541244I-1501J0D01*
G01Y541243D01*
X514789D01*
G03X514741Y541113I152J-130D01*
G01Y540849D01*
G03X514789Y540719I200J0D01*
G01X514790Y540718D01*
G02X515160Y539731I-1131J-987D01*
G02X512156I-1502J0D01*
G02X512526Y540718I1501J0D01*
G01Y540719D01*
X512527D01*
G03X512575Y540849I-152J130D01*
G01Y541113D01*
G03X512527Y541243I-200J0D01*
G01X512526Y541244D01*
G02X512156Y542231I1131J987D01*
G37*
G36*
G01X969243D02*
G02X972247I1502J0D01*
G02X971877Y541244I-1501J0D01*
G01Y541243D01*
X971876D01*
G03X971828Y541113I152J-130D01*
G01Y540849D01*
G03X971876Y540719I200J0D01*
G01X971877Y540718D01*
G02X972247Y539731I-1131J-987D01*
G02X969243I-1502J0D01*
G02X969613Y540718I1501J0D01*
G01Y540719D01*
X969614D01*
G03X969662Y540849I-152J130D01*
G01Y541113D01*
G03X969614Y541243I-200J0D01*
G01X969613Y541244D01*
G02X969243Y542231I1131J987D01*
G37*
G36*
G01X64130Y546397D02*
G02X65632Y544895I0J-1502D01*
G02X65053Y543710I-1502J0D01*
G03X64976Y543552I123J-158D01*
G01Y543238D01*
G03X65053Y543080I200J0D01*
G02X65632Y541895I-923J-1185D01*
G02X64130Y540393I-1502J0D01*
G02X63143Y540763I0J1501D01*
G01X63142D01*
Y540764D01*
G03X63012Y540812I-130J-152D01*
G01X62748D01*
G03X62618Y540764I0J-200D01*
G01X62617Y540763D01*
G02X61630Y540393I-987J1131D01*
G02X60128Y541895I0J1502D01*
G02X60600Y542988I1502J0D01*
G01X60601Y542989D01*
G03X60662Y543154I-138J145D01*
G01X60631Y543469D01*
G03X60537Y543619I-199J-20D01*
G02X59828Y544895I794J1276D01*
G02X61330Y546397I1502J0D01*
G02X62436Y545912I0J-1504D01*
G03X62583Y545847I148J135D01*
G01X62877D01*
G03X63024Y545912I-1J200D01*
G02X64130Y546397I1106J-1019D01*
G37*
G36*
G01X521216D02*
G02X522718Y544895I0J-1502D01*
G02X522139Y543710I-1502J0D01*
G03X522062Y543552I123J-158D01*
G01Y543238D01*
G03X522139Y543080I200J0D01*
G02X522718Y541895I-923J-1185D01*
G02X521216Y540393I-1502J0D01*
G02X520229Y540763I0J1501D01*
G01X520228D01*
Y540764D01*
G03X520098Y540812I-130J-152D01*
G01X519834D01*
G03X519704Y540764I0J-200D01*
G01X519703Y540763D01*
G02X518716Y540393I-987J1131D01*
G02X517214Y541895I0J1502D01*
G02X517686Y542988I1502J0D01*
G01X517687Y542989D01*
G03X517748Y543154I-138J145D01*
G01X517717Y543469D01*
G03X517623Y543619I-199J-20D01*
G02X516914Y544895I794J1276D01*
G02X518416Y546397I1502J0D01*
G02X519522Y545912I0J-1504D01*
G03X519669Y545847I148J135D01*
G01X519963D01*
G03X520110Y545912I-1J200D01*
G02X521216Y546397I1106J-1019D01*
G37*
G36*
G01X978303D02*
G02X979805Y544895I0J-1502D01*
G02X979226Y543710I-1502J0D01*
G03X979149Y543552I123J-158D01*
G01Y543238D01*
G03X979226Y543080I200J0D01*
G02X979805Y541895I-923J-1185D01*
G02X978303Y540393I-1502J0D01*
G02X977316Y540763I0J1501D01*
G01X977315D01*
Y540764D01*
G03X977185Y540812I-130J-152D01*
G01X976921D01*
G03X976791Y540764I0J-200D01*
G01X976790Y540763D01*
G02X975803Y540393I-987J1131D01*
G02X974301Y541895I0J1502D01*
G02X974773Y542988I1502J0D01*
G01X974774Y542989D01*
G03X974835Y543154I-138J145D01*
G01X974804Y543469D01*
G03X974710Y543619I-199J-20D01*
G02X974001Y544895I794J1276D01*
G02X975503Y546397I1502J0D01*
G02X976609Y545912I0J-1504D01*
G03X976756Y545847I148J135D01*
G01X977050D01*
G03X977197Y545912I-1J200D01*
G02X978303Y546397I1106J-1019D01*
G37*
G36*
G01X243860Y546712D02*
G02X245362Y548214I1502J0D01*
G02X246796Y547159I0J-1502D01*
G01Y547157D01*
G03X246845Y547077I190J62D01*
G01X248460Y545462D01*
G02X248842Y544540I-924J-923D01*
G01Y471016D01*
G03X248901Y470874I200J0D01*
G01X250049Y469727D01*
G02X250432Y468803I-923J-924D01*
G01Y466664D01*
G03X250453Y466575I200J0D01*
G01X250454Y466573D01*
G02X250627Y465874I-1329J-700D01*
G02X247623I-1502J0D01*
G02X247795Y466571I1502J-1D01*
G03X247797Y466575I-178J91D01*
G01X247808Y466596D01*
X247818Y466640D01*
Y468179D01*
G03X247759Y468321I-200J0D01*
G01X246612Y469468D01*
G02X246230Y470390I924J923D01*
G01Y540868D01*
G03X246153Y541026I-200J0D01*
G01X245903Y541220D01*
G03X245731Y541256I-123J-158D01*
G02X245362Y541210I-369J1457D01*
G02X243860Y542712I0J1502D01*
G02X245131Y544196I1502J0D01*
G01X245187Y544205D01*
X245273Y544278D01*
X245401Y544670D01*
G03X245352Y544874I-190J62D01*
G01X244997Y545229D01*
G03X244917Y545278I-142J-141D01*
G01X244916D01*
G02X243860Y546712I446J1434D01*
G37*
G36*
G01X700946D02*
G02X702448Y548214I1502J0D01*
G02X703937Y546912I0J-1502D01*
G03X703994Y546797I198J27D01*
G01X707135Y543656D01*
G02X707518Y542732I-923J-924D01*
G01Y466664D01*
G03X707539Y466575I200J0D01*
G01X707540Y466573D01*
G02X707713Y465874I-1329J-700D01*
G02X704709I-1502J0D01*
G02X704881Y466571I1502J-1D01*
G03X704883Y466575I-178J91D01*
G01X704894Y466596D01*
X704904Y466640D01*
Y542108D01*
G03X704845Y542250I-200J0D01*
G01X704573Y542522D01*
G03X704379Y542573I-141J-142D01*
G01X703992Y542467D01*
X703916Y542391D01*
X703903Y542339D01*
G02X702448Y541210I-1455J373D01*
G02X700946Y542712I0J1502D01*
G02X702075Y544167I1502J0D01*
G01X702127Y544180D01*
X702203Y544256D01*
X702309Y544643D01*
G03X702258Y544837I-193J53D01*
G01X701681Y545414D01*
G03X701647Y545441I-141J-142D01*
G02X700946Y546712I802J1271D01*
G37*
G36*
G01X1158033D02*
G02X1159535Y548214I1502J0D01*
G02X1160969Y547159I0J-1502D01*
G01Y547157D01*
G03X1161018Y547077I190J62D01*
G01X1162633Y545462D01*
G02X1163016Y544538I-923J-924D01*
G01Y468087D01*
G03X1163075Y467945I200J0D01*
G01X1163663Y467357D01*
G03X1163743Y467308I142J141D01*
G01X1163744D01*
G02X1164800Y465874I-446J-1434D01*
G02X1163298Y464372I-1502J0D01*
G02X1161864Y465427I0J1502D01*
G01Y465429D01*
G03X1161815Y465509I-190J-62D01*
G01X1160785Y466539D01*
G02X1160402Y467463I923J924D01*
G01Y540868D01*
G03X1160325Y541026I-200J0D01*
G01X1160076Y541220D01*
G03X1159904Y541256I-123J-158D01*
G02X1159535Y541210I-369J1457D01*
G02X1158033Y542712I0J1502D01*
G02X1159304Y544196I1502J0D01*
G01X1159360Y544205D01*
X1159446Y544278D01*
X1159574Y544670D01*
G03X1159525Y544874I-190J62D01*
G01X1159170Y545229D01*
G03X1159090Y545278I-142J-141D01*
G01X1159089D01*
G02X1158033Y546712I446J1434D01*
G37*
G36*
G01X893949Y548865D02*
G02Y545861I0J-1502D01*
G02X892962Y546231I0J1501D01*
G01X892961D01*
Y546232D01*
G03X892831Y546280I-130J-152D01*
G01X892567D01*
G03X892437Y546232I0J-200D01*
G01X892436Y546231D01*
G02X891449Y545861I-987J1131D01*
G02Y548865I0J1502D01*
G02X892436Y548495I0J-1501D01*
G01X892437D01*
Y548494D01*
G03X892567Y548446I130J152D01*
G01X892831D01*
G03X892961Y548494I0J200D01*
G01X892962Y548495D01*
G02X893949Y548865I987J-1131D01*
G37*
G36*
G01X679784Y549800D02*
G02X682788I1502J0D01*
G02X682249Y548648I-1502J1D01*
G01X682248Y548647D01*
G03X682178Y548509I129J-152D01*
G01X682157Y548221D01*
G03X682206Y548075I200J-14D01*
G01X682207Y548074D01*
G02X682588Y547075I-1121J-1000D01*
G02X679584I-1502J0D01*
G02X680123Y548227I1502J-1D01*
G01X680124Y548228D01*
G03X680194Y548366I-129J152D01*
G01X680215Y548654D01*
G03X680166Y548800I-200J14D01*
G01X680165Y548801D01*
G02X679784Y549800I1121J1000D01*
G37*
G36*
G01X1136871D02*
G02X1139875I1502J0D01*
G02X1139336Y548648I-1502J1D01*
G01X1139335Y548647D01*
G03X1139265Y548509I129J-152D01*
G01X1139244Y548221D01*
G03X1139293Y548075I200J-14D01*
G01X1139294Y548074D01*
G02X1139675Y547075I-1121J-1000D01*
G02X1136671I-1502J0D01*
G02X1137210Y548227I1502J-1D01*
G01X1137211Y548228D01*
G03X1137281Y548366I-129J152D01*
G01X1137302Y548654D01*
G03X1137253Y548800I-200J14D01*
G01X1137252Y548801D01*
G02X1136871Y549800I1121J1000D01*
G37*
G36*
G01X1234941Y551639D02*
G02Y548635I0J-1502D01*
G02X1233838Y549117I0J1503D01*
G03X1233691Y549181I-147J-136D01*
G01X1233399D01*
G03X1233252Y549117I0J-200D01*
G02X1232149Y548635I-1103J1021D01*
G02Y551639I0J1502D01*
G02X1233252Y551157I0J-1503D01*
G03X1233399Y551093I147J136D01*
G01X1233691D01*
G03X1233838Y551157I0J200D01*
G02X1234941Y551639I1103J-1021D01*
G37*
G36*
G01X1167900Y554802D02*
G02Y551798I0J-1502D01*
G02X1166913Y552168I0J1501D01*
G01X1166912D01*
Y552169D01*
G03X1166782Y552217I-130J-152D01*
G01X1166518D01*
G03X1166388Y552169I0J-200D01*
G01X1166387Y552168D01*
G02X1165400Y551798I-987J1131D01*
G02Y554802I0J1502D01*
G02X1166387Y554432I0J-1501D01*
G01X1166388D01*
Y554431D01*
G03X1166518Y554383I130J152D01*
G01X1166782D01*
G03X1166912Y554431I0J200D01*
G01X1166913Y554432D01*
G02X1167900Y554802I987J-1131D01*
G37*
G36*
G01X632701Y554909D02*
G02X634203Y553407I0J-1502D01*
G02X633833Y552420I-1501J0D01*
G01Y552419D01*
X633832D01*
G03X633784Y552289I152J-130D01*
G01Y552025D01*
G03X633832Y551895I200J0D01*
G01X633833Y551894D01*
G02X634203Y550907I-1131J-987D01*
G02X632701Y549405I-1502J0D01*
G02X631714Y549775I0J1501D01*
G01X631713D01*
Y549776D01*
G03X631583Y549824I-130J-152D01*
G01X631319D01*
G03X631189Y549776I0J-200D01*
G01X631188Y549775D01*
G02X630201Y549405I-987J1131D01*
G02X628699Y550907I0J1502D01*
G02X629069Y551894I1501J0D01*
G01Y551895D01*
X629070D01*
G03X629118Y552025I-152J130D01*
G01Y552289D01*
G03X629070Y552419I-200J0D01*
G01X629069Y552420D01*
G02X628699Y553407I1131J987D01*
G02X630201Y554909I1502J0D01*
G02X631188Y554539I0J-1501D01*
G01X631189D01*
Y554538D01*
G03X631319Y554490I130J152D01*
G01X631583D01*
G03X631713Y554538I0J200D01*
G01X631714Y554539D01*
G02X632701Y554909I987J-1131D01*
G37*
G36*
G01X1089788D02*
G02X1091290Y553407I0J-1502D01*
G02X1090920Y552420I-1501J0D01*
G01Y552419D01*
X1090919D01*
G03X1090871Y552289I152J-130D01*
G01Y552025D01*
G03X1090919Y551895I200J0D01*
G01X1090920Y551894D01*
G02X1091290Y550907I-1131J-987D01*
G02X1089788Y549405I-1502J0D01*
G02X1088801Y549775I0J1501D01*
G01X1088800D01*
Y549776D01*
G03X1088670Y549824I-130J-152D01*
G01X1088406D01*
G03X1088276Y549776I0J-200D01*
G01X1088275Y549775D01*
G02X1087288Y549405I-987J1131D01*
G02X1085786Y550907I0J1502D01*
G02X1086156Y551894I1501J0D01*
G01Y551895D01*
X1086157D01*
G03X1086205Y552025I-152J130D01*
G01Y552289D01*
G03X1086157Y552419I-200J0D01*
G01X1086156Y552420D01*
G02X1085786Y553407I1131J987D01*
G02X1087288Y554909I1502J0D01*
G02X1088275Y554539I0J-1501D01*
G01X1088276D01*
Y554538D01*
G03X1088406Y554490I130J152D01*
G01X1088670D01*
G03X1088800Y554538I0J200D01*
G01X1088801Y554539D01*
G02X1089788Y554909I987J-1131D01*
G37*
G36*
G01X450902Y554990D02*
G02X452404Y556492I1502J0D01*
G02X453465Y556053I0J-1502D01*
G01X453492Y556026D01*
X453562Y555996D01*
X453914Y555985D01*
X453984Y556010D01*
X454013Y556036D01*
G02X455009Y556414I996J-1123D01*
G02X456511Y554912I0J-1502D01*
G02X456105Y553885I-1502J0D01*
G01X456079Y553858D01*
X456051Y553787D01*
Y553437D01*
X456079Y553366D01*
X456105Y553339D01*
G02Y551285I-1096J-1027D01*
G01X456079Y551258D01*
X456051Y551187D01*
Y550837D01*
X456079Y550766D01*
X456105Y550739D01*
G02X456511Y549712I-1096J-1027D01*
G02X456026Y548606I-1504J0D01*
G03X455961Y548459I135J-148D01*
G01Y548165D01*
G03X456026Y548018I200J1D01*
G02X456511Y546912I-1019J-1106D01*
G02X456105Y545885I-1502J0D01*
G01X456079Y545858D01*
X456051Y545787D01*
Y545437D01*
X456079Y545366D01*
X456105Y545339D01*
G02X456511Y544312I-1096J-1027D01*
G02X455009Y542810I-1502J0D01*
G02X453948Y543249I0J1502D01*
G01X453921Y543276D01*
X453851Y543306D01*
X453499Y543317D01*
X453429Y543292D01*
X453400Y543266D01*
G02X452404Y542888I-996J1123D01*
G02X450902Y544390I0J1502D01*
G02X451308Y545417I1502J0D01*
G01X451334Y545444D01*
X451362Y545515D01*
Y545865D01*
X451334Y545936D01*
X451308Y545963D01*
G02X450902Y546990I1096J1027D01*
G02X451387Y548096I1504J0D01*
G03X451452Y548243I-135J148D01*
G01Y548537D01*
G03X451387Y548684I-200J-1D01*
G02X450902Y549790I1019J1106D01*
G02X451308Y550817I1502J0D01*
G01X451334Y550844D01*
X451362Y550915D01*
Y551265D01*
X451334Y551336D01*
X451308Y551363D01*
G02Y553417I1096J1027D01*
G01X451334Y553444D01*
X451362Y553515D01*
Y553865D01*
X451334Y553936D01*
X451308Y553963D01*
G02X450902Y554990I1096J1027D01*
G37*
G36*
G01X441502Y555090D02*
G02X444506I1502J0D01*
G02X444100Y554063I-1502J0D01*
G01X444074Y554036D01*
X444046Y553965D01*
Y553615D01*
X444074Y553544D01*
X444100Y553517D01*
G02Y551463I-1096J-1027D01*
G01X444074Y551436D01*
X444046Y551365D01*
Y551015D01*
X444074Y550944D01*
X444100Y550917D01*
G02X444506Y549890I-1096J-1027D01*
G02X443892Y548678I-1503J0D01*
G03X443811Y548530I118J-161D01*
G01X443789Y548225D01*
G03X443849Y548068I200J-14D01*
G02X444306Y546990I-1045J-1079D01*
G02X443900Y545963I-1502J0D01*
G01X443874Y545936D01*
X443846Y545865D01*
Y545515D01*
X443874Y545444D01*
X443900Y545417D01*
G02X444306Y544390I-1096J-1027D01*
G02X441302I-1502J0D01*
G02X441708Y545417I1502J0D01*
G01X441734Y545444D01*
X441762Y545515D01*
Y545865D01*
X441734Y545936D01*
X441708Y545963D01*
G02X441302Y546990I1096J1027D01*
G02X441916Y548202I1503J0D01*
G03X441997Y548350I-118J161D01*
G01X442019Y548655D01*
G03X441959Y548812I-200J14D01*
G02X441502Y549890I1045J1079D01*
G02X441908Y550917I1502J0D01*
G01X441934Y550944D01*
X441962Y551015D01*
Y551365D01*
X441934Y551436D01*
X441908Y551463D01*
G02Y553517I1096J1027D01*
G01X441934Y553544D01*
X441962Y553615D01*
Y553965D01*
X441934Y554036D01*
X441908Y554063D01*
G02X441502Y555090I1096J1027D01*
G37*
G36*
G01X417838Y555190D02*
G02X420842I1502J0D01*
G02X420436Y554163I-1502J0D01*
G01X420410Y554136D01*
X420382Y554065D01*
Y553715D01*
X420410Y553644D01*
X420436Y553617D01*
G02Y551563I-1096J-1027D01*
G01X420410Y551536D01*
X420382Y551465D01*
Y551115D01*
X420410Y551044D01*
X420436Y551017D01*
G02X420842Y549990I-1096J-1027D01*
G02X420352Y548881I-1502J1D01*
G03X420350Y548879I140J-142D01*
G03X420287Y548748I136J-146D01*
G01X420265Y548474D01*
G03X420309Y548333I200J-15D01*
G02X420642Y547390I-1169J-943D01*
G02X420236Y546363I-1502J0D01*
G01X420210Y546336D01*
X420182Y546265D01*
Y545915D01*
X420210Y545844D01*
X420236Y545817D01*
G02X420642Y544790I-1096J-1027D01*
G02X417638I-1502J0D01*
G02X418044Y545817I1502J0D01*
G01X418070Y545844D01*
X418098Y545915D01*
Y546265D01*
X418070Y546336D01*
X418044Y546363D01*
G02X417638Y547390I1096J1027D01*
G02X418128Y548499I1502J-1D01*
G03X418130Y548501I-140J142D01*
G03X418193Y548632I-136J146D01*
G01X418215Y548906D01*
G03X418171Y549047I-200J15D01*
G02X417838Y549990I1169J943D01*
G02X418244Y551017I1502J0D01*
G01X418270Y551044D01*
X418298Y551115D01*
Y551465D01*
X418270Y551536D01*
X418244Y551563D01*
G02Y553617I1096J1027D01*
G01X418270Y553644D01*
X418298Y553715D01*
Y554065D01*
X418270Y554136D01*
X418244Y554163D01*
G02X417838Y555190I1096J1027D01*
G37*
G36*
G01X431384Y556692D02*
G02X432886Y555190I0J-1502D01*
G02X432480Y554163I-1502J0D01*
G01X432454Y554136D01*
X432426Y554065D01*
Y553715D01*
X432454Y553644D01*
X432480Y553617D01*
G02Y551563I-1096J-1027D01*
G01X432454Y551536D01*
X432426Y551465D01*
Y551115D01*
X432454Y551044D01*
X432480Y551017D01*
G02X432886Y549990I-1096J-1027D01*
G02X432307Y548805I-1502J0D01*
G03X432230Y548647I123J-158D01*
G01Y548333D01*
G03X432307Y548175I200J0D01*
G02X432886Y546990I-923J-1185D01*
G02X432480Y545963I-1502J0D01*
G01X432454Y545936D01*
X432426Y545865D01*
Y545515D01*
X432454Y545444D01*
X432480Y545417D01*
G02X432886Y544390I-1096J-1027D01*
G02X431384Y542888I-1502J0D01*
G02X430340Y543310I0J1502D01*
G01X430311Y543338D01*
X430241Y543366D01*
X429883D01*
X429813Y543338D01*
X429784Y543310D01*
G02X428740Y542888I-1044J1080D01*
G02X427238Y544390I0J1502D01*
G02X427644Y545417I1502J0D01*
G01X427670Y545444D01*
X427698Y545515D01*
Y545865D01*
X427670Y545936D01*
X427644Y545963D01*
G02X427238Y546990I1096J1027D01*
G02X427817Y548175I1502J0D01*
G03X427894Y548333I-123J158D01*
G01Y548647D01*
G03X427817Y548805I-200J0D01*
G02X427238Y549990I923J1185D01*
G02X427644Y551017I1502J0D01*
G01X427670Y551044D01*
X427698Y551115D01*
Y551465D01*
X427670Y551536D01*
X427644Y551563D01*
G02Y553617I1096J1027D01*
G01X427670Y553644D01*
X427698Y553715D01*
Y554065D01*
X427670Y554136D01*
X427644Y554163D01*
G02X427238Y555190I1096J1027D01*
G02X428740Y556692I1502J0D01*
G02X429784Y556270I0J-1502D01*
G01X429813Y556242D01*
X429883Y556214D01*
X430241D01*
X430311Y556242D01*
X430340Y556270D01*
G02X431384Y556692I1044J-1080D01*
G37*
G36*
G01X46643Y556696D02*
G02Y553692I0J-1502D01*
G02X45537Y554177I0J1504D01*
G03X45390Y554242I-148J-135D01*
G01X45096D01*
G03X44949Y554177I1J-200D01*
G02X43843Y553692I-1106J1019D01*
G02Y556696I0J1502D01*
G02X44949Y556211I0J-1504D01*
G03X45096Y556146I148J135D01*
G01X45390D01*
G03X45537Y556211I-1J200D01*
G02X46643Y556696I1106J-1019D01*
G37*
G36*
G01X503729D02*
G02Y553692I0J-1502D01*
G02X502623Y554177I0J1504D01*
G03X502476Y554242I-148J-135D01*
G01X502182D01*
G03X502035Y554177I1J-200D01*
G02X500929Y553692I-1106J1019D01*
G02Y556696I0J1502D01*
G02X502035Y556211I0J-1504D01*
G03X502182Y556146I148J135D01*
G01X502476D01*
G03X502623Y556211I-1J200D01*
G02X503729Y556696I1106J-1019D01*
G37*
G36*
G01X960816D02*
G02Y553692I0J-1502D01*
G02X959710Y554177I0J1504D01*
G03X959563Y554242I-148J-135D01*
G01X959269D01*
G03X959122Y554177I1J-200D01*
G02X958016Y553692I-1106J1019D01*
G02Y556696I0J1502D01*
G02X959122Y556211I0J-1504D01*
G03X959269Y556146I148J135D01*
G01X959563D01*
G03X959710Y556211I-1J200D01*
G02X960816Y556696I1106J-1019D01*
G37*
G36*
G01X1117345Y561420D02*
G02X1120349I1502J0D01*
G02X1119979Y560433I-1501J0D01*
G03X1119977Y560431I140J-142D01*
G03X1119929Y560301I152J-130D01*
G01Y560036D01*
G03X1119977Y559906I200J0D01*
G01X1119978Y559905D01*
G02X1120349Y558917I-1130J-988D01*
G02X1117345I-1502J0D01*
G02X1117715Y559904I1501J0D01*
G03X1117717Y559906I-140J142D01*
G03X1117765Y560036I-152J130D01*
G01Y560301D01*
G03X1117717Y560431I-200J0D01*
G01X1117716Y560432D01*
G02X1117345Y561420I1130J988D01*
G37*
G36*
G01X46643Y564696D02*
G02Y561692I0J-1502D01*
G02X45537Y562177I0J1504D01*
G03X45390Y562242I-148J-135D01*
G01X45096D01*
G03X44949Y562177I1J-200D01*
G02X43843Y561692I-1106J1019D01*
G02Y564696I0J1502D01*
G02X44949Y564211I0J-1504D01*
G03X45096Y564146I148J135D01*
G01X45390D01*
G03X45537Y564211I-1J200D01*
G02X46643Y564696I1106J-1019D01*
G37*
G36*
G01X503729D02*
G02Y561692I0J-1502D01*
G02X502623Y562177I0J1504D01*
G03X502476Y562242I-148J-135D01*
G01X502182D01*
G03X502035Y562177I1J-200D01*
G02X500929Y561692I-1106J1019D01*
G02Y564696I0J1502D01*
G02X502035Y564211I0J-1504D01*
G03X502182Y564146I148J135D01*
G01X502476D01*
G03X502623Y564211I-1J200D01*
G02X503729Y564696I1106J-1019D01*
G37*
G36*
G01X960816D02*
G02Y561692I0J-1502D01*
G02X959710Y562177I0J1504D01*
G03X959563Y562242I-148J-135D01*
G01X959269D01*
G03X959122Y562177I1J-200D01*
G02X958016Y561692I-1106J1019D01*
G02Y564696I0J1502D01*
G02X959122Y564211I0J-1504D01*
G03X959269Y564146I148J135D01*
G01X959563D01*
G03X959710Y564211I-1J200D01*
G02X960816Y564696I1106J-1019D01*
G37*
G36*
G01X46643Y572696D02*
G02Y569692I0J-1502D01*
G02X45537Y570177I0J1504D01*
G03X45390Y570242I-148J-135D01*
G01X45096D01*
G03X44949Y570177I1J-200D01*
G02X43843Y569692I-1106J1019D01*
G02Y572696I0J1502D01*
G02X44949Y572211I0J-1504D01*
G03X45096Y572146I148J135D01*
G01X45390D01*
G03X45537Y572211I-1J200D01*
G02X46643Y572696I1106J-1019D01*
G37*
G36*
G01X503729D02*
G02Y569692I0J-1502D01*
G02X502623Y570177I0J1504D01*
G03X502476Y570242I-148J-135D01*
G01X502182D01*
G03X502035Y570177I1J-200D01*
G02X500929Y569692I-1106J1019D01*
G02Y572696I0J1502D01*
G02X502035Y572211I0J-1504D01*
G03X502182Y572146I148J135D01*
G01X502476D01*
G03X502623Y572211I-1J200D01*
G02X503729Y572696I1106J-1019D01*
G37*
G36*
G01X960816D02*
G02Y569692I0J-1502D01*
G02X959710Y570177I0J1504D01*
G03X959563Y570242I-148J-135D01*
G01X959269D01*
G03X959122Y570177I1J-200D01*
G02X958016Y569692I-1106J1019D01*
G02Y572696I0J1502D01*
G02X959122Y572211I0J-1504D01*
G03X959269Y572146I148J135D01*
G01X959563D01*
G03X959710Y572211I-1J200D01*
G02X960816Y572696I1106J-1019D01*
G37*
G36*
G01X169837Y572070D02*
G02X172841I1502J0D01*
G02X172820Y571822I-1502J2D01*
G01Y571820D01*
X172814Y571784D01*
X172828Y571714D01*
X172989Y571457D01*
G03X173104Y571371I169J107D01*
G02X173163Y571352I-431J-1439D01*
G03X173167Y571350I91J176D01*
G01X173202Y571339D01*
X173275Y571343D01*
X173591Y571482D01*
X173644Y571535D01*
X173659Y571569D01*
G02X175033Y572464I1374J-607D01*
G02X176509Y571243I0J-1503D01*
G01X176516Y571205D01*
X176555Y571142D01*
X176803Y570958D01*
G03X176942Y570920I119J161D01*
G01X176943D01*
G02X177097Y570928I155J-1494D01*
G01X177099D01*
G02X178601Y569426I0J-1502D01*
G02X178332Y568568I-1503J0D01*
G03X178298Y568431I164J-114D01*
G01X178327Y568169D01*
G03X178392Y568043I199J23D01*
G02X178887Y566929I-1006J-1114D01*
G02X177385Y565427I-1502J0D01*
G02X175893Y566758I0J1502D01*
G01Y566760D01*
G03X175796Y566908I-198J-24D01*
G01X175521Y567072D01*
G03X175344Y567085I-102J-172D01*
G02X174776Y566973I-569J1390D01*
G02X173314Y568132I0J1502D01*
G01Y568133D01*
G03X173233Y568250I-194J-48D01*
G01X173012Y568404D01*
G03X172875Y568438I-114J-165D01*
G01X172874D01*
G02X172686Y568426I-189J1490D01*
G02X171184Y569928I0J1502D01*
G02X171205Y570176I1502J-2D01*
G01Y570178D01*
X171211Y570214D01*
X171197Y570284D01*
X171036Y570541D01*
G03X170921Y570627I-169J-107D01*
G02X169837Y572070I418J1443D01*
G37*
G36*
G01X626923D02*
G02X629927I1502J0D01*
G02X629906Y571822I-1502J2D01*
G01Y571820D01*
X629900Y571784D01*
X629914Y571714D01*
X630075Y571457D01*
G03X630190Y571371I169J107D01*
G02X630249Y571352I-431J-1439D01*
G03X630253Y571350I91J176D01*
G01X630288Y571339D01*
X630361Y571343D01*
X630677Y571482D01*
X630730Y571535D01*
X630745Y571569D01*
G02X632119Y572464I1374J-607D01*
G02X633595Y571243I0J-1503D01*
G01X633602Y571205D01*
X633641Y571142D01*
X633889Y570958D01*
G03X634028Y570920I119J161D01*
G01X634029D01*
G02X634183Y570928I155J-1494D01*
G01X634185D01*
G02X635687Y569426I0J-1502D01*
G02X635418Y568568I-1503J0D01*
G03X635384Y568431I164J-114D01*
G01X635413Y568169D01*
G03X635478Y568043I199J23D01*
G02X635973Y566929I-1006J-1114D01*
G02X634471Y565427I-1502J0D01*
G02X632979Y566758I0J1502D01*
G01Y566760D01*
G03X632882Y566908I-198J-24D01*
G01X632607Y567072D01*
G03X632430Y567085I-102J-172D01*
G02X631862Y566973I-569J1390D01*
G02X630400Y568132I0J1502D01*
G01Y568133D01*
G03X630319Y568250I-194J-48D01*
G01X630098Y568404D01*
G03X629961Y568438I-114J-165D01*
G01X629960D01*
G02X629772Y568426I-189J1490D01*
G02X628270Y569928I0J1502D01*
G02X628291Y570176I1502J-2D01*
G01Y570178D01*
X628297Y570214D01*
X628283Y570284D01*
X628122Y570541D01*
G03X628007Y570627I-169J-107D01*
G02X626923Y572070I418J1443D01*
G37*
G36*
G01X1084010D02*
G02X1087014I1502J0D01*
G02X1086993Y571822I-1502J2D01*
G01Y571820D01*
X1086987Y571784D01*
X1087001Y571714D01*
X1087162Y571457D01*
G03X1087277Y571371I169J107D01*
G02X1087336Y571352I-431J-1439D01*
G03X1087340Y571350I91J176D01*
G01X1087375Y571339D01*
X1087448Y571343D01*
X1087764Y571482D01*
X1087817Y571535D01*
X1087832Y571569D01*
G02X1089206Y572464I1374J-607D01*
G02X1090682Y571243I0J-1503D01*
G01X1090689Y571205D01*
X1090728Y571142D01*
X1090976Y570958D01*
G03X1091115Y570920I119J161D01*
G01X1091116D01*
G02X1091270Y570928I155J-1494D01*
G01X1091272D01*
G02X1092774Y569426I0J-1502D01*
G02X1092505Y568568I-1503J0D01*
G03X1092471Y568431I164J-114D01*
G01X1092500Y568169D01*
G03X1092565Y568043I199J23D01*
G02X1093060Y566929I-1006J-1114D01*
G02X1091558Y565427I-1502J0D01*
G02X1090066Y566758I0J1502D01*
G01Y566760D01*
G03X1089969Y566908I-198J-24D01*
G01X1089694Y567072D01*
G03X1089517Y567085I-102J-172D01*
G02X1088949Y566973I-569J1390D01*
G02X1087487Y568132I0J1502D01*
G01Y568133D01*
G03X1087406Y568250I-194J-48D01*
G01X1087185Y568404D01*
G03X1087048Y568438I-114J-165D01*
G01X1087047D01*
G02X1086859Y568426I-189J1490D01*
G02X1085357Y569928I0J1502D01*
G02X1085378Y570176I1502J-2D01*
G01Y570178D01*
X1085384Y570214D01*
X1085370Y570284D01*
X1085209Y570541D01*
G03X1085094Y570627I-169J-107D01*
G02X1084010Y572070I418J1443D01*
G37*
G36*
G01X73838Y576484D02*
G02X76842I1502J0D01*
G02X76200Y575253I-1501J0D01*
G03X76116Y575114I114J-164D01*
G01X76073Y574778D01*
X76097Y574697D01*
X76125Y574665D01*
G02X76485Y573689I-1143J-976D01*
G02X75764Y572406I-1502J0D01*
G01X75720Y572379D01*
X75669Y572291D01*
X75661Y571849D01*
X75708Y571759D01*
X75751Y571731D01*
G02X76425Y570478I-828J-1253D01*
G02X74923Y568976I-1502J0D01*
G02X73744Y569547I0J1503D01*
G01X73718Y569580D01*
X73644Y569619D01*
X73265Y569648D01*
X73187Y569620D01*
X73156Y569591D01*
G02X72128Y569184I-1028J1095D01*
G02X70626Y570686I0J1502D01*
G02X71127Y571806I1502J0D01*
G01X71156Y571831D01*
X71190Y571901D01*
X71215Y572215D01*
G03X71171Y572356I-199J15D01*
G02X70835Y573303I1167J947D01*
G02X72337Y574805I1502J0D01*
G02X73228Y574512I0J-1501D01*
G01X73229D01*
X73260Y574489D01*
X73336Y574470D01*
X73692Y574522D01*
X73761Y574563D01*
X73784Y574594D01*
G02X74123Y574920I1198J-906D01*
G03X74207Y575059I-114J164D01*
G01X74250Y575395D01*
X74226Y575476D01*
X74198Y575508D01*
G02X73838Y576484I1143J976D01*
G37*
G36*
G01X530924D02*
G02X533928I1502J0D01*
G02X533286Y575253I-1501J0D01*
G03X533202Y575114I114J-164D01*
G01X533159Y574778D01*
X533183Y574697D01*
X533211Y574665D01*
G02X533571Y573689I-1143J-976D01*
G02X532850Y572406I-1502J0D01*
G01X532806Y572379D01*
X532755Y572291D01*
X532747Y571849D01*
X532794Y571759D01*
X532837Y571731D01*
G02X533511Y570478I-828J-1253D01*
G02X532009Y568976I-1502J0D01*
G02X530830Y569547I0J1503D01*
G01X530804Y569580D01*
X530730Y569619D01*
X530351Y569648D01*
X530273Y569620D01*
X530242Y569591D01*
G02X529214Y569184I-1028J1095D01*
G02X527712Y570686I0J1502D01*
G02X528213Y571806I1502J0D01*
G01X528242Y571831D01*
X528276Y571901D01*
X528301Y572215D01*
G03X528257Y572356I-199J15D01*
G02X527921Y573303I1167J947D01*
G02X529423Y574805I1502J0D01*
G02X530314Y574512I0J-1501D01*
G01X530315D01*
X530346Y574489D01*
X530422Y574470D01*
X530778Y574522D01*
X530847Y574563D01*
X530870Y574594D01*
G02X531209Y574920I1198J-906D01*
G03X531293Y575059I-114J164D01*
G01X531336Y575395D01*
X531312Y575476D01*
X531284Y575508D01*
G02X530924Y576484I1143J976D01*
G37*
G36*
G01X988011D02*
G02X991015I1502J0D01*
G02X990373Y575253I-1501J0D01*
G03X990289Y575114I114J-164D01*
G01X990246Y574778D01*
X990270Y574697D01*
X990298Y574665D01*
G02X990658Y573689I-1143J-976D01*
G02X989937Y572406I-1502J0D01*
G01X989893Y572379D01*
X989842Y572291D01*
X989834Y571849D01*
X989881Y571759D01*
X989924Y571731D01*
G02X990598Y570478I-828J-1253D01*
G02X989096Y568976I-1502J0D01*
G02X987917Y569547I0J1503D01*
G01X987891Y569580D01*
X987817Y569619D01*
X987438Y569648D01*
X987360Y569620D01*
X987329Y569591D01*
G02X986301Y569184I-1028J1095D01*
G02X984799Y570686I0J1502D01*
G02X985300Y571806I1502J0D01*
G01X985329Y571831D01*
X985363Y571901D01*
X985388Y572215D01*
G03X985344Y572356I-199J15D01*
G02X985008Y573303I1167J947D01*
G02X986510Y574805I1502J0D01*
G02X987401Y574512I0J-1501D01*
G01X987402D01*
X987433Y574489D01*
X987509Y574470D01*
X987865Y574522D01*
X987934Y574563D01*
X987957Y574594D01*
G02X988296Y574920I1198J-906D01*
G03X988380Y575059I-114J164D01*
G01X988423Y575395D01*
X988399Y575476D01*
X988371Y575508D01*
G02X988011Y576484I1143J976D01*
G37*
G36*
G01X919038Y577876D02*
G02Y580880I0J1502D01*
G02X920272Y580235I0J-1503D01*
G01X920292Y580205D01*
X920354Y580163D01*
X920650Y580093D01*
G03X920791Y580111I47J194D01*
G02X921507Y580293I717J-1320D01*
G02Y577289I0J-1502D01*
G02X920273Y577934I0J1503D01*
G01X920253Y577964D01*
X920191Y578006D01*
X919895Y578076D01*
G03X919754Y578058I-47J-194D01*
G02X919038Y577876I-717J1320D01*
G37*
G36*
G01X51000Y582724D02*
G02Y579720I0J-1502D01*
G02X49894Y580205I0J1504D01*
G03X49747Y580270I-148J-135D01*
G01X49453D01*
G03X49306Y580205I1J-200D01*
G02X47094I-1106J1017D01*
G03X46947Y580270I-148J-135D01*
G01X46653D01*
G03X46506Y580205I1J-200D01*
G02X45400Y579720I-1106J1019D01*
G02Y582724I0J1502D01*
G02X46506Y582239I0J-1504D01*
G03X46653Y582174I148J135D01*
G01X46947D01*
G03X47094Y582239I-1J200D01*
G02X49306I1106J-1017D01*
G03X49453Y582174I148J135D01*
G01X49747D01*
G03X49894Y582239I-1J200D01*
G02X51000Y582724I1106J-1019D01*
G37*
G36*
G01X508086D02*
G02Y579720I0J-1502D01*
G02X506980Y580205I0J1504D01*
G03X506833Y580270I-148J-135D01*
G01X506539D01*
G03X506392Y580205I1J-200D01*
G02X504180I-1106J1017D01*
G03X504033Y580270I-148J-135D01*
G01X503739D01*
G03X503592Y580205I1J-200D01*
G02X502486Y579720I-1106J1019D01*
G02Y582724I0J1502D01*
G02X503592Y582239I0J-1504D01*
G03X503739Y582174I148J135D01*
G01X504033D01*
G03X504180Y582239I-1J200D01*
G02X506392I1106J-1017D01*
G03X506539Y582174I148J135D01*
G01X506833D01*
G03X506980Y582239I-1J200D01*
G02X508086Y582724I1106J-1019D01*
G37*
G36*
G01X965173D02*
G02Y579720I0J-1502D01*
G02X964067Y580205I0J1504D01*
G03X963920Y580270I-148J-135D01*
G01X963626D01*
G03X963479Y580205I1J-200D01*
G02X961267I-1106J1017D01*
G03X961120Y580270I-148J-135D01*
G01X960826D01*
G03X960679Y580205I1J-200D01*
G02X959573Y579720I-1106J1019D01*
G02Y582724I0J1502D01*
G02X960679Y582239I0J-1504D01*
G03X960826Y582174I148J135D01*
G01X961120D01*
G03X961267Y582239I-1J200D01*
G02X963479I1106J-1017D01*
G03X963626Y582174I148J135D01*
G01X963920D01*
G03X964067Y582239I-1J200D01*
G02X965173Y582724I1106J-1019D01*
G37*
G36*
G01X921217Y590718D02*
G02Y587714I0J-1502D01*
G01X921216D01*
G02X921012Y587728I1J1502D01*
G01X921011D01*
G03X920866Y587691I-27J-198D01*
G01X920609Y587502D01*
X920568Y587436D01*
X920562Y587397D01*
G02X919080Y586138I-1482J243D01*
G02Y589142I0J1502D01*
G01X919081D01*
G02X919285Y589128I-1J-1502D01*
G01X919286D01*
G03X919431Y589165I27J198D01*
G01X919688Y589354D01*
X919729Y589420D01*
X919735Y589459D01*
G02X921217Y590718I1482J-243D01*
G37*
G36*
G01X1121203Y591015D02*
G02X1124207I1502J0D01*
G02X1123837Y590028I-1501J0D01*
G01Y590027D01*
X1123836D01*
G03X1123788Y589897I152J-130D01*
G01Y589633D01*
G03X1123836Y589503I200J0D01*
G01X1123837Y589502D01*
G02X1124207Y588515I-1131J-987D01*
G02X1121203I-1502J0D01*
G02X1121573Y589502I1501J0D01*
G01Y589503D01*
X1121574D01*
G03X1121622Y589633I-152J130D01*
G01Y589897D01*
G03X1121574Y590027I-200J0D01*
G01X1121573Y590028D01*
G02X1121203Y591015I1131J987D01*
G37*
G36*
G01X51000Y592717D02*
G02Y589713I0J-1502D01*
G02X49894Y590198I0J1504D01*
G03X49747Y590263I-148J-135D01*
G01X49453D01*
G03X49306Y590198I1J-200D01*
G02X47094I-1106J1017D01*
G03X46947Y590263I-148J-135D01*
G01X46653D01*
G03X46506Y590198I1J-200D01*
G02X45400Y589713I-1106J1019D01*
G02Y592717I0J1502D01*
G02X46506Y592232I0J-1504D01*
G03X46653Y592167I148J135D01*
G01X46947D01*
G03X47094Y592232I-1J200D01*
G02X49306I1106J-1017D01*
G03X49453Y592167I148J135D01*
G01X49747D01*
G03X49894Y592232I-1J200D01*
G02X51000Y592717I1106J-1019D01*
G37*
G36*
G01X508086D02*
G02Y589713I0J-1502D01*
G02X506980Y590198I0J1504D01*
G03X506833Y590263I-148J-135D01*
G01X506539D01*
G03X506392Y590198I1J-200D01*
G02X504180I-1106J1017D01*
G03X504033Y590263I-148J-135D01*
G01X503739D01*
G03X503592Y590198I1J-200D01*
G02X502486Y589713I-1106J1019D01*
G02Y592717I0J1502D01*
G02X503592Y592232I0J-1504D01*
G03X503739Y592167I148J135D01*
G01X504033D01*
G03X504180Y592232I-1J200D01*
G02X506392I1106J-1017D01*
G03X506539Y592167I148J135D01*
G01X506833D01*
G03X506980Y592232I-1J200D01*
G02X508086Y592717I1106J-1019D01*
G37*
G36*
G01X965173D02*
G02Y589713I0J-1502D01*
G02X964067Y590198I0J1504D01*
G03X963920Y590263I-148J-135D01*
G01X963626D01*
G03X963479Y590198I1J-200D01*
G02X961267I-1106J1017D01*
G03X961120Y590263I-148J-135D01*
G01X960826D01*
G03X960679Y590198I1J-200D01*
G02X959573Y589713I-1106J1019D01*
G02Y592717I0J1502D01*
G02X960679Y592232I0J-1504D01*
G03X960826Y592167I148J135D01*
G01X961120D01*
G03X961267Y592232I-1J200D01*
G02X963479I1106J-1017D01*
G03X963626Y592167I148J135D01*
G01X963920D01*
G03X964067Y592232I-1J200D01*
G02X965173Y592717I1106J-1019D01*
G37*
G36*
G01X53972Y612064D02*
G02X55474Y610562I0J-1502D01*
G02X54989Y609456I-1504J0D01*
G03X54924Y609309I135J-148D01*
G01Y609015D01*
G03X54989Y608868I200J1D01*
G02X55474Y607762I-1019J-1106D01*
G02X53972Y606260I-1502J0D01*
G02X52866Y606745I0J1504D01*
G03X52719Y606810I-148J-135D01*
G01X52425D01*
G03X52278Y606745I1J-200D01*
G02X50066I-1106J1017D01*
G03X49919Y606810I-148J-135D01*
G01X49625D01*
G03X49478Y606745I1J-200D01*
G02X47266I-1106J1017D01*
G03X47119Y606810I-148J-135D01*
G01X46825D01*
G03X46678Y606745I1J-200D01*
G02X45572Y606260I-1106J1019D01*
G02X44070Y607762I0J1502D01*
G02X44555Y608868I1504J0D01*
G03X44620Y609015I-135J148D01*
G01Y609309D01*
G03X44555Y609456I-200J-1D01*
G02X44070Y610562I1019J1106D01*
G02X45572Y612064I1502J0D01*
G02X46678Y611579I0J-1504D01*
G03X46825Y611514I148J135D01*
G01X47119D01*
G03X47266Y611579I-1J200D01*
G02X49478I1106J-1017D01*
G03X49625Y611514I148J135D01*
G01X49919D01*
G03X50066Y611579I-1J200D01*
G02X52278I1106J-1017D01*
G03X52425Y611514I148J135D01*
G01X52719D01*
G03X52866Y611579I-1J200D01*
G02X53972Y612064I1106J-1019D01*
G37*
G36*
G01X511058D02*
G02X512560Y610562I0J-1502D01*
G02X512075Y609456I-1504J0D01*
G03X512010Y609309I135J-148D01*
G01Y609015D01*
G03X512075Y608868I200J1D01*
G02X512560Y607762I-1019J-1106D01*
G02X511058Y606260I-1502J0D01*
G02X509952Y606745I0J1504D01*
G03X509805Y606810I-148J-135D01*
G01X509511D01*
G03X509364Y606745I1J-200D01*
G02X507152I-1106J1017D01*
G03X507005Y606810I-148J-135D01*
G01X506711D01*
G03X506564Y606745I1J-200D01*
G02X504352I-1106J1017D01*
G03X504205Y606810I-148J-135D01*
G01X503911D01*
G03X503764Y606745I1J-200D01*
G02X502658Y606260I-1106J1019D01*
G02X501156Y607762I0J1502D01*
G02X501641Y608868I1504J0D01*
G03X501706Y609015I-135J148D01*
G01Y609309D01*
G03X501641Y609456I-200J-1D01*
G02X501156Y610562I1019J1106D01*
G02X502658Y612064I1502J0D01*
G02X503764Y611579I0J-1504D01*
G03X503911Y611514I148J135D01*
G01X504205D01*
G03X504352Y611579I-1J200D01*
G02X506564I1106J-1017D01*
G03X506711Y611514I148J135D01*
G01X507005D01*
G03X507152Y611579I-1J200D01*
G02X509364I1106J-1017D01*
G03X509511Y611514I148J135D01*
G01X509805D01*
G03X509952Y611579I-1J200D01*
G02X511058Y612064I1106J-1019D01*
G37*
G36*
G01X954999Y615706D02*
X970622D01*
G02X971544Y615324I-1J-1306D01*
G01X974833Y612035D01*
G03X974975Y611976I142J141D01*
G01X977371D01*
G02X978295Y611593I0J-1306D01*
G01X981418Y608470D01*
G02X981799Y607616I-924J-924D01*
G03X981857Y607485I200J10D01*
G01X982222Y607120D01*
G03X982302Y607071I142J141D01*
G01X982303D01*
G02X983359Y605637I-446J-1434D01*
G02X981857Y604135I-1502J0D01*
G02X980685Y604697I0J1503D01*
G01X980651Y604739D01*
X980553Y604778D01*
X980104Y604710D01*
X980022Y604644D01*
X980002Y604594D01*
G02X977857Y603136I-2145J849D01*
G02X976226Y603812I1J2307D01*
G01X976109Y603929D01*
G03X975978Y603987I-141J-142D01*
G01X975977D01*
G02X975780Y604004I100J2304D01*
G03X975603Y603936I-25J-199D01*
G02X973857Y603136I-1747J1507D01*
G01X956080D01*
G03X955938Y603077I0J-200D01*
G01X945124Y592264D01*
G03X945096Y592016I141J-142D01*
G02X945327Y591216I-1271J-800D01*
G01Y591215D01*
G02X943825Y589713I-1502J0D01*
G01X943824D01*
G02X942895Y590035I0J1502D01*
G01X942885Y590025D01*
G03X942826Y589883I141J-142D01*
G01Y578857D01*
G03X942885Y578715I200J0D01*
G01X945039Y576562D01*
G02X945714Y574932I-1631J-1630D01*
G01Y559193D01*
G02X945039Y557563I-2306J0D01*
G01X941275Y553799D01*
G03X941249Y553548I141J-141D01*
G02X941494Y552726I-1256J-822D01*
G02X939992Y551224I-1502J0D01*
G02X939170Y551469I0J1501D01*
G03X938919Y551443I-110J-167D01*
G01X936275Y548799D01*
G03X936216Y548657I141J-142D01*
G01Y528738D01*
G03X936276Y528595I200J0D01*
G01X936508Y528367D01*
X936583Y528337D01*
X936623Y528338D01*
X936653D01*
G02Y525334I0J-1502D01*
G01X936623D01*
X936583Y525335D01*
X936508Y525305D01*
X936276Y525077D01*
G03X936216Y524934I140J-143D01*
G01Y513020D01*
G03X936275Y512878I200J0D01*
G01X945039Y504114D01*
G02X945714Y502484I-1631J-1630D01*
G01Y480962D01*
G03X945773Y480820I200J0D01*
G01X953639Y472954D01*
G03X953866Y472914I142J141D01*
G01X954207Y473075D01*
G03X954321Y473275I-85J181D01*
G02X954314Y473419I1495J145D01*
G02X957318I1502J0D01*
G02X957127Y472686I-1502J0D01*
G01X957106Y472648D01*
X957099Y472563D01*
X957216Y472237D01*
G03X957332Y472118I188J68D01*
G02X958131Y471598I-831J-2151D01*
G01X962464Y467265D01*
G02X963071Y466192I-1631J-1631D01*
G01Y466189D01*
G03X963157Y466071I194J51D01*
G01X963421Y465901D01*
X963496Y465887D01*
X963534Y465894D01*
G02X963816Y465921I284J-1475D01*
G02Y462917I0J-1502D01*
G02X963598Y462933I1J1502D01*
G01X963597D01*
G03X963438Y462886I-28J-198D01*
G01X963209Y462689D01*
G03X963140Y462537I131J-151D01*
G01Y460069D01*
G03X963273Y459881I200J0D01*
G02Y457051I-503J-1415D01*
G03X963140Y456863I67J-188D01*
G01Y452958D01*
X963213Y452855D01*
X963272Y452834D01*
G02Y450004I-503J-1415D01*
G01X963213Y449983D01*
X963140Y449880D01*
Y444538D01*
G03X963278Y444348I200J0D01*
G02Y441490I-462J-1429D01*
G01X963216Y441470D01*
X963140Y441365D01*
Y422365D01*
G02X962464Y420734I-2307J1D01*
G01X948513Y406783D01*
G02X946883Y406108I-1630J1631D01*
G01X935584D01*
G03X935442Y406049I0J-200D01*
G01X918563Y389169D01*
G02X916933Y388494I-1630J1631D01*
G01X916623D01*
G03X916445Y388386I0J-200D01*
G01X916256Y388019D01*
X916264Y387908D01*
X916296Y387862D01*
G02X916574Y386992I-1224J-870D01*
G02X913570I-1502J0D01*
G02X913848Y387862I1502J0D01*
G01X913880Y387908D01*
X913888Y388019D01*
X913699Y388386D01*
G03X913521Y388494I-178J-92D01*
G01X912373D01*
G03X912231Y388435I0J-200D01*
G01X912133Y388337D01*
G03Y388055I142J-141D01*
G01X912134Y388054D01*
G02X912574Y386992I-1062J-1062D01*
G02X911072Y385490I-1502J0D01*
G02X910064Y385878I-1J1502D01*
G03X909930Y385930I-134J-148D01*
G01X909810D01*
G03X909668Y385871I0J-200D01*
G01X906679Y382882D01*
G03X906620Y382740I141J-142D01*
G01Y382015D01*
G03X906743Y381830I200J0D01*
G01X906799Y381807D01*
X906917Y381830D01*
X909265Y384178D01*
G02X910896Y384854I1632J-1631D01*
G01X990947D01*
G02X992578Y384178I-1J-2307D01*
G01X1012690Y364065D01*
G03X1012832Y364006I142J141D01*
G01X1044732D01*
G02X1046362Y363331I0J-2306D01*
G01X1053127Y356565D01*
G03X1053269Y356506I142J141D01*
G01X1059135D01*
X1059238Y356580D01*
X1059259Y356641D01*
G02X1062099I1420J-490D01*
G01X1062120Y356580D01*
X1062223Y356506D01*
X1069383D01*
G03X1069525Y356565I0J200D01*
G01X1089400Y376441D01*
G02X1091031Y377116I1630J-1631D01*
G02X1093338Y374810I1J-2306D01*
G02X1093240Y374149I-2306J4D01*
G01Y374147D01*
G03X1093276Y373964I192J-57D01*
G01X1093484Y373707D01*
G03X1093655Y373634I155J126D01*
G01X1093656D01*
G02X1093841Y373642I192J-2299D01*
G02X1096148Y371335I0J-2307D01*
G02X1095472Y369704I-2307J1D01*
G01X1094414Y368646D01*
G02X1092783Y367970I-1632J1631D01*
G01X1091377D01*
G03X1091235Y367911I0J-200D01*
G01X1085100Y361776D01*
G03X1085050Y361693I141J-142D01*
G01Y361692D01*
G02X1084765Y361077I-2212J652D01*
G01X1084764Y361076D01*
G03X1084790Y360825I168J-109D01*
G01X1085488Y360128D01*
G02X1085713Y359866I-1632J-1629D01*
G03X1085900Y359787I161J119D01*
G02X1086197Y359806I295J-2287D01*
G01X1101017D01*
G02X1102647Y359131I0J-2306D01*
G01X1106643Y355135D01*
G02X1107318Y353505I-1631J-1630D01*
G01Y353504D01*
G02X1105012Y351198I-2306J0D01*
G01X1105011D01*
G02X1103381Y351873I0J2306D01*
G01X1103054Y352200D01*
G03X1102805Y352228I-142J-141D01*
G02X1101999Y351993I-807J1267D01*
G02X1101115Y352281I0J1501D01*
G03X1100825Y352222I-118J-162D01*
G02X1098845Y351098I-1980J1182D01*
G01X1098844D01*
G02X1097214Y351773I0J2306D01*
G01X1095755Y353233D01*
G03X1095613Y353292I-142J-141D01*
G01X1094239D01*
G03X1094042Y353125I0J-200D01*
G02X1091080I-1481J249D01*
G03X1090883Y353292I-197J-33D01*
G01X1087936D01*
G03X1087794Y353233I0J-200D01*
G01X1084711Y350149D01*
G03X1084667Y349931I141J-142D01*
G01X1084690Y349875D01*
X1084790Y349808D01*
X1085469D01*
G03X1085599Y349856I0J200D01*
G02X1086449Y350170I850J-993D01*
G01X1192167D01*
G03X1192309Y350229I0J200D01*
G01X1215392Y373312D01*
G02X1216314Y373694I923J-924D01*
G01X1222760D01*
G02X1223682Y373312I-1J-1306D01*
G01X1226120Y370874D01*
G03X1226200Y370825I142J141D01*
G01X1226201D01*
G02X1226753Y370514I-445J-1435D01*
G03X1227027Y370522I133J150D01*
G01X1227491Y370986D01*
G02X1229122Y371662I1632J-1631D01*
G02X1231428Y369355I-1J-2307D01*
G01Y369354D01*
G02X1230753Y367724I-2306J0D01*
G01X1228600Y365571D01*
G02X1226970Y364896I-1630J1631D01*
G01X1221791D01*
G03X1221649Y364837I0J-200D01*
G01X1198450Y341637D01*
G02X1196820Y340962I-1630J1631D01*
G01X1146860D01*
G03X1146673Y340834I0J-200D01*
G01X1146539Y340484D01*
G03X1146592Y340264I187J-71D01*
G02X1147089Y339148I-1004J-1116D01*
G02X1144085I-1502J0D01*
G02X1144582Y340264I1501J0D01*
G03X1144635Y340484I-134J149D01*
G01X1144501Y340834D01*
G03X1144314Y340962I-187J-72D01*
G01X1105334D01*
G03X1105192Y340903I0J-200D01*
G01X1104963Y340672D01*
X1104934Y340598D01*
Y340544D01*
G02X1101930I-1502J0D01*
G01Y340598D01*
X1101901Y340672D01*
X1101672Y340903D01*
G03X1101530Y340962I-142J-141D01*
G01X1099877D01*
G03X1099732Y340900I0J-200D01*
G01X1099503Y340661D01*
X1099475Y340585D01*
X1099477Y340544D01*
G02X1099478Y340478I-1501J-56D01*
G01Y340476D01*
G02X1097976Y338975I-1502J1D01*
G02X1096511Y340146I0J1502D01*
G01X1096499Y340200D01*
X1096424Y340279D01*
X1096035Y340391D01*
G03X1095838Y340340I-55J-192D01*
G01X1094185Y338687D01*
G02X1092554Y338012I-1630J1631D01*
G02X1090672Y338984I-1J2306D01*
G01X1090647Y339020D01*
X1090570Y339064D01*
X1090221Y339093D01*
G03X1090063Y339035I-17J-199D01*
G01X1089919Y338891D01*
G02X1088995Y338508I-924J923D01*
G01X1086405D01*
G03X1086316Y338487I0J-200D01*
G01X1086314Y338486D01*
G02X1085615Y338313I-700J1329D01*
G02X1084113Y339815I0J1502D01*
G02X1084186Y340275I1502J-3D01*
G01Y340277D01*
G03X1084137Y340479I-190J61D01*
G03X1083854I-142J-141D01*
G01X1083780Y340405D01*
G03X1083731Y340325I141J-142D01*
G01Y340324D01*
G02X1082297Y339268I-1434J446D01*
G02X1080795Y340770I0J1502D01*
G02X1081850Y342204I1502J0D01*
G01X1081852D01*
G03X1081932Y342253I-62J190D01*
G01X1082529Y342850D01*
G02X1083451Y343232I923J-924D01*
G01X1088030D01*
G03X1088172Y343291I0J200D01*
G01X1092095Y347215D01*
G03X1092139Y347433I-141J142D01*
G01X1092116Y347489D01*
X1092016Y347556D01*
X1087067D01*
G03X1086937Y347508I0J-200D01*
G02X1086087Y347194I-850J993D01*
G01X1083577D01*
G03X1083488Y347173I0J-200D01*
G01X1083486Y347172D01*
G02X1082787Y346999I-700J1329D01*
G02X1082001Y347221I0J1502D01*
G03X1081754Y347192I-105J-170D01*
G01X1081492Y346930D01*
G02X1079861Y346254I-1632J1631D01*
G01X1049640D01*
G02X1048009Y346930I1J2307D01*
G01X1041205Y353735D01*
G03X1041063Y353794I-142J-141D01*
G01X1002084D01*
G03X1001888Y353636I0J-200D01*
G02X998952I-1468J318D01*
G03X998756Y353794I-196J-42D01*
G01X997447D01*
G03X997265Y353676I0J-200D01*
G01X997115Y353343D01*
G03X997148Y353128I182J-82D01*
G02X997526Y352132I-1123J-996D01*
G02X994522I-1502J0D01*
G02X995254Y353422I1503J0D01*
G01X995300Y353449D01*
X995352Y353541D01*
Y353594D01*
G03X995152Y353794I-200J0D01*
G01X994713D01*
G03X994515Y353620I0J-200D01*
G01Y353619D01*
G02X991537I-1489J194D01*
G01Y353620D01*
G03X991339Y353794I-198J-26D01*
G01X983401D01*
G03X983259Y353735I0J-200D01*
G01X982871Y353346D01*
X982861Y353196D01*
X982907Y353136D01*
G02X983221Y352217I-1188J-919D01*
G02X981719Y350715I-1502J0D01*
G02X981617Y350718I-7J1502D01*
G01X981576Y350721D01*
X981498Y350693D01*
X981254Y350465D01*
G03X981190Y350319I136J-147D01*
G01Y346364D01*
G02X980515Y344734I-2306J0D01*
G01X977262Y341481D01*
G02X975631Y340806I-1630J1631D01*
G02X973324Y343112I-1J2306D01*
G02X973928Y344667I2307J-1D01*
G03X973980Y344801I-148J135D01*
G01Y344923D01*
G03X973928Y345057I-200J-1D01*
G02X973324Y346612I1703J1556D01*
G01Y352068D01*
G02X974000Y353699I2307J-1D01*
G01X979907Y359606D01*
G02X981538Y360282I1632J-1631D01*
G01X1006393D01*
G03X1006578Y360405I0J200D01*
G01X1006601Y360461D01*
X1006578Y360579D01*
X989037Y378121D01*
G03X988895Y378180I-142J-141D01*
G01X931590D01*
G03X931416Y378080I-1J-200D01*
G01X931243Y377778D01*
G03X931244Y377578I174J-99D01*
G02X931449Y376821I-1297J-757D01*
G02X928445I-1502J0D01*
G02X928650Y377578I1502J0D01*
G01X928677Y377625D01*
X928678Y377731D01*
X928478Y378080D01*
G03X928304Y378180I-173J-100D01*
G01X923023D01*
G03X922852Y378083I0J-200D01*
G01X922675Y377789D01*
G03X922670Y377592I172J-103D01*
G02X922845Y376889I-1327J-704D01*
G01Y376888D01*
G02X919841I-1502J0D01*
G01Y376889D01*
G02X920016Y377592I1502J-1D01*
G03X920011Y377789I-177J94D01*
G01X919834Y378083D01*
G03X919663Y378180I-171J-103D01*
G01X918232D01*
G03X918089Y378120I0J-200D01*
G01X917861Y377888D01*
X917831Y377813D01*
X917832Y377773D01*
Y377748D01*
G02X914828I-1502J0D01*
G01Y377773D01*
X914829Y377813D01*
X914799Y377888D01*
X914571Y378120D01*
G03X914428Y378180I-143J-140D01*
G01X912463D01*
G03X912321Y378121I0J-200D01*
G01X911806Y377605D01*
G03X911748Y377472I142J-141D01*
G01X911738Y377200D01*
G03X911785Y377063I200J-8D01*
G01X911786Y377062D01*
G02X912148Y376084I-1140J-978D01*
G02X910646Y374582I-1502J0D01*
G02X909668Y374944I0J1502D01*
G01X909667Y374945D01*
G03X909530Y374992I-129J-153D01*
G01X909258Y374982D01*
G03X909124Y374923I8J-200D01*
G01X907691Y373490D01*
G03X907658Y373252I142J-141D01*
G02X907846Y372525I-1314J-728D01*
G01Y372524D01*
G02X906344Y371022I-1502J0D01*
G01X906343D01*
G02X905616Y371210I1J1502D01*
G03X905378Y371177I-97J-175D01*
G01X901235Y367034D01*
G03X901176Y366892I141J-142D01*
G01Y351114D01*
G02X896562I-2307J0D01*
G01Y352683D01*
G03X896389Y352881I-200J0D01*
G02Y355857I203J1488D01*
G03X896562Y356055I-27J198D01*
G01Y356683D01*
G03X896389Y356881I-200J0D01*
G02Y359857I203J1488D01*
G03X896562Y360055I-27J198D01*
G01Y360682D01*
G03X896389Y360881I-200J1D01*
G02Y363857I203J1488D01*
G03X896562Y364056I-27J198D01*
G01Y364682D01*
G03X896389Y364881I-200J1D01*
G02X896562Y367871I204J1488D01*
G01Y367930D01*
G02X896766Y368877I2307J-1D01*
G02X896594Y368867I-173J1492D01*
G01X896592D01*
G02X895142Y369976I0J1502D01*
G03X894949Y370124I-193J-52D01*
G01X894152D01*
G03X894010Y370065I0J-200D01*
G01X889117Y365171D01*
G03X889058Y365029I141J-142D01*
G01Y360475D01*
G02X888804Y359424I-2307J1D01*
G01X888782Y359382D01*
X888781Y359287D01*
X888965Y358915D01*
X889040Y358858D01*
X889087Y358849D01*
G02X890314Y357372I-275J-1477D01*
G02X888812Y355870I-1502J0D01*
G02X887363Y356977I0J1502D01*
G01Y356979D01*
G03X887221Y357118I-192J-54D01*
G01X886886Y357207D01*
G03X886694Y357156I-51J-193D01*
G01X885183Y355645D01*
G02X883553Y354970I-1630J1631D01*
G01X883552D01*
G02X881246Y357276I0J2306D01*
G01Y357277D01*
G02X881921Y358907I2306J0D01*
G01X884385Y361371D01*
G03X884444Y361513I-141J142D01*
G01Y366067D01*
G02X885120Y367698I2307J-1D01*
G01X891171Y373749D01*
G03X891214Y373966I-142J141D01*
G01X891191Y374023D01*
X891090Y374090D01*
X872879D01*
G02X872884Y373971I-1497J-122D01*
G02X871382Y372469I-1502J0D01*
G02X870547Y372722I-1J1502D01*
G03X870295Y372697I-111J-166D01*
G01X869717Y372119D01*
G02X868087Y371444I-1630J1631D01*
G01X868086D01*
G02X865780Y373750I0J2306D01*
G01Y373751D01*
G02X866455Y375381I2306J0D01*
G01X867945Y376871D01*
G03Y377153I-142J141D01*
G01X865955Y379143D01*
G02X865280Y380773I1631J1630D01*
G01Y382272D01*
G03X865188Y382440I-200J0D01*
G01X864861Y382650D01*
X864759Y382657D01*
X864713Y382635D01*
G02X864086Y382498I-627J1366D01*
G02X862584Y384000I0J1502D01*
G02X862757Y384699I1502J-1D01*
G03X862780Y384792I-177J93D01*
G01Y385122D01*
G02X863162Y386044I1306J-1D01*
G01X864445Y387327D01*
G03X864489Y387545I-141J142D01*
G01X864466Y387601D01*
X864366Y387668D01*
X852014D01*
G02X850669Y388225I0J1902D01*
G01X838851Y400043D01*
G02X838294Y401388I1345J1345D01*
G01Y419132D01*
G02X838851Y420477I1902J0D01*
G01X845687Y427313D01*
G03X845746Y427455I-141J142D01*
G01Y452068D01*
G03X845623Y452253I-200J0D01*
G01X845567Y452276D01*
X845449Y452253D01*
X831138Y437942D01*
G02X830216Y437560I-923J924D01*
G01X811602D01*
G02X810680Y437942I1J1306D01*
G01X801771Y446851D01*
G03X801691Y446900I-142J-141D01*
G01X801690D01*
G02X800634Y448334I446J1434D01*
G02X802136Y449836I1502J0D01*
G02X803570Y448781I0J-1502D01*
G01Y448779D01*
G03X803619Y448699I190J62D01*
G01X808746Y443572D01*
G03X808921Y443517I141J142D01*
G01X809292Y443582D01*
X809369Y443641D01*
X809390Y443685D01*
G02X810749Y444547I1359J-640D01*
G02X812246Y443164I0J-1502D01*
G01Y443162D01*
G03X812345Y443006I199J17D01*
G01X812630Y442841D01*
G03X812816Y442833I101J173D01*
G02X813455Y442976I640J-1359D01*
G01X813456D01*
G02X814612Y442433I0J-1502D01*
G03X814763Y442361I154J128D01*
G01X814891Y442359D01*
G03X815044Y442428I2J200D01*
G01X815045Y442429D01*
G03X815093Y442585I-151J132D01*
G01X815077Y442712D01*
G03X814991Y442852I-198J-25D01*
G02X814338Y444091I849J1239D01*
G02X815840Y445593I1502J0D01*
G02X817025Y445014I0J-1502D01*
G03X817183Y444937I158J123D01*
G01X817497D01*
G03X817655Y445014I0J200D01*
G02X818840Y445593I1185J-923D01*
G02Y442589I0J-1502D01*
G02X817655Y443168I0J1502D01*
G03X817497Y443245I-158J-123D01*
G01X817183D01*
G03X817025Y443168I0J-200D01*
G02X816972Y443104I-1183J926D01*
G03X816925Y442948I151J-131D01*
G01X816940Y442821D01*
G03X817026Y442681I198J25D01*
G02X817679Y441442I-849J-1239D01*
G01Y441441D01*
G02X817513Y440755I-1502J0D01*
G01X817489Y440708D01*
X817493Y440606D01*
X817698Y440268D01*
G03X817869Y440172I171J104D01*
G01X829590D01*
G03X829732Y440231I0J200D01*
G01X844233Y454732D01*
G03X844292Y454874I-141J142D01*
G01Y460069D01*
G03X844166Y460255I-200J0D01*
G01X843763Y460416D01*
X843644Y460390D01*
X843602Y460346D01*
G02X842515Y459880I-1087J1035D01*
G02Y462884I0J1502D01*
G02X843602Y462418I0J-1501D01*
G01X843644Y462374D01*
X843763Y462348D01*
X844166Y462509D01*
G03X844292Y462695I-74J186D01*
G01Y465376D01*
G03X844190Y465550I-200J0D01*
G01X843887Y465722D01*
G03X843687Y465720I-98J-174D01*
G01X843686D01*
G02X842916Y465507I-771J1289D01*
G02Y468511I0J1502D01*
G02X843686Y468298I-1J-1502D01*
G01X843687D01*
G03X843887Y468296I102J172D01*
G01X844190Y468468D01*
G03X844292Y468642I-98J174D01*
G01Y471534D01*
G03X844183Y471712I-200J0D01*
G01X843865Y471874D01*
G03X843658Y471858I-90J-178D01*
G02X842779Y471574I-879J1218D01*
G02Y474578I0J1502D01*
G02X843658Y474294I0J-1502D01*
G01X843704Y474261D01*
X843815Y474253D01*
X844183Y474440D01*
G03X844292Y474618I-91J178D01*
G01Y474678D01*
G03X844233Y474820I-200J0D01*
G01X841337Y477715D01*
G02X840954Y478639I923J924D01*
G01Y482167D01*
G02X840972Y482378I1307J-5D01*
G03X840974Y482407I-198J28D01*
G02X841147Y483081I1502J-26D01*
G03X841170Y483174I-177J93D01*
G01Y491750D01*
G02X841552Y492672I1306J-1D01*
G01X851524Y502644D01*
G02X852446Y503026I923J-924D01*
G01X914193D01*
G02X915115Y502644I-1J-1306D01*
G01X936012Y481747D01*
G02X936394Y480825I-924J-923D01*
G01Y476464D01*
G03X936453Y476322I200J0D01*
G01X945661Y467115D01*
G02X946044Y466191I-923J-924D01*
G01Y443807D01*
G02X945661Y442883I-1306J0D01*
G01X943355Y440577D01*
G03X943306Y440497I141J-142D01*
G01Y440496D01*
G02X941872Y439440I-1434J446D01*
G02X940370Y440942I0J1502D01*
G02X941425Y442376I1502J0D01*
G01X941427D01*
G03X941507Y442425I-62J190D01*
G01X943371Y444289D01*
G03X943430Y444431I-141J142D01*
G01Y465567D01*
G03X943371Y465709I-200J0D01*
G01X934164Y474916D01*
G02X933782Y475838I924J923D01*
G01Y480199D01*
G03X933723Y480341I-200J0D01*
G01X913709Y500355D01*
G03X913567Y500414I-142J-141D01*
G01X853072D01*
G03X852930Y500355I0J-200D01*
G01X843841Y491266D01*
G03X843782Y491124I141J-142D01*
G01Y483174D01*
G03X843805Y483081I200J0D01*
G02X843978Y482382I-1329J-700D01*
G02X843969Y482222I-1502J4D01*
G01X843965Y482181D01*
X843988Y482103D01*
X844202Y481851D01*
G03X844343Y481780I153J128D01*
G02X845572Y481227I-115J-1898D01*
G01X848993Y477806D01*
G02X849550Y476461I-1345J-1345D01*
G01Y471116D01*
G03X849641Y470948I200J0D01*
G01X849966Y470738D01*
X850068Y470730D01*
X850114Y470751D01*
G02X850732Y470884I618J-1369D01*
G02Y467880I0J-1502D01*
G02X850114Y468013I0J1502D01*
G01X850068Y468034D01*
X849966Y468026D01*
X849641Y467816D01*
G03X849550Y467648I109J-168D01*
G01Y467108D01*
G03X849642Y466940I200J0D01*
G01X849969Y466730D01*
X850071Y466723D01*
X850117Y466745D01*
G02X850748Y466884I631J-1363D01*
G02Y463880I0J-1502D01*
G02X850117Y464019I0J1502D01*
G01X850071Y464041D01*
X849969Y464034D01*
X849642Y463824D01*
G03X849550Y463656I108J-168D01*
G01Y426584D01*
G02X848993Y425239I-1902J0D01*
G01X842157Y418403D01*
G03X842098Y418261I141J-142D01*
G01Y402259D01*
G03X842157Y402117I200J0D01*
G01X852743Y391531D01*
G03X852885Y391472I142J141D01*
G01X853021D01*
G03X853221Y391672I0J200D01*
G01Y391717D01*
X853182Y391798D01*
X853146Y391827D01*
G02X852584Y392999I941J1172D01*
G02X855588I1502J0D01*
G02X855296Y392109I-1502J0D01*
G01X855262Y392063D01*
X855253Y391951D01*
X855440Y391582D01*
G03X855618Y391472I178J90D01*
G01X866055D01*
G03X866233Y391582I0J200D01*
G01X866420Y391951D01*
X866411Y392063D01*
X866377Y392109D01*
G02X866084Y393000I1208J891D01*
G02X869088I1502J0D01*
G02X868795Y392109I-1501J0D01*
G01X868761Y392063D01*
X868752Y391951D01*
X868939Y391582D01*
G03X869117Y391472I178J90D01*
G01X870561D01*
G02X870789Y391458I-2J-1902D01*
G01X870830Y391453D01*
X870909Y391476D01*
X871198Y391718D01*
X871234Y391792D01*
X871236Y391834D01*
G02X872736Y393256I1500J-80D01*
G02X874238Y391754I0J-1502D01*
G02X873269Y390350I-1502J0D01*
G01X873267D01*
X873220Y390332D01*
X873155Y390255D01*
X873073Y389877D01*
G03X873127Y389693I196J-43D01*
G01X873376Y389444D01*
G03X873518Y389386I141J142D01*
G01X881549D01*
G03X881733Y389507I0J200D01*
G01X881878Y389845D01*
G03X881839Y390062I-184J79D01*
G02X881423Y391099I1086J1038D01*
G02X884427I1502J0D01*
G02X884011Y390062I-1502J1D01*
G03X883972Y389845I145J-138D01*
G01X884117Y389507D01*
G03X884301Y389386I184J79D01*
G01X891251D01*
G02Y385582I0J-1902D01*
G01X872647D01*
G02X872204Y385635I3J1902D01*
G03X872033Y385598I-47J-194D01*
G01X871786Y385403D01*
G03X871710Y385246I124J-157D01*
G01Y381868D01*
G03X871769Y381726I200J0D01*
G01X872063Y381432D01*
G03X872205Y381374I141J142D01*
G01X875398D01*
G03X875583Y381498I0J200D01*
G01X875723Y381840D01*
G03X875680Y382057I-185J76D01*
G01X875679Y382058D01*
G02X875234Y383125I1057J1067D01*
G02X878238I1502J0D01*
G02X877793Y382058I-1502J0D01*
G01X877792Y382057D01*
G03X877749Y381840I142J-141D01*
G01X877889Y381498D01*
G03X878074Y381374I185J76D01*
G01X879398D01*
G03X879583Y381498I0J200D01*
G01X879723Y381840D01*
G03X879680Y382057I-185J76D01*
G01X879679Y382058D01*
G02X879234Y383125I1057J1067D01*
G02X882238I1502J0D01*
G02X881793Y382058I-1502J0D01*
G01X881792Y382057D01*
G03X881749Y381840I142J-141D01*
G01X881889Y381498D01*
G03X882074Y381374I185J76D01*
G01X896936D01*
G03X897078Y381433I0J200D01*
G01X897110Y381465D01*
G03Y381747I-142J141D01*
G01X897087Y381770D01*
X897059Y381784D01*
G02X896234Y383125I677J1341D01*
G02X897736Y384627I1502J0D01*
G02X898239Y384540I-1J-1502D01*
G03X898422Y384565I67J188D01*
G01X898689Y384753D01*
G03X898774Y384917I-115J164D01*
G01Y384937D01*
G02X899156Y385859I1306J-1D01*
G01X908721Y395424D01*
G02X909643Y395806I923J-924D01*
G01X914264D01*
G03X914406Y395865I0J200D01*
G01X931939Y413399D01*
G02X932863Y413782I924J-923D01*
G01X944575D01*
G03X944717Y413841I0J200D01*
G01X955117Y424240D01*
G03X955176Y424382I-141J142D01*
G01Y447039D01*
G03X955117Y447181I-200J0D01*
G01X954026Y448271D01*
G02X953644Y449193I924J923D01*
G01Y453398D01*
G02X954026Y454320I1306J-1D01*
G01X955117Y455411D01*
G03X955176Y455553I-141J142D01*
G01Y460864D01*
G03X955117Y461006I-200J0D01*
G01X938423Y477700D01*
G02X938040Y478624I923J924D01*
G01Y500176D01*
G03X937981Y500318I-200J0D01*
G01X928924Y509375D01*
G02X928542Y510297I924J923D01*
G01Y551380D01*
G02X928924Y552302I1306J-1D01*
G01X932087Y555465D01*
G03X932126Y555691I-142J141D01*
G01X931967Y556032D01*
G03X931767Y556146I-181J-85D01*
G02X931627Y556139I-145J1495D01*
G02X933129Y557641I0J1502D01*
G02X933122Y557501I-1502J5D01*
G01X933116Y557438D01*
X933179Y557328D01*
X933577Y557142D01*
G03X933803Y557181I85J181D01*
G01X937981Y561359D01*
G03X938040Y561501I-141J142D01*
G01Y572624D01*
G03X937981Y572766I-200J0D01*
G01X935535Y575212D01*
G02X935152Y576136I923J924D01*
G01Y583988D01*
G03X935055Y584159I-200J0D01*
G01X934762Y584336D01*
G03X934567Y584342I-103J-171D01*
G01X934566D01*
G02X933725Y584134I-840J1594D01*
G02X931922Y585936I-1J1802D01*
G01Y589336D01*
G02X933725Y591138I1803J-1D01*
G01X933726D01*
G02X934566Y590930I0J-1802D01*
G01X934567D01*
G03X934762Y590936I92J177D01*
G01X935055Y591113D01*
G03X935152Y591284I-103J171D01*
G01Y593008D01*
G02X935155Y593081I1306J-17D01*
G03X935149Y593146I-200J14D01*
G03X934845Y593262I-194J-51D01*
G03X934834Y593254I112J-166D01*
G02X933741Y592884I-1094J1433D01*
G02X931938Y594687I0J1803D01*
G01Y598087D01*
G02X935544I1803J0D01*
G01Y594687D01*
G02X935525Y594431I-1803J5D01*
G01X935518Y594383D01*
X935548Y594295D01*
X935582Y594261D01*
G03X935864I141J142D01*
G01X950993Y609390D01*
G03X951052Y609532I-141J142D01*
G01Y611758D01*
G02X951435Y612682I1306J0D01*
G01X954077Y615324D01*
G02X954999Y615706I923J-924D01*
G37*
G36*
G01X68168Y619513D02*
G02X71172I1502J0D01*
G02X70687Y618407I-1504J0D01*
G03X70622Y618260I135J-148D01*
G01Y617966D01*
G03X70687Y617819I200J1D01*
G02Y615607I-1017J-1106D01*
G03X70622Y615460I135J-148D01*
G01Y615166D01*
G03X70687Y615019I200J1D01*
G02X71172Y613913I-1019J-1106D01*
G02X68168I-1502J0D01*
G02X68653Y615019I1504J0D01*
G03X68718Y615166I-135J148D01*
G01Y615460D01*
G03X68653Y615607I-200J-1D01*
G02Y617819I1017J1106D01*
G03X68718Y617966I-135J148D01*
G01Y618260D01*
G03X68653Y618407I-200J-1D01*
G02X68168Y619513I1019J1106D01*
G37*
G36*
G01X525254D02*
G02X528258I1502J0D01*
G02X527773Y618407I-1504J0D01*
G03X527708Y618260I135J-148D01*
G01Y617966D01*
G03X527773Y617819I200J1D01*
G02Y615607I-1017J-1106D01*
G03X527708Y615460I135J-148D01*
G01Y615166D01*
G03X527773Y615019I200J1D01*
G02X528258Y613913I-1019J-1106D01*
G02X525254I-1502J0D01*
G02X525739Y615019I1504J0D01*
G03X525804Y615166I-135J148D01*
G01Y615460D01*
G03X525739Y615607I-200J-1D01*
G02Y617819I1017J1106D01*
G03X525804Y617966I-135J148D01*
G01Y618260D01*
G03X525739Y618407I-200J-1D01*
G02X525254Y619513I1019J1106D01*
G37*
G36*
G01X982341D02*
G02X985345I1502J0D01*
G02X984860Y618407I-1504J0D01*
G03X984795Y618260I135J-148D01*
G01Y617966D01*
G03X984860Y617819I200J1D01*
G02Y615607I-1017J-1106D01*
G03X984795Y615460I135J-148D01*
G01Y615166D01*
G03X984860Y615019I200J1D01*
G02X985345Y613913I-1019J-1106D01*
G02X982341I-1502J0D01*
G02X982826Y615019I1504J0D01*
G03X982891Y615166I-135J148D01*
G01Y615460D01*
G03X982826Y615607I-200J-1D01*
G02Y617819I1017J1106D01*
G03X982891Y617966I-135J148D01*
G01Y618260D01*
G03X982826Y618407I-200J-1D01*
G02X982341Y619513I1019J1106D01*
G37*
G36*
G01X80238Y619758D02*
G02X83242I1502J0D01*
G02X82757Y618652I-1504J0D01*
G03X82692Y618505I135J-148D01*
G01Y618211D01*
G03X82757Y618064I200J1D01*
G02Y615852I-1017J-1106D01*
G03X82692Y615705I135J-148D01*
G01Y615411D01*
G03X82757Y615264I200J1D01*
G02X83242Y614158I-1019J-1106D01*
G02X80238I-1502J0D01*
G02X80723Y615264I1504J0D01*
G03X80788Y615411I-135J148D01*
G01Y615705D01*
G03X80723Y615852I-200J-1D01*
G02Y618064I1017J1106D01*
G03X80788Y618211I-135J148D01*
G01Y618505D01*
G03X80723Y618652I-200J-1D01*
G02X80238Y619758I1019J1106D01*
G37*
G36*
G01X537324D02*
G02X540328I1502J0D01*
G02X539843Y618652I-1504J0D01*
G03X539778Y618505I135J-148D01*
G01Y618211D01*
G03X539843Y618064I200J1D01*
G02Y615852I-1017J-1106D01*
G03X539778Y615705I135J-148D01*
G01Y615411D01*
G03X539843Y615264I200J1D01*
G02X540328Y614158I-1019J-1106D01*
G02X537324I-1502J0D01*
G02X537809Y615264I1504J0D01*
G03X537874Y615411I-135J148D01*
G01Y615705D01*
G03X537809Y615852I-200J-1D01*
G02Y618064I1017J1106D01*
G03X537874Y618211I-135J148D01*
G01Y618505D01*
G03X537809Y618652I-200J-1D01*
G02X537324Y619758I1019J1106D01*
G37*
G36*
G01X994411D02*
G02X997415I1502J0D01*
G02X996930Y618652I-1504J0D01*
G03X996865Y618505I135J-148D01*
G01Y618211D01*
G03X996930Y618064I200J1D01*
G02Y615852I-1017J-1106D01*
G03X996865Y615705I135J-148D01*
G01Y615411D01*
G03X996930Y615264I200J1D01*
G02X997415Y614158I-1019J-1106D01*
G02X994411I-1502J0D01*
G02X994896Y615264I1504J0D01*
G03X994961Y615411I-135J148D01*
G01Y615705D01*
G03X994896Y615852I-200J-1D01*
G02Y618064I1017J1106D01*
G03X994961Y618211I-135J148D01*
G01Y618505D01*
G03X994896Y618652I-200J-1D01*
G02X994411Y619758I1019J1106D01*
G37*
G36*
G01X43362Y620661D02*
G02X45966I1302J0D01*
G02X45404Y619590I-1301J0D01*
G03Y618932I228J-329D01*
G02X45966Y617861I-739J-1071D01*
G02X43362I-1302J0D01*
G02X43924Y618932I1301J0D01*
G03Y619590I-228J329D01*
G02X43362Y620661I739J1071D01*
G37*
G36*
G01X46905D02*
G02X49509I1302J0D01*
G02X48947Y619590I-1301J0D01*
G03Y618932I228J-329D01*
G02X49509Y617861I-739J-1071D01*
G02X46905I-1302J0D01*
G02X47467Y618932I1301J0D01*
G03Y619590I-228J329D01*
G02X46905Y620661I739J1071D01*
G37*
G36*
G01X50448D02*
G02X53052I1302J0D01*
G02X52490Y619590I-1301J0D01*
G03Y618932I228J-329D01*
G02X53052Y617861I-739J-1071D01*
G02X50448I-1302J0D01*
G02X51010Y618932I1301J0D01*
G03Y619590I-228J329D01*
G02X50448Y620661I739J1071D01*
G37*
G36*
G01X53992D02*
G02X56596I1302J0D01*
G02X56034Y619590I-1301J0D01*
G03Y618932I228J-329D01*
G02X56596Y617861I-739J-1071D01*
G02X53992I-1302J0D01*
G02X54554Y618932I1301J0D01*
G03Y619590I-228J329D01*
G02X53992Y620661I739J1071D01*
G37*
G36*
G01X500448D02*
G02X503052I1302J0D01*
G02X502490Y619590I-1301J0D01*
G03Y618932I228J-329D01*
G02X503052Y617861I-739J-1071D01*
G02X500448I-1302J0D01*
G02X501010Y618932I1301J0D01*
G03Y619590I-228J329D01*
G02X500448Y620661I739J1071D01*
G37*
G36*
G01X503991D02*
G02X506595I1302J0D01*
G02X506033Y619590I-1301J0D01*
G03Y618932I228J-329D01*
G02X506595Y617861I-739J-1071D01*
G02X503991I-1302J0D01*
G02X504553Y618932I1301J0D01*
G03Y619590I-228J329D01*
G02X503991Y620661I739J1071D01*
G37*
G36*
G01X507534D02*
G02X510138I1302J0D01*
G02X509576Y619590I-1301J0D01*
G03Y618932I228J-329D01*
G02X510138Y617861I-739J-1071D01*
G02X507534I-1302J0D01*
G02X508096Y618932I1301J0D01*
G03Y619590I-228J329D01*
G02X507534Y620661I739J1071D01*
G37*
G36*
G01X511078D02*
G02X513682I1302J0D01*
G02X513120Y619590I-1301J0D01*
G03Y618932I228J-329D01*
G02X513682Y617861I-739J-1071D01*
G02X511078I-1302J0D01*
G02X511640Y618932I1301J0D01*
G03Y619590I-228J329D01*
G02X511078Y620661I739J1071D01*
G37*
G36*
G01X957535D02*
G02X960139I1302J0D01*
G02X959577Y619590I-1301J0D01*
G03Y618932I228J-329D01*
G02X960139Y617861I-739J-1071D01*
G02X957535I-1302J0D01*
G02X958097Y618932I1301J0D01*
G03Y619590I-228J329D01*
G02X957535Y620661I739J1071D01*
G37*
G36*
G01X961078D02*
G02X963682I1302J0D01*
G02X963120Y619590I-1301J0D01*
G03Y618932I228J-329D01*
G02X963682Y617861I-739J-1071D01*
G02X961078I-1302J0D01*
G02X961640Y618932I1301J0D01*
G03Y619590I-228J329D01*
G02X961078Y620661I739J1071D01*
G37*
G36*
G01X964621D02*
G02X967225I1302J0D01*
G02X966663Y619590I-1301J0D01*
G03Y618932I228J-329D01*
G02X967225Y617861I-739J-1071D01*
G02X964621I-1302J0D01*
G02X965183Y618932I1301J0D01*
G03Y619590I-228J329D01*
G02X964621Y620661I739J1071D01*
G37*
G36*
G01X968165D02*
G02X970769I1302J0D01*
G02X970207Y619590I-1301J0D01*
G03Y618932I228J-329D01*
G02X970769Y617861I-739J-1071D01*
G02X968165I-1302J0D01*
G02X968727Y618932I1301J0D01*
G03Y619590I-228J329D01*
G02X968165Y620661I739J1071D01*
G37*
G36*
G01X60352Y620653D02*
G02X63356I1502J0D01*
G02X62871Y619547I-1504J0D01*
G03X62806Y619400I135J-148D01*
G01Y619106D01*
G03X62871Y618959I200J1D01*
G02X63356Y617853I-1019J-1106D01*
G02X60352I-1502J0D01*
G02X60837Y618959I1504J0D01*
G03X60902Y619106I-135J148D01*
G01Y619400D01*
G03X60837Y619547I-200J-1D01*
G02X60352Y620653I1019J1106D01*
G37*
G36*
G01X517438D02*
G02X520442I1502J0D01*
G02X519957Y619547I-1504J0D01*
G03X519892Y619400I135J-148D01*
G01Y619106D01*
G03X519957Y618959I200J1D01*
G02X520442Y617853I-1019J-1106D01*
G02X517438I-1502J0D01*
G02X517923Y618959I1504J0D01*
G03X517988Y619106I-135J148D01*
G01Y619400D01*
G03X517923Y619547I-200J-1D01*
G02X517438Y620653I1019J1106D01*
G37*
G36*
G01X974525D02*
G02X977529I1502J0D01*
G02X977044Y619547I-1504J0D01*
G03X976979Y619400I135J-148D01*
G01Y619106D01*
G03X977044Y618959I200J1D01*
G02X977529Y617853I-1019J-1106D01*
G02X974525I-1502J0D01*
G02X975010Y618959I1504J0D01*
G03X975075Y619106I-135J148D01*
G01Y619400D01*
G03X975010Y619547I-200J-1D01*
G02X974525Y620653I1019J1106D01*
G37*
G36*
G01X900676Y623338D02*
X904076D01*
G02Y619734I0J-1802D01*
G01X900676D01*
G02Y623338I0J1802D01*
G37*
G36*
G01X909508Y623418D02*
X912908D01*
G02Y619814I0J-1802D01*
G01X909508D01*
G02Y623418I0J1802D01*
G37*
G36*
G01X918300Y631202D02*
G02Y628198I0J-1502D01*
G02X917313Y628568I0J1501D01*
G01X917312D01*
Y628569D01*
G03X917182Y628617I-130J-152D01*
G01X916918D01*
G03X916788Y628569I0J-200D01*
G01X916787Y628568D01*
G02X915800Y628198I-987J1131D01*
G02Y631202I0J1502D01*
G02X916787Y630832I0J-1501D01*
G01X916788D01*
Y630831D01*
G03X916918Y630783I130J152D01*
G01X917182D01*
G03X917312Y630831I0J200D01*
G01X917313Y630832D01*
G02X918300Y631202I987J-1131D01*
G37*
G36*
G01X943933Y634388D02*
G02X945434Y635827I1501J-63D01*
G02Y632823I0J-1502D01*
G01X945433D01*
G02X945155Y632849I0J1502D01*
G03X944682Y632473I-74J-393D01*
G02X943181Y631034I-1501J63D01*
G02Y634038I0J1502D01*
G01X943182D01*
G02X943460Y634012I0J-1502D01*
G03X943933Y634388I74J393D01*
G37*
G36*
G01X246102Y657823D02*
G02X247604Y656321I0J-1502D01*
G02X246549Y654887I-1502J0D01*
G01X246547D01*
G03X246467Y654838I62J-190D01*
G01X227005Y635377D01*
G03X226946Y635235I141J-142D01*
G01Y574337D01*
G02X226564Y573415I-1306J1D01*
G01X223330Y570181D01*
G03X223285Y569969I142J-141D01*
G01X223414Y569628D01*
G03X223589Y569499I187J71D01*
G02X225002Y568000I-89J-1499D01*
G02X223500Y566498I-1502J0D01*
G01X223499D01*
G02X222794Y566674I1J1502D01*
G03X222597Y566669I-94J-177D01*
G01X222303Y566492D01*
G03X222206Y566321I103J-171D01*
G01Y563973D01*
G03X222341Y563784I200J0D01*
G01X222698Y563660D01*
G03X222921Y563726I65J189D01*
G02X224104Y564302I1183J-927D01*
G02Y561298I0J-1502D01*
G02X222921Y561874I0J1503D01*
G03X222698Y561940I-158J-123D01*
G01X222341Y561816D01*
G03X222206Y561627I65J-189D01*
G01Y560050D01*
G03X222336Y559862I200J-1D01*
G01X222688Y559731D01*
G03X222908Y559787I69J188D01*
G02X224040Y560302I1132J-987D01*
G02Y557298I0J-1502D01*
G02X222908Y557813I0J1502D01*
G01X222866Y557861D01*
X222747Y557891D01*
X222336Y557738D01*
G03X222206Y557550I70J-187D01*
G01Y548369D01*
G03X222333Y548183I200J0D01*
G01X222680Y548047D01*
G03X222900Y548097I73J186D01*
G02X223037Y548227I1100J-1022D01*
G01X223038Y548228D01*
G03X223108Y548366I-129J152D01*
G01X223129Y548654D01*
G03X223080Y548800I-200J14D01*
G01X223079Y548801D01*
G02X222698Y549800I1121J1000D01*
G02X225702I1502J0D01*
G02X225163Y548648I-1501J0D01*
G01X225162Y548647D01*
G03X225092Y548509I129J-152D01*
G01X225071Y548221D01*
G03X225120Y548075I200J-14D01*
G01X225121Y548074D01*
G02X225502Y547075I-1121J-1000D01*
G02X224000Y545573I-1502J0D01*
G02X222900Y546053I1J1502D01*
G03X222680Y546103I-147J-136D01*
G01X222333Y545967D01*
G03X222206Y545781I73J-186D01*
G01Y540037D01*
G03X222330Y539852I200J0D01*
G01X222386Y539828D01*
X222504Y539852D01*
X223517Y540865D01*
G03X223566Y540945I-141J142D01*
G01Y540946D01*
G02X225000Y542002I1434J-446D01*
G02X226502Y540500I0J-1502D01*
G02X225447Y539066I-1502J0D01*
G01X225445D01*
G03X225365Y539017I62J-190D01*
G01X224327Y537979D01*
G03X224268Y537837I141J-142D01*
G01Y532575D01*
G03X224350Y532413I200J0D01*
G01X224650Y532195D01*
X224745Y532180D01*
X224791Y532195D01*
G02X225496Y532306I707J-2195D01*
G01X225500D01*
G02X227806Y530000I0J-2306D01*
G01Y527158D01*
G03X227865Y527016I200J0D01*
G01X230828Y524054D01*
G02X231504Y522423I-1631J-1632D01*
G01Y462766D01*
G03X231563Y462624I200J0D01*
G01X250696Y443491D01*
G03X250871Y443436I141J142D01*
G01X251242Y443500D01*
X251318Y443558D01*
X251339Y443602D01*
G02X252695Y444458I1356J-646D01*
G02X254197Y442956I0J-1502D01*
G02X253341Y441600I-1502J0D01*
G01X253297Y441579D01*
X253239Y441503D01*
X253175Y441132D01*
G03X253230Y440957I197J-34D01*
G01X253498Y440689D01*
G03X253640Y440630I142J141D01*
G01X254512D01*
G02Y436016I0J-2307D01*
G01X252602D01*
G02X250971Y436692I1J2307D01*
G01X228071Y459592D01*
G03X227789I-141J-142D01*
G01X222859Y454662D01*
G03X222810Y454582I141J-142D01*
G01Y454581D01*
G02X221375Y453522I-1435J443D01*
G02X220132Y454180I0J1503D01*
G01Y454182D01*
X220106Y454218D01*
X220031Y454263D01*
X219679Y454296D01*
G03X219518Y454238I-19J-199D01*
G01X213356Y448076D01*
G02X212434Y447694I-923J924D01*
G01X203925D01*
G03X203783Y447635I0J-200D01*
G01X202555Y446407D01*
G03X202496Y446265I141J-142D01*
G01Y388431D01*
G03X202555Y388289I200J0D01*
G01X205599Y385246D01*
G02X205982Y384322I-923J-924D01*
G01Y382899D01*
G03X206003Y382810I200J0D01*
G01X206004Y382808D01*
G02X206177Y382109I-1329J-700D01*
G02X203173I-1502J0D01*
G02X203345Y382806I1502J-1D01*
G03X203347Y382810I-178J91D01*
G01X203358Y382831D01*
X203368Y382875D01*
Y383698D01*
G03X203309Y383840I-200J0D01*
G01X200266Y386883D01*
G02X199884Y387805I924J923D01*
G01Y446891D01*
G02X200266Y447813I1306J-1D01*
G01X202377Y449924D01*
G02X203299Y450306I923J-924D01*
G01X211808D01*
G03X211950Y450365I0J200D01*
G01X224235Y462650D01*
G03X224294Y462792I-141J142D01*
G01Y520076D01*
G03X224235Y520218I-200J0D01*
G01X219976Y524476D01*
G02X219594Y525398I924J923D01*
G01Y569601D01*
G02X219976Y570523I1306J-1D01*
G01X224275Y574821D01*
G03X224334Y574963I-141J142D01*
G01Y635861D01*
G02X224716Y636783I1306J-1D01*
G01X242092Y654159D01*
G03X242141Y654363I-141J142D01*
G01X242013Y654755D01*
X241927Y654828D01*
X241871Y654837D01*
G02X240600Y656321I231J1484D01*
G02X242102Y657823I1502J0D01*
G02X243586Y656552I0J-1502D01*
G01X243595Y656496D01*
X243668Y656410D01*
X244060Y656282D01*
G03X244264Y656331I62J190D01*
G01X244619Y656686D01*
G03X244668Y656766I-141J142D01*
G01Y656767D01*
G02X246102Y657823I1434J-446D01*
G37*
G36*
G01X248600Y656321D02*
G02X251604I1502J0D01*
G02X251431Y655622I-1502J1D01*
G03X251408Y655529I177J-93D01*
G01Y647754D01*
G02X251026Y646832I-1306J1D01*
G01X246507Y642314D01*
G03X246448Y642172I141J-142D01*
G01Y633741D01*
G02X246066Y632819I-1306J1D01*
G01X244643Y631397D01*
G03X244584Y631255I141J-142D01*
G01Y619080D01*
G03X244607Y618987I200J0D01*
G02X244780Y618288I-1329J-700D01*
G02X241776I-1502J0D01*
G02X241949Y618987I1502J-1D01*
G03X241972Y619080I-177J93D01*
G01Y631881D01*
G02X242354Y632803I1306J-1D01*
G01X243777Y634225D01*
G03X243836Y634367I-141J142D01*
G01Y642798D01*
G02X244218Y643720I1306J-1D01*
G01X248737Y648238D01*
G03X248796Y648380I-141J142D01*
G01Y655529D01*
G03X248773Y655622I-200J0D01*
G02X248600Y656321I1329J700D01*
G37*
G36*
G01X1160275Y657823D02*
G02X1161777Y656321I0J-1502D01*
G02X1160722Y654887I-1502J0D01*
G01X1160720D01*
G03X1160640Y654838I62J-190D01*
G01X1141107Y635305D01*
G03X1141048Y635163I141J-142D01*
G01Y578529D01*
G02X1140665Y577605I-1306J0D01*
G01X1134365Y571306D01*
G03X1134306Y571164I141J-142D01*
G01Y537964D01*
G03X1134430Y537779I200J0D01*
G01X1134486Y537755D01*
X1134604Y537779D01*
X1137690Y540865D01*
G03X1137739Y540945I-141J142D01*
G01Y540946D01*
G02X1139173Y542002I1434J-446D01*
G02X1140675Y540500I0J-1502D01*
G02X1139620Y539066I-1502J0D01*
G01X1139618D01*
G03X1139538Y539017I62J-190D01*
G01X1136039Y535518D01*
G03X1135980Y535376I141J-142D01*
G01Y529125D01*
G03X1136039Y528983I200J0D01*
G01X1142528Y522494D01*
G02X1142910Y521572I-924J-923D01*
G01Y465176D01*
G02X1142528Y464254I-1306J1D01*
G01X1136913Y458640D01*
G03X1136854Y458498I141J-142D01*
G01Y456596D01*
G03X1136877Y456503I200J0D01*
G02X1137050Y455804I-1329J-700D01*
G02X1134046I-1502J0D01*
G02X1134219Y456503I1502J-1D01*
G03X1134242Y456596I-177J93D01*
G01Y458010D01*
G03X1134118Y458195I-200J0D01*
G01X1134062Y458219D01*
X1133944Y458195D01*
X1131357Y455608D01*
G02X1130435Y455226I-923J924D01*
G01X1125394D01*
G03X1125252Y455167I0J-200D01*
G01X1116465Y446380D01*
G03X1116406Y446238I141J-142D01*
G01Y386481D01*
G03X1116465Y386339I200J0D01*
G01X1119213Y383592D01*
G03X1119293Y383543I142J141D01*
G01X1119294D01*
G02X1120350Y382109I-446J-1434D01*
G02X1118848Y380607I-1502J0D01*
G02X1117414Y381662I0J1502D01*
G01Y381664D01*
G03X1117365Y381744I-190J-62D01*
G01X1114176Y384933D01*
G02X1113794Y385855I924J923D01*
G01Y446864D01*
G02X1114176Y447786I1306J-1D01*
G01X1123846Y457456D01*
G02X1124768Y457838I923J-924D01*
G01X1129809D01*
G03X1129951Y457897I0J200D01*
G01X1138535Y466481D01*
G03X1138594Y466623I-141J142D01*
G01Y520477D01*
G03X1138535Y520619I-200J0D01*
G01X1132076Y527077D01*
G02X1131694Y527999I924J923D01*
G01Y571790D01*
G02X1132076Y572712I1306J-1D01*
G01X1138375Y579011D01*
G03X1138434Y579153I-141J142D01*
G01Y635787D01*
G02X1138817Y636711I1306J0D01*
G01X1156265Y654159D01*
G03X1156314Y654363I-141J142D01*
G01X1156186Y654755D01*
X1156100Y654828D01*
X1156044Y654837D01*
G02X1154773Y656321I231J1484D01*
G02X1156275Y657823I1502J0D01*
G02X1157759Y656552I0J-1502D01*
G01X1157768Y656496D01*
X1157841Y656410D01*
X1158233Y656282D01*
G03X1158437Y656331I62J190D01*
G01X1158792Y656686D01*
G03X1158841Y656766I-141J142D01*
G01Y656767D01*
G02X1160275Y657823I1434J-446D01*
G37*
G36*
G01X1162773Y656321D02*
G02X1165777I1502J0D01*
G02X1165605Y655624I-1502J1D01*
G03X1165603Y655620I178J-91D01*
G01X1165592Y655599D01*
X1165582Y655555D01*
Y647756D01*
G02X1165199Y646832I-1306J0D01*
G01X1160681Y642314D01*
G03X1160622Y642172I141J-142D01*
G01Y633743D01*
G02X1160239Y632819I-1306J0D01*
G01X1158817Y631397D01*
G03X1158758Y631255I141J-142D01*
G01Y619078D01*
G03X1158779Y618989I200J0D01*
G01X1158780Y618987D01*
G02X1158953Y618288I-1329J-700D01*
G02X1155949I-1502J0D01*
G02X1156121Y618985I1502J-1D01*
G03X1156123Y618989I-178J91D01*
G01X1156134Y619010D01*
X1156144Y619054D01*
Y631879D01*
G02X1156527Y632803I1306J0D01*
G01X1157949Y634225D01*
G03X1158008Y634367I-141J142D01*
G01Y642796D01*
G02X1158391Y643720I1306J0D01*
G01X1162909Y648238D01*
G03X1162968Y648380I-141J142D01*
G01Y655531D01*
G03X1162947Y655620I-200J0D01*
G01X1162946Y655622D01*
G02X1162773Y656321I1329J700D01*
G37*
G36*
G01X499528Y656341D02*
G02Y659345I0J1502D01*
G02X500839Y658576I0J-1502D01*
G03X501517Y658545I349J196D01*
G02X502755Y659196I1238J-852D01*
G02Y656192I0J-1502D01*
G02X501444Y656961I0J1502D01*
G03X500766Y656992I-349J-196D01*
G02X499528Y656341I-1238J852D01*
G37*
G36*
G01X534264Y663358D02*
X537664D01*
G02Y659754I0J-1802D01*
G01X534264D01*
G02Y663358I0J1802D01*
G37*
G36*
G01X35293Y661450D02*
G02Y664454I0J1502D01*
G02X36320Y664048I0J-1502D01*
G01X36347Y664023D01*
X36415Y663995D01*
X36723Y663990D01*
G03X36857Y664039I3J200D01*
G02X37847Y664412I991J-1129D01*
G02Y661408I0J-1502D01*
G02X36820Y661814I0J1502D01*
G01X36793Y661839D01*
X36725Y661867D01*
X36417Y661872D01*
G03X36283Y661823I-3J-200D01*
G02X35293Y661450I-991J1129D01*
G37*
G36*
G01X526264Y665858D02*
X529664D01*
G02Y662254I0J-1802D01*
G01X526264D01*
G02Y665858I0J1802D01*
G37*
G36*
G01X947907Y667522D02*
G02X949137Y668162I1230J-862D01*
G02Y665158I0J-1502D01*
G02X947991Y665689I0J1502D01*
G03X947358Y665660I-305J-258D01*
G02X946128Y665020I-1230J862D01*
G02Y668024I0J1502D01*
G02X947274Y667493I0J-1502D01*
G03X947907Y667522I305J258D01*
G37*
G36*
G01X966797Y669456D02*
X970197D01*
G02Y665850I0J-1803D01*
G01X966797D01*
G02Y669456I0J1803D01*
G37*
G36*
G01X37804Y673010D02*
G02Y670006I0J-1502D01*
G02X36796Y670395I1J1502D01*
G01X36795Y670396D01*
G03X36661Y670447I-133J-149D01*
G01X36393D01*
G03X36259Y670396I-1J-200D01*
G01X36258Y670395D01*
G02X35250Y670006I-1009J1113D01*
G02Y673010I0J1502D01*
G02X36258Y672621I-1J-1502D01*
G01X36259Y672620D01*
G03X36393Y672569I133J149D01*
G01X36661D01*
G03X36795Y672620I1J200D01*
G01X36796Y672621D01*
G02X37804Y673010I1009J-1113D01*
G37*
G36*
G01X545725Y678299D02*
G02X548729I1502J0D01*
G02X548272Y677220I-1502J0D01*
G01X548242Y677191D01*
X548211Y677115D01*
X548217Y676739D01*
X548251Y676664D01*
X548282Y676636D01*
G02X548778Y675521I-1005J-1115D01*
G02X545774I-1502J0D01*
G02X546231Y676600I1502J0D01*
G01X546261Y676629D01*
X546292Y676705D01*
X546286Y677081D01*
X546252Y677156D01*
X546221Y677184D01*
G02X545725Y678299I1005J1115D01*
G37*
G36*
G01X496782Y681453D02*
G02X499786I1502J0D01*
G02X499416Y680466I-1501J0D01*
G01Y680465D01*
X499415D01*
G03X499367Y680335I152J-130D01*
G01Y680071D01*
G03X499415Y679941I200J0D01*
G01X499416Y679940D01*
G02X499786Y678953I-1131J-987D01*
G02X496782I-1502J0D01*
G02X497152Y679940I1501J0D01*
G01Y679941D01*
X497153D01*
G03X497201Y680071I-152J130D01*
G01Y680335D01*
G03X497153Y680465I-200J0D01*
G01X497152Y680466D01*
G02X496782Y681453I1131J987D01*
G37*
G36*
G01X39549Y683610D02*
G02Y680606I0J-1502D01*
G02X38507Y681026I0J1503D01*
G01X38478Y681054D01*
X38408Y681082D01*
X38051D01*
X37981Y681054D01*
X37952Y681026D01*
G02X36910Y680606I-1042J1083D01*
G02Y683610I0J1502D01*
G02X37952Y683190I0J-1503D01*
G01X37981Y683162D01*
X38051Y683134D01*
X38408D01*
X38478Y683162D01*
X38507Y683190D01*
G02X39549Y683610I1042J-1083D01*
G37*
G36*
G01X535738Y688991D02*
G02X536812Y688539I0J-1502D01*
G03X536945Y688479I143J140D01*
G01X537254Y688463D01*
X537325Y688487D01*
X537354Y688511D01*
G02X538315Y688859I961J-1154D01*
G01X538316D01*
G02Y685855I0J-1502D01*
G02X537242Y686307I0J1502D01*
G03X537109Y686367I-143J-140D01*
G01X536800Y686383D01*
X536729Y686359D01*
X536700Y686335D01*
G02X535739Y685987I-961J1154D01*
G01X535738D01*
G02Y688991I0J1502D01*
G37*
G36*
G01X201115Y697083D02*
G02X202617Y695610I0J-1502D01*
G03X203023Y695218I400J8D01*
G01X203046D01*
G02Y692214I0J-1502D01*
G02X201544Y693687I0J1502D01*
G03X201138Y694079I-400J-8D01*
G01X201115D01*
G02Y697083I0J1502D01*
G37*
G36*
G01X514017Y695757D02*
G02X516951I1467J0D01*
G02X516193Y694473I-1467J0D01*
G01X516144Y694446D01*
X516089Y694351D01*
X516098Y693884D01*
X516156Y693791D01*
X516206Y693766D01*
G02X516677Y693379I-633J-1251D01*
G01X516678Y693378D01*
G03X516826Y693302I157J124D01*
G01X517171Y693285D01*
X517252Y693318D01*
X517282Y693350D01*
G02X518299Y693786I1016J-966D01*
G02X519272Y693394I1J-1402D01*
G01X519301Y693366D01*
X519371Y693338D01*
X519727D01*
X519797Y693366D01*
X519826Y693394D01*
G02X520798Y693786I972J-1010D01*
G01X520799D01*
G02Y690982I0J-1402D01*
G01X520798D01*
G02X519826Y691374I0J1402D01*
G01X519797Y691402D01*
X519727Y691430D01*
X519371D01*
X519301Y691402D01*
X519272Y691374D01*
G02X518300Y690982I-972J1010D01*
G01X518299D01*
G02X517195Y691520I0J1402D01*
G01X517194Y691521D01*
G03X517046Y691597I-157J-124D01*
G01X516701Y691614D01*
X516620Y691581D01*
X516590Y691549D01*
G02X515575Y691113I-1016J966D01*
G01X515573D01*
G02X514171Y692515I0J1402D01*
G02X514872Y693729I1402J0D01*
G01X514873Y693730D01*
G03X514973Y693910I-100J173D01*
G01X514957Y694319D01*
X514896Y694412D01*
X514846Y694436D01*
G02X514017Y695757I638J1321D01*
G37*
G36*
G01X40165Y700584D02*
G02Y697580I0J-1502D01*
G02X39059Y698065I0J1504D01*
G03X38912Y698130I-148J-135D01*
G01X38618D01*
G03X38471Y698065I1J-200D01*
G02X36259I-1106J1017D01*
G03X36112Y698130I-148J-135D01*
G01X35818D01*
G03X35671Y698065I1J-200D01*
G02X34565Y697580I-1106J1019D01*
G02Y700584I0J1502D01*
G02X35671Y700099I0J-1504D01*
G03X35818Y700034I148J135D01*
G01X36112D01*
G03X36259Y700099I-1J200D01*
G02X38471I1106J-1017D01*
G03X38618Y700034I148J135D01*
G01X38912D01*
G03X39059Y700099I-1J200D01*
G02X40165Y700584I1106J-1019D01*
G37*
G36*
G01X1162646Y700993D02*
G02Y697989I0J-1502D01*
G02X1161659Y698359I0J1501D01*
G01X1161658D01*
Y698360D01*
G03X1161528Y698408I-130J-152D01*
G01X1161264D01*
G03X1161134Y698360I0J-200D01*
G01X1161133Y698359D01*
G02X1159159I-987J1131D01*
G01X1159158D01*
Y698360D01*
G03X1159028Y698408I-130J-152D01*
G01X1158764D01*
G03X1158634Y698360I0J-200D01*
G01X1158633Y698359D01*
G02X1156659I-987J1131D01*
G01X1156658D01*
Y698360D01*
G03X1156528Y698408I-130J-152D01*
G01X1156264D01*
G03X1156134Y698360I0J-200D01*
G01X1156133Y698359D01*
G02X1155146Y697989I-987J1131D01*
G02Y700993I0J1502D01*
G02X1156133Y700623I0J-1501D01*
G01X1156134D01*
Y700622D01*
G03X1156264Y700574I130J152D01*
G01X1156528D01*
G03X1156658Y700622I0J200D01*
G01X1156659Y700623D01*
G02X1158633I987J-1131D01*
G01X1158634D01*
Y700622D01*
G03X1158764Y700574I130J152D01*
G01X1159028D01*
G03X1159158Y700622I0J200D01*
G01X1159159Y700623D01*
G02X1161133I987J-1131D01*
G01X1161134D01*
Y700622D01*
G03X1161264Y700574I130J152D01*
G01X1161528D01*
G03X1161658Y700622I0J200D01*
G01X1161659Y700623D01*
G02X1162646Y700993I987J-1131D01*
G37*
G36*
G01X528099Y702622D02*
G02X530903I1402J0D01*
G02X530436Y701577I-1403J0D01*
G01X530404Y701549D01*
X530369Y701471D01*
X530368Y701131D01*
G03X530434Y700982I200J0D01*
G02X530895Y699943I-940J-1039D01*
G01Y699942D01*
G02X530503Y698970I-1402J0D01*
G01X530475Y698941D01*
X530447Y698871D01*
Y698515D01*
X530475Y698445D01*
X530503Y698416D01*
G02X530895Y697443I-1010J-972D01*
G02X530503Y696470I-1402J-1D01*
G01X530475Y696441D01*
X530447Y696371D01*
Y696015D01*
X530475Y695945D01*
X530503Y695916D01*
G02X530895Y694943I-1010J-972D01*
G02X530503Y693970I-1402J-1D01*
G01X530475Y693941D01*
X530447Y693871D01*
Y693515D01*
X530475Y693445D01*
X530503Y693416D01*
G02X530895Y692444I-1010J-972D01*
G01Y692443D01*
G02X529493Y691041I-1402J0D01*
G01X529492D01*
G02X528520Y691433I0J1402D01*
G01X528491Y691461D01*
X528421Y691489D01*
X528065D01*
X527995Y691461D01*
X527966Y691433D01*
G02X526993Y691041I-972J1010D01*
G02X526020Y691433I-1J1402D01*
G01X525991Y691461D01*
X525921Y691489D01*
X525565D01*
X525495Y691461D01*
X525466Y691433D01*
G02X524494Y691041I-972J1010D01*
G01X524493D01*
G02Y693845I0J1402D01*
G01X524494D01*
G02X525466Y693453I0J-1402D01*
G01X525495Y693425D01*
X525565Y693397D01*
X525921D01*
X525991Y693425D01*
X526020Y693453D01*
G02X526993Y693845I972J-1010D01*
G02X527966Y693453I1J-1402D01*
G01X527995Y693425D01*
X528065Y693397D01*
X528421D01*
X528491Y693425D01*
X528520Y693453D01*
G02X528550Y693481I972J-1011D01*
G03X528616Y693629I-134J148D01*
G01Y693757D01*
G03X528550Y693905I-200J0D01*
G02X528091Y694943I944J1038D01*
G01Y694944D01*
G02X528483Y695916I1402J0D01*
G01X528511Y695945D01*
X528539Y696015D01*
Y696371D01*
X528511Y696441D01*
X528483Y696470D01*
G02X528091Y697443I1010J972D01*
G02X528483Y698416I1402J1D01*
G01X528511Y698445D01*
X528539Y698515D01*
Y698871D01*
X528511Y698941D01*
X528483Y698970D01*
G02X528091Y699942I1010J972D01*
G01Y699943D01*
G02X528558Y700988I1403J0D01*
G01X528590Y701016D01*
X528625Y701094D01*
X528626Y701434D01*
G03X528560Y701583I-200J0D01*
G02X528099Y702622I940J1039D01*
G37*
G36*
G01X527843Y707306D02*
G03X527987Y707232I156J126D01*
G01X528285Y707215D01*
G03X528436Y707271I12J200D01*
G01X528437Y707272D01*
G02X529469Y707697I1033J-1042D01*
G02Y704763I0J-1467D01*
G02X528325Y705312I0J1466D01*
G01X528298Y705345D01*
X528223Y705384D01*
X527883Y705403D01*
G03X527732Y705347I-12J-200D01*
G01X527731Y705346D01*
G02X526699Y704921I-1033J1042D01*
G02X525611Y705404I0J1467D01*
G03X525463Y705470I-148J-134D01*
G01X525165D01*
G03X525017Y705404I0J-200D01*
G02X522841I-1088J983D01*
G03X522693Y705470I-148J-134D01*
G01X522395D01*
G03X522247Y705404I0J-200D01*
G02X520071I-1088J983D01*
G03X519923Y705470I-148J-134D01*
G01X519625D01*
G03X519477Y705404I0J-200D01*
G02X518389Y704921I-1088J984D01*
G02X517313Y705392I1J1467D01*
G03X517166Y705456I-147J-136D01*
G01X516872D01*
G03X516725Y705392I0J-200D01*
G02X515649Y704921I-1077J996D01*
G02Y707855I0J1467D01*
G02X516725Y707384I-1J-1467D01*
G03X516872Y707320I147J136D01*
G01X517166D01*
G03X517313Y707384I0J200D01*
G02X518389Y707855I1077J-996D01*
G02X519477Y707372I0J-1467D01*
G03X519625Y707306I148J134D01*
G01X519923D01*
G03X520071Y707372I0J200D01*
G02X522247I1088J-983D01*
G03X522395Y707306I148J134D01*
G01X522693D01*
G03X522841Y707372I0J200D01*
G02X525017I1088J-983D01*
G03X525165Y707306I148J134D01*
G01X525463D01*
G03X525611Y707372I0J200D01*
G02X527843Y707306I1088J-983D01*
G37*
G36*
G01X363015Y708863D02*
G02Y711867I0J1502D01*
G02X364161Y711335I0J-1500D01*
G01X364189Y711302D01*
X364267Y711265D01*
X364657Y711261D01*
X364737Y711296D01*
X364765Y711328D01*
G02X365887Y711831I1122J-1000D01*
G02Y708827I0J-1502D01*
G02X364741Y709359I0J1500D01*
G01X364713Y709392D01*
X364635Y709429D01*
X364245Y709433D01*
X364165Y709398D01*
X364137Y709366D01*
G02X363015Y708863I-1122J1000D01*
G37*
G36*
G01X844348Y710969D02*
G02X847352I1502J0D01*
G01Y710968D01*
G02X846805Y709809I-1502J0D01*
G01X846771Y709781D01*
X846733Y709703D01*
X846724Y709313D01*
X846759Y709233D01*
X846791Y709204D01*
G02X847286Y708089I-1008J-1115D01*
G02X846880Y707062I-1502J0D01*
G01X846854Y707035D01*
X846826Y706964D01*
Y706614D01*
X846854Y706543D01*
X846880Y706516D01*
G02X847286Y705489I-1096J-1027D01*
G02X844282I-1502J0D01*
G02X844688Y706516I1502J0D01*
G01X844714Y706543D01*
X844742Y706614D01*
Y706964D01*
X844714Y707035D01*
X844688Y707062D01*
G02X844282Y708089I1096J1027D01*
G01Y708090D01*
G02X844829Y709249I1502J0D01*
G01X844863Y709277D01*
X844901Y709355D01*
X844910Y709745D01*
X844875Y709825D01*
X844843Y709854D01*
G02X844348Y710969I1008J1115D01*
G37*
G36*
G01X439290Y713901D02*
G02X440792Y712399I0J-1502D01*
G02X440386Y711372I-1502J0D01*
G01X440360Y711345D01*
X440332Y711274D01*
Y710924D01*
X440360Y710853D01*
X440386Y710826D01*
G02X440792Y709799I-1096J-1027D01*
G02X439290Y708297I-1502J0D01*
G02X438303Y708667I0J1501D01*
G01X438302D01*
Y708668D01*
G03X438172Y708716I-130J-152D01*
G01X437908D01*
G03X437778Y708668I0J-200D01*
G01X437777Y708667D01*
G02X435803I-987J1131D01*
G01X435802D01*
Y708668D01*
G03X435672Y708716I-130J-152D01*
G01X435408D01*
G03X435278Y708668I0J-200D01*
G01X435277Y708667D01*
G02X433303I-987J1131D01*
G01X433302D01*
Y708668D01*
G03X433172Y708716I-130J-152D01*
G01X432908D01*
G03X432778Y708668I0J-200D01*
G01X432777Y708667D01*
G02X430803I-987J1131D01*
G01X430802D01*
Y708668D01*
G03X430672Y708716I-130J-152D01*
G01X430408D01*
G03X430278Y708668I0J-200D01*
G01X430277Y708667D01*
G02X429290Y708297I-987J1131D01*
G02X428246Y708719I0J1502D01*
G01X428217Y708747D01*
X428145Y708775D01*
X427822Y708771D01*
G03X427682Y708711I3J-200D01*
G02X426607Y708258I-1075J1049D01*
G02X425105Y709760I0J1502D01*
G02X425511Y710787I1502J0D01*
G01X425537Y710814D01*
X425565Y710885D01*
Y711235D01*
X425537Y711306D01*
X425511Y711333D01*
G02X425105Y712360I1096J1027D01*
G02X426607Y713862I1502J0D01*
G02X427651Y713440I0J-1502D01*
G01X427680Y713412D01*
X427752Y713384D01*
X428075Y713388D01*
G03X428215Y713448I-3J200D01*
G02X429290Y713901I1075J-1049D01*
G02X430277Y713531I0J-1501D01*
G01X430278D01*
Y713530D01*
G03X430408Y713482I130J152D01*
G01X430672D01*
G03X430802Y713530I0J200D01*
G01X430803Y713531D01*
G02X432777I987J-1131D01*
G01X432778D01*
Y713530D01*
G03X432908Y713482I130J152D01*
G01X433172D01*
G03X433302Y713530I0J200D01*
G01X433303Y713531D01*
G02X435277I987J-1131D01*
G01X435278D01*
Y713530D01*
G03X435408Y713482I130J152D01*
G01X435672D01*
G03X435802Y713530I0J200D01*
G01X435803Y713531D01*
G02X437777I987J-1131D01*
G01X437778D01*
Y713530D01*
G03X437908Y713482I130J152D01*
G01X438172D01*
G03X438302Y713530I0J200D01*
G01X438303Y713531D01*
G02X439290Y713901I987J-1131D01*
G37*
G36*
G01X512530Y719803D02*
G02X514032Y718298I0J-1502D01*
G03X514094Y718153I200J0D01*
G01X514334Y717924D01*
X514412Y717896D01*
X514453Y717898D01*
G02X514530Y717900I77J-1500D01*
G01X514531D01*
G02Y714896I0J-1502D01*
G02X513029Y716401I0J1502D01*
G03X512967Y716546I-200J0D01*
G01X512727Y716775D01*
X512649Y716803D01*
X512608Y716801D01*
G02X512531Y716799I-77J1500D01*
G01X512530D01*
G02Y719803I0J1502D01*
G37*
G36*
G01X910836Y720068D02*
G02Y723072I0J1502D01*
G02X912113Y722361I0J-1502D01*
G03X912749Y722302I340J210D01*
G02X913858Y722791I1109J-1013D01*
G02Y719787I0J-1502D01*
G02X912581Y720498I0J1502D01*
G03X911945Y720557I-340J-210D01*
G02X910836Y720068I-1109J1013D01*
G37*
G36*
G01X562374Y723095D02*
G02Y720091I0J-1502D01*
G02X561203Y720652I0J1503D01*
G03X560850Y720495I-156J-125D01*
G02X560872Y720209I-1780J-281D01*
G01Y716809D01*
G02X557268I-1802J0D01*
G01Y720211D01*
G02X559070Y722012I1802J-1D01*
G02X560235Y721584I-1J-1803D01*
G03X560237Y721582I142J140D01*
G03X560435Y721548I128J154D01*
G01X560814Y721689D01*
X560882Y721772D01*
X560890Y721826D01*
G02X562374Y723095I1484J-233D01*
G37*
G36*
G01X971081Y724139D02*
G02X972346Y723447I0J-1502D01*
G01X972367Y723414D01*
X972432Y723369D01*
X972748Y723300D01*
G03X972899Y723327I43J195D01*
G02X973712Y723566I813J-1263D01*
G02Y720562I0J-1502D01*
G02X972447Y721254I0J1502D01*
G01X972426Y721287D01*
X972361Y721332D01*
X972045Y721401D01*
G03X971894Y721374I-43J-195D01*
G02X971081Y721135I-813J1263D01*
G02X970189Y721429I1J1502D01*
G01X970160Y721451D01*
X970091Y721470D01*
X969756Y721443D01*
X969690Y721412D01*
X969665Y721386D01*
G02X968589Y720932I-1076J1048D01*
G02Y723936I0J1502D01*
G02X969481Y723642I-1J-1502D01*
G01X969510Y723620D01*
X969579Y723601D01*
X969914Y723628D01*
X969980Y723659D01*
X970005Y723685D01*
G02X971081Y724139I1076J-1048D01*
G37*
G36*
G01X962367Y725057D02*
G02X965371I1502J0D01*
G01Y725055D01*
G02X965158Y724285I-1502J1D01*
G03X965404Y723692I343J-205D01*
G02X966544Y722234I-362J-1458D01*
G02X963540I-1502J0D01*
G01Y722236D01*
G02X963753Y723006I1502J-1D01*
G03X963507Y723599I-343J205D01*
G02X962367Y725057I362J1458D01*
G37*
G36*
G01X821582Y725638D02*
G02Y728642I0J1502D01*
G02X822978Y727693I0J-1501D01*
G01X822995Y727651D01*
X823060Y727590D01*
X823442Y727469D01*
X823530Y727481D01*
X823568Y727505D01*
G02X824387Y727748I819J-1259D01*
G02Y724744I0J-1502D01*
G02X822991Y725693I0J1501D01*
G01X822974Y725735D01*
X822909Y725796D01*
X822527Y725917D01*
X822439Y725905D01*
X822401Y725881D01*
G02X821582Y725638I-819J1259D01*
G37*
G36*
G01X560604Y733386D02*
G02X562001Y734336I1397J-552D01*
G02Y731332I0J-1502D01*
G02X560725Y732042I0J1502D01*
G03X560013Y731978I-340J-211D01*
G02X558616Y731028I-1397J552D01*
G02Y734032I0J1502D01*
G02X559892Y733322I0J-1502D01*
G03X560604Y733386I340J211D01*
G37*
G36*
G01X535585Y738396D02*
X538985D01*
G02Y734790I0J-1803D01*
G01X535585D01*
G02Y738396I0J1803D01*
G37*
G36*
G01X508324Y742838D02*
X511724D01*
G02Y739232I0J-1803D01*
G01X508324D01*
G02Y742838I0J1803D01*
G37*
G36*
G01X517731Y742874D02*
X521131D01*
G02Y739268I0J-1803D01*
G01X517731D01*
G02Y742874I0J1803D01*
G37*
G36*
G01X527585Y743396D02*
X530985D01*
G02Y739790I0J-1803D01*
G01X527585D01*
G02Y743396I0J1803D01*
G37*
G36*
G01X829002Y750000D02*
G02X827946Y748566I-1502J0D01*
G03X827733Y747962I119J-382D01*
G02X827986Y747128I-1249J-834D01*
G01Y747127D01*
G02X824982I-1502J0D01*
G02X826038Y748561I1502J0D01*
G03X826251Y749165I-119J382D01*
G02X825998Y749999I1249J834D01*
G01Y750000D01*
G02X829002I1502J0D01*
G37*
G36*
G01X513504Y754302D02*
G02X515006Y755804I0J1502D01*
G01Y755801D01*
G02X514964Y755450I-1502J2D01*
G03X515367Y754956I389J-94D01*
G02X515422Y754957I55J-1501D01*
G02X513920Y753455I0J-1502D01*
G01Y753458D01*
G02X513962Y753809I1502J-2D01*
G03X513559Y754303I-389J94D01*
G02X513504Y754302I-55J1501D01*
G37*
G36*
G01X1030635Y750994D02*
G02Y758098I0J3552D01*
G02X1033608Y756490I0J-3552D01*
G01Y756488D01*
X1033609D01*
G03X1033784Y756399I166J111D01*
G01X1034181Y756416D01*
X1034271Y756473D01*
X1034295Y756519D01*
G02X1035619Y757311I1324J-711D01*
G01X1035620D01*
G02X1036454Y757058I0J-1502D01*
G01X1036489Y757035D01*
X1036572Y757020D01*
X1036940Y757110D01*
X1037007Y757161D01*
X1037027Y757198D01*
G02X1038344Y757978I1317J-722D01*
G02Y754974I0J-1502D01*
G01X1038343D01*
G02X1037509Y755227I0J1502D01*
G01X1037474Y755250D01*
X1037391Y755265D01*
X1037023Y755175D01*
X1036956Y755124D01*
X1036936Y755087D01*
G02X1035619Y754307I-1317J722D01*
G01X1035618D01*
G02X1034793Y754554I0J1502D01*
G01X1034749Y754583D01*
X1034643Y754590D01*
X1034239Y754394D01*
X1034179Y754306D01*
X1034175Y754253D01*
G02X1030635Y750994I-3540J293D01*
G37*
G36*
G01X501495Y772260D02*
X504895D01*
G02Y768654I0J-1803D01*
G01X501495D01*
G02Y772260I0J1803D01*
G37*
G36*
G01X857498Y781000D02*
G02X860502I1502J0D01*
G02X859923Y779815I-1502J0D01*
G03X859846Y779657I123J-158D01*
G01Y779343D01*
G03X859923Y779185I200J0D01*
G02X860502Y778000I-923J-1185D01*
G02X857498I-1502J0D01*
G02X858077Y779185I1502J0D01*
G03X858154Y779343I-123J158D01*
G01Y779657D01*
G03X858077Y779815I-200J0D01*
G02X857498Y781000I923J1185D01*
G37*
G36*
G01X711720Y793312D02*
G02X714724I1502J0D01*
G02X714354Y792325I-1501J0D01*
G01Y792324D01*
X714353D01*
G03X714305Y792194I152J-130D01*
G01Y791930D01*
G03X714353Y791800I200J0D01*
G01X714354Y791799D01*
G02X714724Y790812I-1131J-987D01*
G02X711720I-1502J0D01*
G02X712090Y791799I1501J0D01*
G01Y791800D01*
X712091D01*
G03X712139Y791930I-152J130D01*
G01Y792194D01*
G03X712091Y792324I-200J0D01*
G01X712090Y792325D01*
G02X711720Y793312I1131J987D01*
G37*
G36*
G01X400023Y798294D02*
G02Y795290I0J-1502D01*
G02X398917Y795775I0J1504D01*
G03X398770Y795840I-148J-135D01*
G01X398476D01*
G03X398329Y795775I1J-200D01*
G02X397223Y795290I-1106J1019D01*
G02Y798294I0J1502D01*
G02X398329Y797809I0J-1504D01*
G03X398476Y797744I148J135D01*
G01X398770D01*
G03X398917Y797809I-1J200D01*
G02X400023Y798294I1106J-1019D01*
G37*
G36*
G01X521228Y797415D02*
G02X522697Y798604I1469J-313D01*
G02Y795600I0J-1502D01*
G02X521950Y795799I0J1502D01*
G03X521360Y795535I-199J-347D01*
G02X519891Y794346I-1469J313D01*
G02Y797350I0J1502D01*
G02X520638Y797151I0J-1502D01*
G03X521228Y797415I199J347D01*
G37*
G36*
G01X424798Y797400D02*
G02X426300Y795898I1502J0D01*
G01X426299D01*
G02X425745Y796004I0J1502D01*
G03X425198Y795606I-148J-372D01*
G01Y795605D01*
G02X425202Y795500I-1498J-110D01*
G02X423700Y797002I-1502J0D01*
G01X423701D01*
G02X424255Y796896I0J-1502D01*
G03X424802Y797294I148J372D01*
G01Y797295D01*
G02X424798Y797400I1498J110D01*
G37*
G36*
G01X520741Y806651D02*
G02Y803647I0J-1502D01*
G02X520135Y803775I1J1502D01*
G01X520095Y803793D01*
X520011Y803792D01*
X519699Y803650D01*
G03X519591Y803528I83J-182D01*
G01Y803527D01*
G02X518157Y802471I-1434J446D01*
G02Y805475I0J1502D01*
G02X518763Y805347I-1J-1502D01*
G01X518803Y805329D01*
X518887Y805330D01*
X519199Y805472D01*
G03X519307Y805594I-83J182D01*
G01Y805595D01*
G02X520741Y806651I1434J-446D01*
G37*
G36*
G01X586875Y807536D02*
G02X589879I1502J0D01*
G02X589290Y806343I-1503J0D01*
G01X589254Y806316D01*
X589213Y806237D01*
X589199Y805837D01*
X589234Y805756D01*
X589267Y805726D01*
G02X589774Y804601I-995J-1125D01*
G02X589137Y803373I-1502J0D01*
G03X589052Y803212I115J-164D01*
G01X589047Y802888D01*
G03X589128Y802725I200J-2D01*
G02X589733Y801520I-898J-1205D01*
G02X586729I-1502J0D01*
G02X587366Y802748I1502J0D01*
G03X587451Y802909I-115J164D01*
G01X587456Y803233D01*
G03X587375Y803396I-200J2D01*
G02X586770Y804601I898J1205D01*
G02X587359Y805794I1503J0D01*
G01X587395Y805821D01*
X587436Y805900D01*
X587450Y806300D01*
X587415Y806381D01*
X587382Y806411D01*
G02X586875Y807536I995J1125D01*
G37*
G36*
G01X381631Y812645D02*
G02Y815649I0J1502D01*
G02X382843Y815035I0J-1503D01*
G01X382870Y814997D01*
X382953Y814954D01*
X383368Y814948D01*
X383452Y814988D01*
X383481Y815026D01*
G02X384666Y815605I1185J-923D01*
G02X386055Y814674I0J-1502D01*
G01Y814673D01*
G03X386215Y814552I184J78D01*
G01X386563Y814509D01*
G03X386747Y814588I24J199D01*
G01X386748Y814589D01*
G02X387958Y815202I1210J-888D01*
G02Y812198I0J-1502D01*
G02X386569Y813129I0J1502D01*
G01Y813130D01*
G03X386409Y813251I-184J-78D01*
G01X386061Y813294D01*
G03X385877Y813215I-24J-199D01*
G01X385876Y813214D01*
G02X384666Y812601I-1210J888D01*
G02X383454Y813215I0J1503D01*
G01X383427Y813253D01*
X383344Y813296D01*
X382929Y813302D01*
X382845Y813262D01*
X382816Y813224D01*
G02X381631Y812645I-1185J923D01*
G37*
G36*
G01X72847Y824718D02*
G02X75851I1502J0D01*
G02X75366Y823612I-1504J0D01*
G03X75301Y823465I135J-148D01*
G01Y823171D01*
G03X75366Y823024I200J1D01*
G02X75851Y821918I-1019J-1106D01*
G02X72847I-1502J0D01*
G02X73332Y823024I1504J0D01*
G03X73397Y823171I-135J148D01*
G01Y823465D01*
G03X73332Y823612I-200J-1D01*
G02X72847Y824718I1019J1106D01*
G37*
G36*
G01X733680Y830479D02*
G02Y827475I0J-1502D01*
G02X732594Y827940I0J1501D01*
G01X732593Y827941D01*
X732564Y827971D01*
X732488Y828002D01*
X732108Y827995D01*
X732033Y827960D01*
X732005Y827929D01*
G02X730880Y827422I-1125J995D01*
G02Y830426I0J1502D01*
G02X731966Y829961I0J-1501D01*
G01X731967Y829960D01*
X731996Y829930D01*
X732072Y829899D01*
X732452Y829906D01*
X732527Y829941D01*
X732555Y829972D01*
G02X733680Y830479I1125J-995D01*
G37*
G36*
G01X546855Y828447D02*
G02Y831451I0J1502D01*
G02X548159Y830695I0J-1503D01*
G03X548838Y830671I347J199D01*
G02X550087Y831338I1249J-836D01*
G02Y828334I0J-1502D01*
G02X548783Y829090I0J1503D01*
G03X548104Y829114I-347J-199D01*
G02X546855Y828447I-1249J836D01*
G37*
G36*
G01X250803Y831018D02*
G02X253807I1502J0D01*
G02X253286Y829881I-1501J0D01*
G01X253245Y829846D01*
X253210Y829748D01*
X253279Y829356D01*
G03X253403Y829204I197J34D01*
G01X253404D01*
G02X254209Y828682I-825J-2154D01*
G01X256920Y825971D01*
G02X257596Y824340I-1631J-1632D01*
G02X255289Y822034I-2307J1D01*
G01X255288D01*
G02X253658Y822709I0J2306D01*
G01X251682Y824685D01*
G03X251540Y824744I-142J-141D01*
G01X251240D01*
G03X251090Y824676I0J-200D01*
G01X250892Y824451D01*
G03X250844Y824295I150J-132D01*
G01Y824294D01*
G02X250862Y824003I-2288J-288D01*
G01Y821564D01*
G03X251020Y821368I200J0D01*
G02X252036Y820586I-321J-1467D01*
G03X252211Y820477I178J91D01*
G01X252563Y820472D01*
G03X252742Y820576I4J200D01*
G02X254058Y821353I1316J-726D01*
G02Y818349I0J-1502D01*
G02X252722Y819165I0J1502D01*
G03X252547Y819274I-178J-91D01*
G01X252195Y819279D01*
G03X252016Y819175I-4J-200D01*
G02X251020Y818432I-1316J725D01*
G03X250862Y818236I42J-196D01*
G01Y815254D01*
G02X250187Y813624I-2306J0D01*
G01X249691Y813128D01*
X249679Y812982D01*
X249723Y812922D01*
G02X250008Y812042I-1216J-880D01*
G02X248506Y810540I-1502J0D01*
G02X248034Y810617I3J1502D01*
G01X248032D01*
G03X247853Y810589I-62J-190D01*
G01X247589Y810399D01*
G03X247506Y810237I117J-162D01*
G01Y730799D01*
G02X246831Y729169I-2306J0D01*
G01X219565Y701904D01*
G03X219506Y701762I141J-142D01*
G01Y631619D01*
G03X219578Y631465I200J0D01*
G01X219850Y631239D01*
X219936Y631217D01*
X219980Y631226D01*
G02X220255Y631251I273J-1477D01*
G02Y628247I0J-1502D01*
G02X219980Y628272I-2J1502D01*
G01X219936Y628281D01*
X219850Y628259D01*
X219578Y628033D01*
G03X219506Y627879I128J-154D01*
G01Y619783D01*
G03X219581Y619627I200J0D01*
G01X219863Y619403D01*
X219951Y619383D01*
X219996Y619394D01*
G02X220330Y619432I336J-1464D01*
G01X220333D01*
G02Y616428I0J-1502D01*
G01X220330D01*
G02X219996Y616466I2J1502D01*
G01X219951Y616477D01*
X219863Y616457D01*
X219581Y616233D01*
G03X219506Y616077I125J-156D01*
G01Y580299D01*
G02X218831Y578669I-2306J0D01*
G01X214247Y574086D01*
G03X214188Y573944I141J-142D01*
G01Y564381D01*
G02X213513Y562751I-2306J0D01*
G01X208048Y557286D01*
G02X206417Y556610I-1632J1631D01*
G01X204674D01*
G02X202368Y558917I1J2307D01*
G02X202676Y560068I2305J0D01*
G03Y560268I-173J100D01*
G02X202368Y561420I1998J1151D01*
G02X202390Y561737I2306J-1D01*
G01Y561740D01*
G03X202343Y561897I-198J26D01*
G01X202144Y562125D01*
G03X201993Y562194I-151J-131D01*
G01X199154D01*
G02X198232Y562576I1J1306D01*
G01X193519Y567289D01*
G03X193377Y567348I-142J-141D01*
G01X186179D01*
G03X186037Y567289I0J-200D01*
G01X173965Y555218D01*
G03X173907Y555062I141J-141D01*
G01X173929Y554759D01*
G03X174009Y554613I200J15D01*
G01X174010D01*
G02X174102Y554539I-895J-1206D01*
G01X174103Y554538D01*
G03X174233Y554490I130J152D01*
G01X174497D01*
G03X174627Y554538I0J200D01*
G01X174628Y554539D01*
G02X175615Y554909I987J-1131D01*
G02X177117Y553407I0J-1502D01*
G02X176747Y552420I-1501J0D01*
G01Y552419D01*
X176746D01*
G03X176698Y552289I152J-130D01*
G01Y552025D01*
G03X176746Y551895I200J0D01*
G01X176747Y551894D01*
G02X177117Y550907I-1131J-987D01*
G02X175615Y549405I-1502J0D01*
G02X174628Y549775I0J1501D01*
G01X174627D01*
Y549776D01*
G03X174497Y549824I-130J-152D01*
G01X174233D01*
G03X174103Y549776I0J-200D01*
G01X174102Y549775D01*
G02X173115Y549405I-987J1131D01*
G02X171613Y550907I0J1502D01*
G02X171983Y551894I1501J0D01*
G01Y551895D01*
X171984D01*
G03X172032Y552025I-152J130D01*
G01Y552289D01*
G03X171984Y552419I-200J0D01*
G01X171983Y552420D01*
G02X171909Y552512I1132J987D01*
G01Y552513D01*
G03X171763Y552593I-161J-120D01*
G01X171460Y552615D01*
G03X171304Y552557I-15J-199D01*
G01X167575Y548828D01*
G03X167516Y548686I141J-142D01*
G01Y479543D01*
G02X167134Y478621I-1306J1D01*
G01X149031Y460518D01*
G03X148973Y460362I141J-141D01*
G01X148998Y460017D01*
X149040Y459940D01*
X149074Y459915D01*
G02X149678Y458711I-898J-1204D01*
G02X149418Y457867I-1502J1D01*
G01Y457866D01*
X149393Y457830D01*
X149379Y457746D01*
X149483Y457365D01*
X149539Y457299D01*
X149579Y457280D01*
G02X150442Y455921I-639J-1359D01*
G01Y455918D01*
G02X150418Y455652I-1502J1D01*
G01X150410Y455610D01*
X150431Y455527D01*
X150670Y455224D01*
X150746Y455184D01*
X150789Y455182D01*
G02X152205Y453682I-86J-1500D01*
G02X149201I-1502J0D01*
G01Y453685D01*
G02X149225Y453951I1502J-1D01*
G01X149233Y453993D01*
X149212Y454076D01*
X148973Y454379D01*
X148897Y454419D01*
X148854Y454421D01*
G02X148339Y454544I86J1500D01*
G01X148293Y454564D01*
X148192Y454556D01*
X147870Y454345D01*
G03X147780Y454178I110J-167D01*
G01Y449831D01*
G03X147839Y449689I200J0D01*
G01X155583Y441945D01*
G02X155966Y441021I-923J-924D01*
G01Y385198D01*
G02X155583Y384274I-1306J0D01*
G01X149544Y378235D01*
G03X149495Y378155I141J-142D01*
G01Y378154D01*
G02X148061Y377098I-1434J446D01*
G02X146559Y378600I0J1502D01*
G02X147614Y380034I1502J0D01*
G01X147616D01*
G03X147696Y380083I-62J190D01*
G01X148051Y380438D01*
G03X148100Y380642I-141J142D01*
G01X147972Y381034D01*
X147886Y381107D01*
X147830Y381116D01*
G02X146559Y382600I231J1484D01*
G02X148061Y384102I1502J0D01*
G02X149545Y382831I0J-1502D01*
G01X149554Y382775D01*
X149627Y382689D01*
X150019Y382561D01*
G03X150223Y382610I62J190D01*
G01X153293Y385680D01*
G03X153352Y385822I-141J142D01*
G01Y440397D01*
G03X153293Y440539I-200J0D01*
G01X145549Y448283D01*
G02X145166Y449207I923J924D01*
G01Y457008D01*
G02X145167Y457052I1307J-8D01*
G01X145056Y457198D01*
G03X144953Y457270I-160J-120D01*
G02X143874Y458711I423J1441D01*
G02X144929Y460145I1502J0D01*
G01X144931D01*
G03X145011Y460194I-62J190D01*
G01X146634Y461816D01*
G03X146692Y461970I-141J141D01*
G01X146671Y462313D01*
X146631Y462389D01*
X146597Y462415D01*
G02X146018Y463600I923J1185D01*
G02X147520Y465102I1502J0D01*
G02X148705Y464523I0J-1502D01*
G01X148731Y464489D01*
X148807Y464449D01*
X149150Y464428D01*
G03X149304Y464486I13J199D01*
G01X164845Y480027D01*
G03X164904Y480169I-141J142D01*
G01Y549312D01*
G02X165286Y550234I1306J-1D01*
G01X184631Y569579D01*
G02X185555Y569962I924J-923D01*
G01X194001D01*
G02X194925Y569579I0J-1306D01*
G01X199638Y564865D01*
G03X199780Y564806I142J141D01*
G01X204176D01*
G03X204318Y564865I0J200D01*
G01X206185Y566732D01*
G03X206244Y566874I-141J142D01*
G01Y576237D01*
G03X206178Y576386I-200J1D01*
G01X205959Y576585D01*
G03X205806Y576636I-134J-148D01*
G02X205685Y576630I-125J1301D01*
G01X201285D01*
G03X201196Y576609I0J-200D01*
G01X201194Y576608D01*
G02X200495Y576435I-700J1329D01*
G02Y579439I0J1502D01*
G02X201192Y579267I-1J-1502D01*
G03X201196Y579265I91J178D01*
G01X201217Y579254D01*
X201261Y579244D01*
X205061D01*
G03X205203Y579303I0J200D01*
G01X210225Y584325D01*
G03X210284Y584467I-141J142D01*
G01Y594196D01*
G03X210158Y594382I-200J0D01*
G01X209755Y594542D01*
X209635Y594515D01*
X209593Y594470D01*
G02X208500Y593998I-1093J1030D01*
G02Y597002I0J1502D01*
G02X209593Y596530I0J-1502D01*
G01X209635Y596485D01*
X209755Y596458D01*
X210158Y596618D01*
G03X210284Y596804I-74J186D01*
G01Y608314D01*
G03X210195Y608480I-200J0D01*
G01X209877Y608693D01*
X209777Y608703D01*
X209732Y608684D01*
G02X209158Y608570I-574J1388D01*
G02Y611574I0J1502D01*
G02X209732Y611460I0J-1502D01*
G01X209777Y611441D01*
X209877Y611451D01*
X210195Y611664D01*
G03X210284Y611830I-111J166D01*
G01Y614587D01*
G03X210192Y614755I-200J0D01*
G01X209909Y614937D01*
G03X209719Y614951I-108J-168D01*
G01X209718D01*
G02X209094Y614815I-625J1366D01*
G02Y617819I0J1502D01*
G02X209718Y617683I-1J-1502D01*
G01X209719D01*
G03X209909Y617697I82J182D01*
G01X210192Y617879D01*
G03X210284Y618047I-108J168D01*
G01Y620245D01*
G03X210161Y620430I-200J0D01*
G01X209763Y620595D01*
X209644Y620571D01*
X209602Y620529D01*
G02X208540Y620089I-1062J1062D01*
G02Y623093I0J1502D01*
G02X209602Y622653I0J-1502D01*
G01X209644Y622611D01*
X209763Y622587D01*
X210161Y622752D01*
G03X210284Y622937I-77J185D01*
G01Y662660D01*
G03X210225Y662802I-200J0D01*
G01X205576Y667451D01*
G03X205496Y667500I-142J-141D01*
G01X205495D01*
G02X204439Y668934I446J1434D01*
G02X205941Y670436I1502J0D01*
G02X207375Y669381I0J-1502D01*
G01Y669379D01*
G03X207424Y669299I190J62D01*
G01X211553Y665170D01*
G03X211770Y665127I141J142D01*
G01X211827Y665150D01*
X211894Y665251D01*
Y704294D01*
G02X212276Y705216I1306J-1D01*
G01X240047Y732986D01*
G03X240106Y733128I-141J142D01*
G01Y748086D01*
G03X240047Y748228I-200J0D01*
G01X235425Y752849D01*
G03X235345Y752898I-142J-141D01*
G01X235344D01*
G02X234288Y754332I446J1434D01*
G02X235790Y755834I1502J0D01*
G02X237224Y754779I0J-1502D01*
G01Y754777D01*
G03X237273Y754697I190J62D01*
G01X240651Y751319D01*
G03X240869Y751275I142J141D01*
G01X240925Y751298D01*
X240992Y751398D01*
Y813259D01*
X240908Y813367D01*
X240841Y813384D01*
G02Y816298I362J1457D01*
G01X240908Y816315D01*
X240992Y816423D01*
Y822358D01*
G02X241668Y823989I2307J-1D01*
G01X246361Y828682D01*
G02X247992Y829358I1632J-1631D01*
G01X250881D01*
G03X251063Y829476I0J200D01*
G01X251213Y829808D01*
G03X251180Y830023I-182J82D01*
G02X250803Y831018I1125J995D01*
G37*
G36*
G01X416267Y833195D02*
G02X417769Y831693I0J-1502D01*
G02X417399Y830706I-1501J0D01*
G01Y830705D01*
X417398D01*
G03X417350Y830575I152J-130D01*
G01Y830311D01*
G03X417398Y830181I200J0D01*
G01X417399Y830180D01*
G02X417769Y829193I-1131J-987D01*
G02X416267Y827691I-1502J0D01*
G02X415280Y828061I0J1501D01*
G01X415279D01*
Y828062D01*
G03X415149Y828110I-130J-152D01*
G01X414885D01*
G03X414755Y828062I0J-200D01*
G01X414754Y828061D01*
G02X412780I-987J1131D01*
G01X412779D01*
Y828062D01*
G03X412649Y828110I-130J-152D01*
G01X412385D01*
G03X412255Y828062I0J-200D01*
G01X412254Y828061D01*
G02X411267Y827691I-987J1131D01*
G02X409765Y829193I0J1502D01*
G02X410135Y830180I1501J0D01*
G01Y830181D01*
X410136D01*
G03X410184Y830311I-152J130D01*
G01Y830575D01*
G03X410136Y830705I-200J0D01*
G01X410135Y830706D01*
G02X409765Y831693I1131J987D01*
G02X411267Y833195I1502J0D01*
G02X412254Y832825I0J-1501D01*
G01X412255D01*
Y832824D01*
G03X412385Y832776I130J152D01*
G01X412649D01*
G03X412779Y832824I0J200D01*
G01X412780Y832825D01*
G02X414754I987J-1131D01*
G01X414755D01*
Y832824D01*
G03X414885Y832776I130J152D01*
G01X415149D01*
G03X415279Y832824I0J200D01*
G01X415280Y832825D01*
G02X416267Y833195I987J-1131D01*
G37*
G36*
G01X52349Y839220D02*
G02Y836216I0J-1502D01*
G02X51125Y836848I0J1501D01*
G03X50962Y836932I-163J-116D01*
G01X50636D01*
G03X50473Y836848I0J-200D01*
G02X49249Y836216I-1224J869D01*
G02X47986Y836906I0J1501D01*
G03X47817Y836998I-168J-108D01*
G01X47481D01*
G03X47312Y836906I-1J-200D01*
G02X46049Y836216I-1263J811D01*
G02Y839220I0J1502D01*
G02X47312Y838530I0J-1501D01*
G03X47481Y838438I168J108D01*
G01X47817D01*
G03X47986Y838530I1J200D01*
G02X49249Y839220I1263J-811D01*
G02X50473Y838588I0J-1501D01*
G03X50636Y838504I163J116D01*
G01X50962D01*
G03X51125Y838588I0J200D01*
G02X52349Y839220I1224J-869D01*
G37*
G36*
G01X1052500Y839698D02*
G02Y842702I0J1502D01*
G02X1053839Y841881I0J-1502D01*
G03X1054511Y841818I356J182D01*
G02X1055700Y842402I1189J-918D01*
G02Y839398I0J-1502D01*
G02X1054361Y840219I0J1502D01*
G03X1053689Y840282I-356J-182D01*
G02X1052500Y839698I-1189J918D01*
G37*
G36*
G01X1039320Y841339D02*
G02X1042324I1502J0D01*
G02X1041921Y840315I-1502J0D01*
G01X1041891Y840283D01*
X1041864Y840202D01*
X1041897Y839860D01*
G03X1041979Y839718I199J20D01*
G02X1042602Y838500I-879J-1218D01*
G02X1042598Y838388I-1502J-2D01*
G03X1042676Y838214I199J-15D01*
G01X1042942Y838010D01*
G03X1043128Y837980I121J159D01*
G01X1043129D01*
G02X1043626Y838065I498J-1417D01*
G02X1042124Y836563I0J-1502D01*
G02X1042128Y836675I1502J2D01*
G03X1042050Y836849I-199J15D01*
G01X1041784Y837053D01*
G03X1041598Y837083I-121J-159D01*
G01X1041597D01*
G02X1041100Y836998I-498J1417D01*
G02X1039598Y838500I0J1502D01*
G02X1040001Y839524I1502J0D01*
G01X1040031Y839556D01*
X1040058Y839637D01*
X1040025Y839979D01*
G03X1039943Y840121I-199J-20D01*
G02X1039320Y841339I879J1218D01*
G37*
G36*
G01X532498Y843000D02*
G02X534000Y844502I1502J0D01*
G02X535303Y843747I0J-1502D01*
G01X535326Y843706D01*
X535404Y843654D01*
X535765Y843606D01*
G03X535933Y843663I26J198D01*
G01X536235Y843965D01*
G02X537300Y844406I1065J-1065D01*
G02X538806Y842900I0J-1506D01*
G02X538365Y841835I-1506J0D01*
G01X533865Y837335D01*
G02X532800Y836894I-1065J1065D01*
G01X526407D01*
G03X526265Y836835I0J-200D01*
G01X518092Y828662D01*
G03X518038Y828478I141J-141D01*
G01X518120Y828100D01*
X518186Y828023D01*
X518234Y828005D01*
G02X519204Y826600I-533J-1405D01*
G02X517702Y825098I-1502J0D01*
G02X516297Y826068I0J1503D01*
G01X516279Y826116D01*
X516202Y826182D01*
X515824Y826264D01*
G03X515640Y826210I-43J-195D01*
G01X515165Y825735D01*
G02X514100Y825294I-1065J1065D01*
G01X511528D01*
G03X511373Y825220I0J-200D01*
G01X511177Y824979D01*
G03X511136Y824813I155J-126D01*
G02X511167Y824512I-1471J-304D01*
G02X508163I-1502J0D01*
G02X508194Y824813I1502J-3D01*
G01X508203Y824858D01*
X508182Y824944D01*
X507957Y825220D01*
G03X507802Y825294I-155J-126D01*
G01X486907D01*
G03X486765Y825235I0J-200D01*
G01X435065Y773535D01*
G02X434000Y773094I-1065J1065D01*
G01X394169D01*
G03X394027Y773035I0J-200D01*
G01X391227Y770235D01*
G02X390162Y769794I-1065J1065D01*
G01X381692D01*
G03X381543Y769728I0J-200D01*
G01X381316Y769475D01*
X381290Y769395D01*
X381294Y769353D01*
G02X381302Y769200I-1494J-155D01*
G02X378298I-1502J0D01*
G02X378306Y769353I1502J-2D01*
G01X378310Y769395D01*
X378284Y769475D01*
X378057Y769728D01*
G03X377908Y769794I-149J-134D01*
G01X374730D01*
G03X374588Y769735I0J-200D01*
G01X374114Y769260D01*
G03X374058Y769090I142J-141D01*
G01X374111Y768724D01*
X374166Y768647D01*
X374208Y768625D01*
G02X374606Y768317I-707J-1325D01*
G03X374753Y768252I148J135D01*
G01X375047D01*
G03X375194Y768317I-1J200D01*
G02X376300Y768802I1106J-1019D01*
G02Y765798I0J-1502D01*
G02X375194Y766283I0J1504D01*
G03X375047Y766348I-148J-135D01*
G01X374753D01*
G03X374606Y766283I1J-200D01*
G02X373500Y765798I-1106J1019D01*
G02X372283Y766419I0J1503D01*
G01X372255Y766458D01*
X372170Y766502D01*
X372122D01*
G03X371922Y766302I0J-200D01*
G01Y766108D01*
G02X368908I-1507J0D01*
G01Y767692D01*
G02X369350Y768757I1507J-1D01*
G01X372958Y772365D01*
G02X374023Y772806I1065J-1065D01*
G01X389455D01*
G03X389597Y772865I0J200D01*
G01X392397Y775665D01*
G02X393462Y776106I1065J-1065D01*
G01X433293D01*
G03X433435Y776165I0J200D01*
G01X485135Y827865D01*
G02X486200Y828306I1065J-1065D01*
G01X513393D01*
G03X513535Y828365I0J200D01*
G01X524635Y839465D01*
G02X525700Y839906I1065J-1065D01*
G01X532093D01*
G03X532235Y839965I0J200D01*
G01X533337Y841067D01*
G03X533394Y841235I-141J142D01*
G01X533346Y841596D01*
X533294Y841674D01*
X533253Y841697D01*
G02X532498Y843000I747J1303D01*
G37*
G36*
G01X120935Y860775D02*
G02X123939I1502J0D01*
G02X123225Y859496I-1503J0D01*
G01X123180Y859469D01*
X123130Y859379D01*
X123129Y858986D01*
G03X123224Y858816I200J0D01*
G02X123727Y858300I-792J-1276D01*
G01Y858299D01*
G03X123898Y858201I172J102D01*
G01X124242Y858199D01*
G03X124414Y858295I1J200D01*
G02X125698Y859017I1284J-781D01*
G02Y856013I0J-1502D01*
G02X124403Y856755I0J1501D01*
G01Y856756D01*
G03X124232Y856854I-172J-102D01*
G01X123888Y856856D01*
G03X123716Y856760I-1J-200D01*
G02X122432Y856038I-1284J781D01*
G02X120930Y857540I0J1502D01*
G02X121644Y858819I1503J0D01*
G01X121689Y858846D01*
X121739Y858936D01*
X121740Y859329D01*
G03X121645Y859499I-200J0D01*
G02X120935Y860775I792J1276D01*
G37*
G36*
G01X1035185Y861291D02*
G02Y864295I0J1502D01*
G02X1036174Y863923I0J-1501D01*
G01X1036201Y863899D01*
X1036268Y863874D01*
X1036567Y863873D01*
G03X1036700Y863923I1J200D01*
G02X1037685Y864291I985J-1134D01*
G02Y861287I0J-1502D01*
G02X1036696Y861659I0J1501D01*
G01X1036669Y861683D01*
X1036602Y861708D01*
X1036303Y861709D01*
G03X1036170Y861659I-1J-200D01*
G02X1035185Y861291I-985J1134D01*
G37*
G36*
G01X101445Y877196D02*
G02X104449I1502J0D01*
G02X103624Y875855I-1502J0D01*
G01X103584Y875835D01*
X103528Y875762D01*
X103447Y875363D01*
X103470Y875274D01*
X103500Y875239D01*
G02X103857Y874267I-1145J-972D01*
G02X100853I-1502J0D01*
G02X101678Y875608I1502J0D01*
G01X101718Y875628D01*
X101774Y875701D01*
X101855Y876100D01*
X101832Y876189D01*
X101802Y876224D01*
G02X101445Y877196I1145J972D01*
G37*
G36*
G01X558385D02*
G02X561389I1502J0D01*
G02X560564Y875855I-1502J0D01*
G01X560524Y875835D01*
X560468Y875762D01*
X560387Y875363D01*
X560410Y875274D01*
X560440Y875239D01*
G02X560797Y874267I-1145J-972D01*
G02X557793I-1502J0D01*
G02X558618Y875608I1502J0D01*
G01X558658Y875628D01*
X558714Y875701D01*
X558795Y876100D01*
X558772Y876189D01*
X558742Y876224D01*
G02X558385Y877196I1145J972D01*
G37*
G36*
G01X850800Y885002D02*
G02Y881998I0J-1502D01*
G02X849815Y882366I0J1502D01*
G01X849786Y882391D01*
X849716Y882416D01*
X849365Y882403D01*
X849295Y882372D01*
X849269Y882345D01*
G02X848200Y881898I-1069J1055D01*
G02X847147Y882329I0J1502D01*
G01X847146Y882330D01*
G03X847013Y882387I-140J-143D01*
G01X846706Y882398D01*
X846635Y882373D01*
X846607Y882349D01*
G02X845633Y881990I-974J1142D01*
G02Y884994I0J1502D01*
G02X846686Y884563I0J-1502D01*
G01X846687Y884562D01*
G03X846820Y884505I140J143D01*
G01X847127Y884494D01*
X847198Y884519D01*
X847226Y884543D01*
G02X848200Y884902I974J-1142D01*
G02X849185Y884534I0J-1502D01*
G01X849214Y884509D01*
X849284Y884484D01*
X849635Y884497D01*
X849705Y884528D01*
X849731Y884555D01*
G02X850800Y885002I1069J-1055D01*
G37*
G36*
G01X810717Y883586D02*
G02X813721I1502J0D01*
G02X813378Y882631I-1501J0D01*
G01X813352Y882599D01*
X813329Y882519D01*
X813372Y882188D01*
G03X813452Y882052I199J25D01*
G01X813453D01*
G02X814077Y880834I-877J-1218D01*
G02X811073I-1502J0D01*
G02X811416Y881789I1501J0D01*
G01X811442Y881821D01*
X811465Y881901D01*
X811422Y882232D01*
G03X811342Y882368I-199J-25D01*
G01X811341D01*
G02X810717Y883586I877J1218D01*
G37*
G36*
G01X834465Y883036D02*
G02Y886040I0J1502D01*
G02X835904Y884969I0J-1502D01*
G03X836495Y884742I383J115D01*
G02X837276Y884961I781J-1283D01*
G02Y881957I0J-1502D01*
G02X835837Y883028I0J1502D01*
G03X835246Y883255I-383J-115D01*
G02X834465Y883036I-781J1283D01*
G37*
G36*
G01X1178225Y886197D02*
G02X1181229I1502J0D01*
G02X1180817Y885164I-1501J0D01*
G01X1180789Y885134D01*
X1180761Y885058D01*
X1180777Y884728D01*
G03X1180845Y884587I200J9D01*
G02X1181360Y883455I-987J-1132D01*
G02X1178356I-1502J0D01*
G02X1178768Y884488I1501J0D01*
G01X1178796Y884518D01*
X1178824Y884594D01*
X1178808Y884924D01*
G03X1178740Y885065I-200J-9D01*
G02X1178225Y886197I987J1132D01*
G37*
G36*
G01X945982Y888540D02*
X949382D01*
G02Y884936I0J-1802D01*
G01X945982D01*
G02Y888540I0J1802D01*
G37*
G36*
G01X817139Y891832D02*
G02X818549Y890849I0J-1503D01*
G01X818564Y890807D01*
X818628Y890744D01*
X818962Y890627D01*
G03X819133Y890646I66J189D01*
G02X819917Y890867I784J-1281D01*
G01X819918D01*
G02Y887863I0J-1502D01*
G02X818508Y888846I0J1503D01*
G01X818493Y888888D01*
X818429Y888951D01*
X818095Y889068D01*
G03X817924Y889049I-66J-189D01*
G02X817140Y888828I-784J1281D01*
G01X817139D01*
G02Y891832I0J1502D01*
G37*
G36*
G01X849267Y894069D02*
G02Y891065I0J-1502D01*
G01X849266D01*
G02X848999Y891089I0J1502D01*
G01X848962Y891096D01*
X848889Y891082D01*
X848630Y890920D01*
G03X848543Y890804I106J-170D01*
G02X848404Y890471I-1446J408D01*
G01X848381Y890429D01*
X848376Y890336D01*
X848543Y889955D01*
X848615Y889895D01*
X848661Y889884D01*
G02X849365Y889501I-340J-1463D01*
G03X849367Y889499I142J140D01*
G03X849500Y889444I138J145D01*
G01X849773Y889438D01*
G03X849908Y889486I5J200D01*
G01X849909Y889487D01*
G02X850900Y889861I992J-1128D01*
G02Y886857I0J-1502D01*
G02X849857Y887279I1J1502D01*
G03X849855Y887281I-142J-140D01*
G03X849722Y887336I-138J-145D01*
G01X849449Y887342D01*
G03X849314Y887294I-5J-200D01*
G01X849313Y887293D01*
G02X848322Y886919I-992J1128D01*
G02X847802Y887012I0J1502D01*
G01X847768Y887025D01*
X847695Y887024D01*
X847411Y886912D01*
G03X847307Y886817I74J-186D01*
G01X847306Y886816D01*
G02X845964Y885988I-1342J674D01*
G02Y888992I0J1502D01*
G02X846484Y888899I0J-1502D01*
G01X846518Y888886D01*
X846591Y888887D01*
X846875Y888999D01*
G03X846979Y889094I-74J186D01*
G01X846980Y889095D01*
G02X847016Y889163I1345J-669D01*
G03X847025Y889341I-174J98D01*
G01X846877Y889679D01*
X846805Y889739D01*
X846759Y889750D01*
G02X845596Y891213I339J1463D01*
G02X847098Y892715I1502J0D01*
G01X847099D01*
G02X847366Y892691I0J-1502D01*
G01X847403Y892684D01*
X847476Y892698D01*
X847735Y892860D01*
G03X847822Y892976I-106J170D01*
G02X849267Y894069I1445J-409D01*
G37*
G36*
G01X724707Y894645D02*
G02X726170Y893484I0J-1502D01*
G01X726183Y893430D01*
X726258Y893352D01*
X726702Y893229D01*
X726808Y893258D01*
X726846Y893297D01*
G02X728503Y893998I1656J-1605D01*
G02X730810Y891692I1J-2306D01*
G01Y889402D01*
G02X730512Y888269I-2307J1D01*
G03X730527Y888050I174J-98D01*
G02X730998Y886653I-1836J-1397D01*
G01Y886652D01*
G02X730323Y885022I-2306J0D01*
G01X728953Y883653D01*
G03X728894Y883511I141J-142D01*
G01Y751731D01*
G02X728219Y750101I-2306J0D01*
G01X675565Y697448D01*
G03X675506Y697306I141J-142D01*
G01Y630970D01*
G03X675630Y630785I200J0D01*
G01X675686Y630761D01*
X675804Y630785D01*
X699178Y654159D01*
G03X699227Y654363I-141J142D01*
G01X699099Y654755D01*
X699013Y654828D01*
X698957Y654837D01*
G02X697686Y656321I231J1484D01*
G02X699188Y657823I1502J0D01*
G02X700672Y656552I0J-1502D01*
G01X700681Y656496D01*
X700754Y656410D01*
X701146Y656282D01*
G03X701350Y656331I62J190D01*
G01X701732Y656713D01*
G02X702656Y657096I924J-923D01*
G01X704600D01*
G03X704689Y657117I0J200D01*
G01X704691Y657118D01*
G02X705390Y657291I700J-1329D01*
G02Y654287I0J-1502D01*
G02X704693Y654459I1J1502D01*
G03X704689Y654461I-91J-178D01*
G01X704668Y654472D01*
X704624Y654482D01*
X703280D01*
G03X703138Y654423I0J-200D01*
G01X676565Y627851D01*
G03X676506Y627709I141J-142D01*
G01Y569440D01*
G03X676565Y569298I200J0D01*
G01X678224Y567640D01*
G02X678606Y566718I-924J-923D01*
G01Y539351D01*
G03X678730Y539166I200J0D01*
G01X678786Y539142D01*
X678904Y539166D01*
X680603Y540865D01*
G03X680652Y540945I-141J142D01*
G01Y540946D01*
G02X682086Y542002I1434J-446D01*
G02X683588Y540500I0J-1502D01*
G02X682533Y539066I-1502J0D01*
G01X682531D01*
G03X682451Y539017I62J-190D01*
G01X680327Y536893D01*
G03X680268Y536751I141J-142D01*
G01Y531426D01*
G03X680391Y531241I200J0D01*
G01X680447Y531218D01*
X680565Y531241D01*
X680955Y531631D01*
G02X682585Y532306I1630J-1631D01*
G01X682586D01*
G02X684892Y530000I0J-2306D01*
G01Y529999D01*
G02X684217Y528369I-2306J0D01*
G01X683365Y527518D01*
G03X683306Y527376I141J-142D01*
G01Y469959D01*
G03X683365Y469817I200J0D01*
G01X708903Y444279D01*
X709032Y444260D01*
X709090Y444290D01*
G02X709780Y444458I690J-1334D01*
G01X709781D01*
G02X711283Y442956I0J-1502D01*
G01Y442955D01*
G02X711115Y442265I-1502J0D01*
G01X711085Y442207D01*
X711104Y442078D01*
X713229Y439954D01*
G02X713904Y438323I-1631J-1630D01*
G02X711598Y436016I-2306J-1D01*
G02X709967Y436692I1J2307D01*
G01X680609Y466050D01*
G03X680391Y466094I-142J-141D01*
G01X680335Y466071D01*
X680268Y465971D01*
Y456481D01*
G02X679938Y455614I-1307J1D01*
G03X679897Y455540I151J-132D01*
G02X678461Y454479I-1436J441D01*
G02X676959Y455981I0J1502D01*
G02X677572Y457192I1503J0D01*
G03X677654Y457353I-118J161D01*
G01Y462224D01*
G03X677531Y462409I-200J0D01*
G01X677475Y462432D01*
X677357Y462409D01*
X674886Y459938D01*
G02X673964Y459556I-923J924D01*
G01X673187D01*
G03X673045Y459497I0J-200D01*
G01X659665Y446117D01*
G03X659606Y445975I141J-142D01*
G01Y386194D01*
G03X659665Y386052I200J0D01*
G01X662126Y383592D01*
G03X662206Y383543I142J141D01*
G01X662207D01*
G02X663263Y382109I-446J-1434D01*
G02X661761Y380607I-1502J0D01*
G02X660327Y381662I0J1502D01*
G01Y381664D01*
G03X660278Y381744I-190J-62D01*
G01X657376Y384646D01*
G02X656994Y385568I924J923D01*
G01Y446601D01*
G02X657376Y447523I1306J-1D01*
G01X671639Y461786D01*
G02X672561Y462168I923J-924D01*
G01X673338D01*
G03X673480Y462227I0J200D01*
G01X674814Y463562D01*
G03X674868Y463743I-142J141D01*
G01X674791Y464120D01*
X674727Y464197D01*
X674680Y464216D01*
G02X673735Y465611I557J1395D01*
G02X675237Y467113I1502J0D01*
G02X675518Y467086I-3J-1502D01*
G01X675520D01*
X675564Y467078D01*
X675648Y467100D01*
X675921Y467325D01*
G03X675994Y467479I-127J154D01*
G01Y566092D01*
G03X675935Y566234I-200J0D01*
G01X675020Y567149D01*
G03X674738I-141J-142D01*
G01X664875Y557286D01*
G02X663244Y556610I-1632J1631D01*
G01X661760D01*
G02X659454Y558917I1J2307D01*
G02X659762Y560068I2305J0D01*
G03Y560268I-173J100D01*
G02X659454Y561419I1998J1151D01*
G01Y561420D01*
G02X661760Y563726I2306J0D01*
G01X661982D01*
G03X662124Y563785I0J200D01*
G01X668955Y570616D01*
G03X669014Y570758I-141J142D01*
G01Y581849D01*
G03X668890Y582034I-200J0D01*
G01X668834Y582058D01*
X668716Y582034D01*
X664899Y578217D01*
G02X663975Y577834I-924J923D01*
G01X659409D01*
G03X659267Y577775I0J-200D01*
G01X659064Y577572D01*
G03X659015Y577492I141J-142D01*
G01Y577491D01*
G02X657581Y576435I-1434J446D01*
G02X656079Y577937I0J1502D01*
G02X657134Y579371I1502J0D01*
G01X657136D01*
G03X657216Y579420I-62J190D01*
G01X657861Y580065D01*
G02X658785Y580448I924J-923D01*
G01X663351D01*
G03X663493Y580507I0J200D01*
G01X668043Y585057D01*
G03X668102Y585199I-141J142D01*
G01Y608851D01*
G03X667970Y609039I-200J0D01*
G01X667557Y609189D01*
X667437Y609157D01*
X667396Y609108D01*
G02X666244Y608570I-1152J964D01*
G02Y611574I0J1502D01*
G02X667396Y611036I0J-1502D01*
G01X667437Y610987D01*
X667557Y610955D01*
X667970Y611105D01*
G03X668102Y611293I-68J188D01*
G01Y702052D01*
G02X668485Y702976I1306J0D01*
G01X691113Y725603D01*
G03X691172Y725745I-141J142D01*
G01Y729849D01*
G03X691149Y729942I-200J0D01*
G02X690976Y730641I1329J700D01*
G02X693980I1502J0D01*
G02X693807Y729942I-1502J1D01*
G03X693784Y729849I177J-93D01*
G01Y726629D01*
G03X693908Y726444I200J0D01*
G01X693964Y726420D01*
X694082Y726444D01*
X722185Y754547D01*
G03X722244Y754689I-141J142D01*
G01Y819876D01*
G03X722121Y820061I-200J0D01*
G01X722065Y820084D01*
X721947Y820061D01*
X685126Y783240D01*
G03X685083Y783175I142J-141D01*
G01X640749Y676146D01*
G03X640737Y676109I183J-80D01*
G01X631586Y630104D01*
G03X631582Y630065I196J-40D01*
G01Y591252D01*
G02X631200Y590330I-1306J1D01*
G01X624663Y583793D01*
G03X624604Y583651I141J-142D01*
G01Y479546D01*
G02X624221Y478622I-1306J0D01*
G01X606117Y460518D01*
G03X606059Y460362I141J-141D01*
G01X606084Y460017D01*
X606126Y459940D01*
X606160Y459915D01*
G02X606764Y458711I-898J-1204D01*
G02X606504Y457867I-1502J1D01*
G01Y457866D01*
X606479Y457830D01*
X606465Y457746D01*
X606569Y457365D01*
X606625Y457299D01*
X606665Y457280D01*
G02X607528Y455921I-639J-1359D01*
G01Y455918D01*
G02X607504Y455652I-1502J1D01*
G01X607496Y455610D01*
X607517Y455527D01*
X607756Y455224D01*
X607832Y455184D01*
X607875Y455182D01*
G02X609291Y453682I-86J-1500D01*
G02X606287I-1502J0D01*
G01Y453685D01*
G02X606311Y453951I1502J-1D01*
G01X606319Y453993D01*
X606298Y454076D01*
X606059Y454379D01*
X605983Y454419D01*
X605940Y454421D01*
G02X605425Y454544I86J1500D01*
G01X605379Y454564D01*
X605278Y454556D01*
X604956Y454345D01*
G03X604866Y454178I110J-167D01*
G01Y449831D01*
G03X604925Y449689I200J0D01*
G01X612669Y441945D01*
G02X613052Y441021I-923J-924D01*
G01Y385198D01*
G02X612669Y384274I-1306J0D01*
G01X606630Y378235D01*
G03X606581Y378155I141J-142D01*
G01Y378154D01*
G02X605147Y377098I-1434J446D01*
G02X603645Y378600I0J1502D01*
G02X604700Y380034I1502J0D01*
G01X604702D01*
G03X604782Y380083I-62J190D01*
G01X605137Y380438D01*
G03X605186Y380642I-141J142D01*
G01X605058Y381034D01*
X604972Y381107D01*
X604916Y381116D01*
G02X603645Y382600I231J1484D01*
G02X605147Y384102I1502J0D01*
G02X606631Y382831I0J-1502D01*
G01X606640Y382775D01*
X606713Y382689D01*
X607105Y382561D01*
G03X607309Y382610I62J190D01*
G01X610379Y385680D01*
G03X610438Y385822I-141J142D01*
G01Y440397D01*
G03X610379Y440539I-200J0D01*
G01X602635Y448283D01*
G02X602252Y449207I923J924D01*
G01Y457008D01*
G02X602253Y457052I1307J-8D01*
G01X602142Y457198D01*
G03X602039Y457270I-160J-120D01*
G02X600960Y458711I423J1441D01*
G02X602015Y460145I1502J0D01*
G01X602017D01*
G03X602097Y460194I-62J190D01*
G01X603720Y461816D01*
G03X603778Y461970I-141J141D01*
G01X603757Y462313D01*
X603717Y462389D01*
X603683Y462415D01*
G02X603104Y463600I923J1185D01*
G02X604606Y465102I1502J0D01*
G02X605791Y464523I0J-1502D01*
G01X605817Y464489D01*
X605893Y464449D01*
X606236Y464428D01*
G03X606390Y464486I13J199D01*
G01X621931Y480028D01*
G03X621990Y480170I-141J142D01*
G01Y584275D01*
G02X622373Y585199I1306J0D01*
G01X628911Y591736D01*
G03X628970Y591878I-141J142D01*
G01Y630215D01*
G02X628995Y630469I1306J0D01*
G01X638204Y676764D01*
G02X638278Y677009I1281J-253D01*
G01X682783Y784452D01*
G02X683066Y784876I1207J-499D01*
G01X720941Y822750D01*
G03X721000Y822892I-141J142D01*
G01Y865681D01*
G03X720941Y865823I-200J0D01*
G01X719575Y867188D01*
G02X719192Y868112I923J924D01*
G01Y870914D01*
G02X719575Y871838I1306J0D01*
G01X721285Y873547D01*
G03X721344Y873689I-141J142D01*
G01Y891088D01*
G02X721726Y892010I1306J-1D01*
G01X723224Y893508D01*
G03X723273Y893588I-141J142D01*
G01Y893589D01*
G02X724707Y894645I1434J-446D01*
G37*
G36*
G01X527473Y898346D02*
G02X530477I1502J0D01*
G02X530305Y897649I-1502J1D01*
G03X530303Y897645I178J-91D01*
G01X530292Y897624D01*
X530282Y897580D01*
Y892606D01*
G03X530482Y892406I200J0D01*
G01X530652D01*
G03X530852Y892606I0J200D01*
G01Y894053D01*
G02X531234Y894975I1306J-1D01*
G01X531764Y895505D01*
G02X532688Y895888I924J-923D01*
G01X534158D01*
G02X535082Y895505I0J-1306D01*
G01X535612Y894975D01*
G02X535994Y894053I-924J-923D01*
G01Y892506D01*
G03X536194Y892306I200J0D01*
G01X540618D01*
G02X541540Y891924I-1J-1306D01*
G01X550386Y883078D01*
G03X550638Y883053I141J141D01*
G01X550698Y883093D01*
X550740Y883229D01*
X550624Y883506D01*
G03X550581Y883571I-185J-76D01*
G01X537705Y896448D01*
X537610Y896477D01*
X537561Y896468D01*
G02X537279Y896441I-284J1475D01*
G02Y899445I0J1502D01*
G02X538021Y899249I0J-1503D01*
G02X538055Y899250I55J-1305D01*
G01X538059D01*
G02X538981Y898867I-2J-1306D01*
G01X552641Y885207D01*
G02X552924Y884783I-924J-923D01*
G01X555333Y878967D01*
G02X555432Y878469I-1207J-499D01*
G01Y871998D01*
G03X555491Y871856I200J0D01*
G01X570182Y857165D01*
G03X570324Y857106I142J141D01*
G01X571002D01*
G02X571924Y856724I-1J-1306D01*
G01X579624Y849024D01*
G02X580006Y848102I-924J-923D01*
G01Y847424D01*
G03X580065Y847282I200J0D01*
G01X590142Y837206D01*
G02X590425Y836782I-924J-923D01*
G01X594277Y827483D01*
G02X594376Y826985I-1207J-499D01*
G01Y789565D01*
G02X594277Y789067I-1306J1D01*
G01X591491Y782342D01*
G02X591208Y781918I-1207J499D01*
G01X587395Y778105D01*
G03X587346Y778025I141J-142D01*
G01Y778024D01*
G02X585912Y776968I-1434J446D01*
G02X584410Y778470I0J1502D01*
G02X585465Y779904I1502J0D01*
G01X585467D01*
G03X585547Y779953I-62J190D01*
G01X589148Y783554D01*
G03X589191Y783619I-142J141D01*
G01X591749Y789790D01*
G03X591764Y789867I-185J76D01*
G01Y826683D01*
G03X591749Y826760I-200J1D01*
G01X588125Y835505D01*
G03X588082Y835570I-185J-76D01*
G01X578100Y845552D01*
G03X577847Y845577I-142J-141D01*
G01X577788Y845537D01*
X577747Y845401D01*
X579310Y841629D01*
G02X579410Y841129I-1207J-501D01*
G02X579310Y840628I-1307J0D01*
G01X579023Y839937D01*
G02X578997Y839880I-1201J514D01*
G01Y839878D01*
X578996D01*
G03X578993Y839717I182J-84D01*
G01X579122Y839403D01*
X579184Y839345D01*
X579224Y839331D01*
G02X579286Y839307I-441J-1230D01*
G01X579977Y839020D01*
G02X580683Y838313I-501J-1207D01*
G01X587533Y821775D01*
G02X587632Y821277I-1207J-499D01*
G01Y811478D01*
G02X587250Y810556I-1306J1D01*
G01X581999Y805305D01*
G03X581940Y805163I141J-142D01*
G01Y794291D01*
G03X581999Y794149I200J0D01*
G01X585682Y790465D01*
G03X585824Y790406I142J141D01*
G01X586799D01*
G03X586941Y790465I0J200D01*
G01X587176Y790701D01*
G03X587225Y790781I-141J142D01*
G01Y790782D01*
G02X588659Y791838I1434J-446D01*
G02X590161Y790336I0J-1502D01*
G02X589106Y788902I-1502J0D01*
G01X589104D01*
G03X589024Y788853I62J-190D01*
G01X588347Y788176D01*
G02X587425Y787794I-923J924D01*
G01X585198D01*
G02X584276Y788176I1J1306D01*
G01X579709Y792743D01*
G02X579326Y793667I923J924D01*
G01Y805787D01*
G02X579709Y806711I1306J0D01*
G01X584961Y811962D01*
G03X585020Y812104I-141J142D01*
G01Y820975D01*
G03X585005Y821052I-200J1D01*
G01X578643Y836410D01*
G03X578381Y836518I-185J-77D01*
G01X578136Y836416D01*
G02X577635Y836316I-501J1207D01*
G02X577134Y836416I0J1307D01*
G01X576442Y836703D01*
G02X575736Y837410I501J1207D01*
G01X575172Y838770D01*
G02X575072Y839270I1207J501D01*
G02X575172Y839771I1307J0D01*
G01X575459Y840462D01*
G02X576165Y841168I1207J-501D01*
G01X576413Y841271D01*
G03X576521Y841532I-77J185D01*
G01X574273Y846956D01*
G03X574230Y847021I-185J-76D01*
G01X570418Y850833D01*
G03X570276Y850892I-142J-141D01*
G01X569500D01*
G02X568576Y851275I0J1306D01*
G01X567419Y852432D01*
G03X567137I-141J-142D01*
G01X567101Y852396D01*
X567072Y852300D01*
X567082Y852252D01*
G02X567106Y852000I-1282J-249D01*
G01Y845912D01*
G03X567239Y845723I200J-1D01*
G01X567656Y845576D01*
X567778Y845611D01*
X567818Y845661D01*
G02X568990Y846223I1172J-941D01*
G02X570492Y844721I0J-1502D01*
G02X569232Y843239I-1502J0D01*
G01X569231D01*
G03X569074Y843103I33J-197D01*
G01X568965Y842764D01*
G03X569014Y842561I190J-62D01*
G01X569124Y842451D01*
G02X569506Y841529I-924J-923D01*
G01Y831224D01*
G03X569565Y831082I200J0D01*
G01X571126Y829521D01*
G03X571334Y829474I141J142D01*
G01X571675Y829594D01*
G03X571807Y829761I-67J189D01*
G02X573300Y831102I1493J-161D01*
G02X574802Y829600I0J-1502D01*
G02X573461Y828107I-1502J0D01*
G01X573403Y828100D01*
X573314Y828030D01*
X573174Y827634D01*
G03X573221Y827426I189J-67D01*
G01X574024Y826624D01*
G02X574406Y825702I-924J-923D01*
G01Y795420D01*
G03X574465Y795278I200J0D01*
G01X578763Y790981D01*
G02X579146Y790057I-923J-924D01*
G01Y782048D01*
G03X579205Y781906I200J0D01*
G01X584026Y777085D01*
G02X584408Y776163I-924J-923D01*
G01Y767929D01*
G03X584431Y767836I200J0D01*
G02X584604Y767137I-1329J-700D01*
G02X581600I-1502J0D01*
G02X581773Y767836I1502J-1D01*
G03X581796Y767929I-177J93D01*
G01Y775537D01*
G03X581737Y775679I-200J0D01*
G01X576915Y780500D01*
G02X576872Y780545I923J925D01*
G03X576734Y780611I-149J-134D01*
G01X576612Y780617D01*
G03X576460Y780559I-11J-200D01*
G01X572907Y777007D01*
G03X572848Y776865I141J-142D01*
G01Y770909D01*
G03X572907Y770767I200J0D01*
G01X578636Y765039D01*
G03X578716Y764990I142J141D01*
G01X578717D01*
G02X579773Y763556I-446J-1434D01*
G02X578271Y762054I-1502J0D01*
G02X576837Y763109I0J1502D01*
G01Y763111D01*
G03X576788Y763191I-190J-62D01*
G01X570618Y769361D01*
G02X570236Y770283I924J923D01*
G01Y777491D01*
G02X570618Y778413I1306J-1D01*
G01X574317Y782111D01*
G03X574376Y782253I-141J142D01*
G01Y788195D01*
G03X574317Y788337I-200J0D01*
G01X569576Y793077D01*
G02X569194Y793999I924J923D01*
G01Y801561D01*
G03X569078Y801743I-200J0D01*
G01X568694Y801919D01*
X568579Y801903D01*
X568534Y801865D01*
G02X567560Y801506I-975J1143D01*
G01X567559D01*
G02Y804510I0J1502D01*
G01X567560D01*
G02X568534Y804151I-1J-1502D01*
G01X568579Y804113D01*
X568694Y804097D01*
X569078Y804273D01*
G03X569194Y804455I-84J182D01*
G01Y816876D01*
G03X569135Y817018I-200J0D01*
G01X563376Y822776D01*
G02X562994Y823698I924J923D01*
G01Y828102D01*
G02X563376Y829024I1306J-1D01*
G01X564439Y830086D01*
G03X564498Y830228I-141J142D01*
G01Y840180D01*
G03X564439Y840322I-200J0D01*
G01X562656Y842104D01*
G02X562274Y843026I924J923D01*
G01Y850095D01*
G03X562215Y850237I-200J0D01*
G01X553827Y858624D01*
G03X553545I-141J-142D01*
G01X549527Y854605D01*
G02X548603Y854222I-924J923D01*
G01X547691D01*
G02X546767Y854605I0J1306D01*
G01X545646Y855726D01*
G02X545264Y856648I924J923D01*
G01Y857341D01*
G03X545140Y857526I-200J0D01*
G01X545084Y857550D01*
X544966Y857526D01*
X543343Y855903D01*
G02X542419Y855520I-924J923D01*
G01X540873D01*
G02X539949Y855903I0J1306D01*
G01X532544Y863308D01*
G02X532162Y864230I924J923D01*
G01Y877741D01*
G03X532139Y877834I-200J0D01*
G02X531966Y878533I1329J700D01*
G02X534970I1502J0D01*
G02X534797Y877834I-1502J1D01*
G03X534774Y877741I177J-93D01*
G01Y864856D01*
G03X534833Y864714I200J0D01*
G01X535172Y864376D01*
G03X535454I141J142D01*
G03X535513Y864529I-141J142D01*
G02X535510Y864606I1304J89D01*
G01Y865356D01*
G02X535893Y866280I1306J0D01*
G01X540763Y871150D01*
G03Y871432I-142J141D01*
G01X540044Y872151D01*
G02X539662Y873073I924J923D01*
G01Y877568D01*
G03X539639Y877661I-200J0D01*
G02X539466Y878360I1329J700D01*
G02X542470I1502J0D01*
G02X542297Y877661I-1502J1D01*
G03X542274Y877568I177J-93D01*
G01Y873699D01*
G03X542333Y873557I200J0D01*
G01X543301Y872590D01*
G02X543684Y871666I-923J-924D01*
G01Y870916D01*
G02X543682Y870851I-1307J8D01*
G01X543680Y870809D01*
X543710Y870730D01*
X543980Y870460D01*
X544059Y870430D01*
X544101Y870432D01*
G02X544166Y870434I73J-1305D01*
G01X544916D01*
G02X545076Y870424I-1J-1307D01*
G01X545126Y870417D01*
X545221Y870455D01*
X545470Y870753D01*
G03X545507Y870940I-154J128D01*
G02X545438Y871389I1433J450D01*
G02X548442I1502J0D01*
G02X546963Y869887I-1502J0D01*
G03X546780Y869762I2J-200D01*
G01X546643Y869421D01*
G03X546687Y869204I185J-75D01*
G01X546879Y869012D01*
G02X547262Y868088I-923J-924D01*
G01Y867397D01*
G03X547385Y867212I200J0D01*
G01X547441Y867189D01*
X547559Y867212D01*
X548258Y867911D01*
G02X549182Y868294I924J-923D01*
G01X550813D01*
G02X551065Y868269I-2J-1307D01*
G01X551113Y868259D01*
X551209Y868288D01*
X551245Y868324D01*
G03Y868606I-142J141D01*
G01X550566Y869285D01*
G02X550184Y870207I924J923D01*
G01Y877698D01*
G03X550169Y877775I-200J1D01*
G01X548891Y880855D01*
G03X548848Y880920I-185J-76D01*
G01X540134Y889635D01*
G03X539992Y889694I-142J-141D01*
G01X539892D01*
G03X539710Y889576I0J-200D01*
G01X539560Y889243D01*
G03X539593Y889028I182J-82D01*
G02X539970Y888033I-1125J-995D01*
G02X536966I-1502J0D01*
G02X537343Y889028I1502J0D01*
G03X537376Y889243I-149J133D01*
G01X537226Y889576D01*
G03X537044Y889694I-182J-82D01*
G01X535276D01*
G02X534354Y890076I1J1306D01*
G01X533764Y890666D01*
G02X533716Y890717I927J921D01*
G01X533688Y890749D01*
X533611Y890783D01*
X533272Y890785D01*
G03X533123Y890719I0J-200D01*
G02X533082Y890676I-966J880D01*
G01X532582Y890176D01*
G02X532212Y889917I-923J925D01*
G01X532169Y889897D01*
X532111Y889822D01*
X532038Y889460D01*
G03X532085Y889287I196J-40D01*
G02X532470Y888283I-1117J-1004D01*
G02X529466I-1502J0D01*
G02X530010Y889440I1502J0D01*
G01X530044Y889469D01*
X530082Y889549D01*
Y889594D01*
G03X529882Y889794I-200J0D01*
G01X529473D01*
G02X528551Y890176I1J1306D01*
G01X528051Y890676D01*
G02X527668Y891600I923J924D01*
G01Y897556D01*
G03X527647Y897645I-200J0D01*
G01X527646Y897647D01*
G02X527473Y898346I1329J700D01*
G37*
G36*
G01X841813Y916612D02*
G02X843315Y915110I1502J0D01*
G01X843314D01*
G02X843110Y915124I1J1502D01*
G03X842680Y914587I-55J-396D01*
G02X842776Y914060I-1406J-528D01*
G02X841274Y915562I-1502J0D01*
G01X841275D01*
G02X841479Y915548I-1J-1502D01*
G03X841909Y916085I55J396D01*
G02X841813Y916612I1406J528D01*
G37*
G36*
G01X835407Y916618D02*
G02X838411I1502J0D01*
G02X838005Y915591I-1502J0D01*
G01X837979Y915564D01*
X837951Y915493D01*
Y915143D01*
X837979Y915072D01*
X838005Y915045D01*
G02X838411Y914018I-1096J-1027D01*
G02X835407I-1502J0D01*
G02X835813Y915045I1502J0D01*
G01X835839Y915072D01*
X835867Y915143D01*
Y915493D01*
X835839Y915564D01*
X835813Y915591D01*
G02X835407Y916618I1096J1027D01*
G37*
G36*
G01X829555Y916745D02*
G02X832559I1502J0D01*
G02X831494Y915308I-1502J0D01*
G01X831453Y915295D01*
X831391Y915241D01*
X831245Y914936D01*
G03X831240Y914775I180J-86D01*
G02X831350Y914211I-1391J-564D01*
G02X828346I-1502J0D01*
G02X829411Y915648I1502J0D01*
G01X829452Y915661D01*
X829514Y915715D01*
X829660Y916020D01*
G03X829665Y916181I-180J86D01*
G02X829555Y916745I1391J564D01*
G37*
G36*
G01X399619Y932186D02*
G02X402623I1502J0D01*
G02X402253Y931199I-1501J0D01*
G01Y931198D01*
X402252D01*
G03X402204Y931068I152J-130D01*
G01Y930804D01*
G03X402252Y930674I200J0D01*
G01X402253Y930673D01*
G02X402623Y929686I-1131J-987D01*
G02X399619I-1502J0D01*
G02X399989Y930673I1501J0D01*
G01Y930674D01*
X399990D01*
G03X400038Y930804I-152J130D01*
G01Y931068D01*
G03X399990Y931198I-200J0D01*
G01X399989Y931199D01*
G02X399619Y932186I1131J987D01*
G37*
G36*
G01X407619D02*
G02X410623I1502J0D01*
G02X410253Y931199I-1501J0D01*
G01Y931198D01*
X410252D01*
G03X410204Y931068I152J-130D01*
G01Y930804D01*
G03X410252Y930674I200J0D01*
G01X410253Y930673D01*
G02X410623Y929686I-1131J-987D01*
G02X407619I-1502J0D01*
G02X407989Y930673I1501J0D01*
G01Y930674D01*
X407990D01*
G03X408038Y930804I-152J130D01*
G01Y931068D01*
G03X407990Y931198I-200J0D01*
G01X407989Y931199D01*
G02X407619Y932186I1131J987D01*
G37*
G36*
G01X415619D02*
G02X418623I1502J0D01*
G02X418253Y931199I-1501J0D01*
G01Y931198D01*
X418252D01*
G03X418204Y931068I152J-130D01*
G01Y930804D01*
G03X418252Y930674I200J0D01*
G01X418253Y930673D01*
G02X418623Y929686I-1131J-987D01*
G02X415619I-1502J0D01*
G02X415989Y930673I1501J0D01*
G01Y930674D01*
X415990D01*
G03X416038Y930804I-152J130D01*
G01Y931068D01*
G03X415990Y931198I-200J0D01*
G01X415989Y931199D01*
G02X415619Y932186I1131J987D01*
G37*
G36*
G01X423619D02*
G02X426623I1502J0D01*
G02X426253Y931199I-1501J0D01*
G01Y931198D01*
X426252D01*
G03X426204Y931068I152J-130D01*
G01Y930804D01*
G03X426252Y930674I200J0D01*
G01X426253Y930673D01*
G02X426623Y929686I-1131J-987D01*
G02X423619I-1502J0D01*
G02X423989Y930673I1501J0D01*
G01Y930674D01*
X423990D01*
G03X424038Y930804I-152J130D01*
G01Y931068D01*
G03X423990Y931198I-200J0D01*
G01X423989Y931199D01*
G02X423619Y932186I1131J987D01*
G37*
G36*
G01X1068190Y933538D02*
G02X1069685Y934893I1495J-147D01*
G02Y931889I0J-1502D01*
G02X1068963Y932074I0J1501D01*
G03X1068373Y931762I-192J-351D01*
G02X1066878Y930407I-1495J147D01*
G02Y933411I0J1502D01*
G02X1067600Y933226I0J-1501D01*
G03X1068190Y933538I192J351D01*
G37*
G36*
G01X1031517Y935822D02*
G02X1034521I1502J0D01*
G02X1034036Y934716I-1504J0D01*
G03X1033971Y934569I135J-148D01*
G01Y934275D01*
G03X1034036Y934128I200J1D01*
G02X1034521Y933022I-1019J-1106D01*
G02X1031517I-1502J0D01*
G02X1032002Y934128I1504J0D01*
G03X1032067Y934275I-135J148D01*
G01Y934569D01*
G03X1032002Y934716I-200J-1D01*
G02X1031517Y935822I1019J1106D01*
G37*
G36*
G01X589901Y938807D02*
G02X592905I1502J0D01*
G02X592420Y937701I-1504J0D01*
G03X592355Y937554I135J-148D01*
G01Y937260D01*
G03X592420Y937113I200J1D01*
G02X592905Y936007I-1019J-1106D01*
G02X589901I-1502J0D01*
G02X590386Y937113I1504J0D01*
G03X590451Y937260I-135J148D01*
G01Y937554D01*
G03X590386Y937701I-200J-1D01*
G02X589901Y938807I1019J1106D01*
G37*
G36*
G01X520146Y937739D02*
G02Y940743I0J1502D01*
G02X521399Y940069I0J-1502D01*
G03X522060Y940059I334J220D01*
G02X523289Y940697I1229J-865D01*
G02Y937693I0J-1502D01*
G02X522036Y938367I0J1502D01*
G03X521375Y938377I-334J-220D01*
G02X520146Y937739I-1229J865D01*
G37*
G36*
G01X836243Y941081D02*
G02Y938077I0J-1502D01*
G02X835232Y938468I0J1503D01*
G01X835205Y938493D01*
X835135Y938520D01*
X834791D01*
X834721Y938493D01*
X834694Y938468D01*
G02X833683Y938077I-1011J1112D01*
G02Y941081I0J1502D01*
G02X834694Y940690I0J-1503D01*
G01X834721Y940665D01*
X834791Y940638D01*
X835135D01*
X835205Y940665D01*
X835232Y940690D01*
G02X836243Y941081I1011J-1112D01*
G37*
G36*
G01X605733Y942940D02*
X609133D01*
G02Y939336I0J-1802D01*
G01X605733D01*
G02Y942940I0J1802D01*
G37*
G36*
G01X722400Y940998D02*
G02Y944002I0J1502D01*
G02X723655Y943325I0J-1502D01*
G01X723679Y943289D01*
X723749Y943244D01*
X724086Y943192D01*
G03X724243Y943235I30J198D01*
G02X725194Y943575I952J-1162D01*
G02Y940571I0J-1502D01*
G02X723939Y941248I0J1502D01*
G01X723915Y941284D01*
X723845Y941329D01*
X723508Y941381D01*
G03X723351Y941338I-30J-198D01*
G02X722400Y940998I-952J1162D01*
G37*
G36*
G01X1011019Y950324D02*
G02Y947320I0J-1502D01*
G02X1009795Y947952I0J1501D01*
G03X1009632Y948036I-163J-116D01*
G01X1009306D01*
G03X1009143Y947952I0J-200D01*
G02X1007919Y947320I-1224J869D01*
G02X1006656Y948010I0J1501D01*
G03X1006487Y948102I-168J-108D01*
G01X1006151D01*
G03X1005982Y948010I-1J-200D01*
G02X1004719Y947320I-1263J811D01*
G02Y950324I0J1502D01*
G02X1005982Y949634I0J-1501D01*
G03X1006151Y949542I168J108D01*
G01X1006487D01*
G03X1006656Y949634I1J200D01*
G02X1007919Y950324I1263J-811D01*
G02X1009143Y949692I0J-1501D01*
G03X1009306Y949608I163J116D01*
G01X1009632D01*
G03X1009795Y949692I0J200D01*
G02X1011019Y950324I1224J-869D01*
G37*
G36*
G01X836243Y950607D02*
G02Y947603I0J-1502D01*
G02X835232Y947994I0J1503D01*
G01X835205Y948019D01*
X835135Y948046D01*
X834791D01*
X834721Y948019D01*
X834694Y947994D01*
G02X833683Y947603I-1011J1112D01*
G02Y950607I0J1502D01*
G02X834694Y950216I0J-1503D01*
G01X834721Y950191D01*
X834791Y950164D01*
X835135D01*
X835205Y950191D01*
X835232Y950216D01*
G02X836243Y950607I1011J-1112D01*
G37*
G36*
G01X569403Y953309D02*
G02Y950305I0J-1502D01*
G02X568179Y950937I0J1501D01*
G03X568016Y951021I-163J-116D01*
G01X567690D01*
G03X567527Y950937I0J-200D01*
G02X566303Y950305I-1224J869D01*
G02X565040Y950995I0J1501D01*
G03X564871Y951087I-168J-108D01*
G01X564535D01*
G03X564366Y950995I-1J-200D01*
G02X563103Y950305I-1263J811D01*
G02Y953309I0J1502D01*
G02X564366Y952619I0J-1501D01*
G03X564535Y952527I168J108D01*
G01X564871D01*
G03X565040Y952619I1J200D01*
G02X566303Y953309I1263J-811D01*
G02X567527Y952677I0J-1501D01*
G03X567690Y952593I163J116D01*
G01X568016D01*
G03X568179Y952677I0J200D01*
G02X569403Y953309I1224J-869D01*
G37*
G36*
G01X473992Y951044D02*
G02Y954048I0J1502D01*
G02X475107Y953553I0J-1503D01*
G01X475131Y953526D01*
X475196Y953492D01*
X475493Y953457D01*
G03X475629Y953490I24J199D01*
G02X476475Y953751I846J-1241D01*
G02X477730Y953074I0J-1502D01*
G03X477893Y952984I167J110D01*
G01X478273Y952976D01*
X478361Y953021D01*
X478390Y953061D01*
G02X479613Y953691I1223J-872D01*
G02Y950687I0J-1502D01*
G02X478358Y951364I0J1502D01*
G03X478195Y951454I-167J-110D01*
G01X477815Y951462D01*
X477727Y951417D01*
X477698Y951377D01*
G02X476475Y950747I-1223J872D01*
G02X475360Y951242I0J1503D01*
G01X475336Y951269D01*
X475271Y951303D01*
X474974Y951338D01*
G03X474838Y951305I-24J-199D01*
G02X473992Y951044I-846J1241D01*
G37*
G36*
G01X380747Y956643D02*
G02X379584Y955180I-1502J0D01*
G03X379348Y954560I91J-389D01*
G02X379621Y953697I-1229J-864D01*
G01Y953696D01*
G02X376617I-1502J0D01*
G02X377780Y955159I1502J0D01*
G03X378016Y955779I-91J389D01*
G02X377743Y956642I1229J864D01*
G01Y956643D01*
G02X380747I1502J0D01*
G37*
G36*
G01X399173Y957966D02*
G02Y960970I0J1502D01*
G02X400404Y960328I0J-1501D01*
G03X400543Y960244I164J114D01*
G01X400879Y960201D01*
X400960Y960225D01*
X400992Y960253D01*
G02X401968Y960613I976J-1143D01*
G02X403251Y959892I0J-1502D01*
G01X403278Y959848D01*
X403366Y959797D01*
X403808Y959789D01*
X403898Y959836D01*
X403926Y959879D01*
G02X405179Y960553I1253J-828D01*
G02X406681Y959051I0J-1502D01*
G02X406110Y957872I-1503J0D01*
G01X406077Y957846D01*
X406038Y957772D01*
X406009Y957393D01*
X406037Y957315D01*
X406066Y957284D01*
G02X406473Y956256I-1095J-1028D01*
G02X404971Y954754I-1502J0D01*
G02X403851Y955255I0J1502D01*
G01X403826Y955284D01*
X403756Y955318D01*
X403442Y955343D01*
G03X403301Y955299I-15J-199D01*
G02X402354Y954963I-947J1167D01*
G02X400852Y956465I0J1502D01*
G02X401145Y957356I1501J0D01*
G01Y957357D01*
X401168Y957388D01*
X401187Y957464D01*
X401135Y957820D01*
X401094Y957889D01*
X401063Y957912D01*
G02X400737Y958251I906J1198D01*
G03X400598Y958335I-164J-114D01*
G01X400262Y958378D01*
X400181Y958354D01*
X400149Y958326D01*
G02X399173Y957966I-976J1143D01*
G37*
G36*
G01X417160Y963763D02*
G02Y960759I0J-1502D01*
G02X416133Y961165I0J1502D01*
G01X416106Y961191D01*
X416035Y961219D01*
X415685D01*
X415614Y961191D01*
X415587Y961165D01*
G02X413533I-1027J1096D01*
G01X413506Y961191D01*
X413435Y961219D01*
X413085D01*
X413014Y961191D01*
X412987Y961165D01*
G02X411960Y960759I-1027J1096D01*
G02Y963763I0J1502D01*
G02X412987Y963357I0J-1502D01*
G01X413014Y963331D01*
X413085Y963303D01*
X413435D01*
X413506Y963331D01*
X413533Y963357D01*
G02X415587I1027J-1096D01*
G01X415614Y963331D01*
X415685Y963303D01*
X416035D01*
X416106Y963331D01*
X416133Y963357D01*
G02X417160Y963763I1027J-1096D01*
G37*
G36*
G01X402674Y977684D02*
G02X405678I1502J0D01*
G02X405272Y976657I-1502J0D01*
G01X405246Y976630D01*
X405218Y976559D01*
Y976209D01*
X405246Y976138D01*
X405272Y976111D01*
G02Y974057I-1096J-1027D01*
G01X405246Y974030D01*
X405218Y973959D01*
Y973609D01*
X405246Y973538D01*
X405272Y973511D01*
G02X405678Y972484I-1096J-1027D01*
G02X405308Y971497I-1501J0D01*
G01Y971496D01*
X405307D01*
G03X405259Y971366I152J-130D01*
G01Y971102D01*
G03X405307Y970972I200J0D01*
G01X405308Y970971D01*
G02X405678Y969984I-1131J-987D01*
G02X402674I-1502J0D01*
G02X403044Y970971I1501J0D01*
G01Y970972D01*
X403045D01*
G03X403093Y971102I-152J130D01*
G01Y971366D01*
G03X403045Y971496I-200J0D01*
G01X403044Y971497D01*
G02X402674Y972484I1131J987D01*
G02X403080Y973511I1502J0D01*
G01X403106Y973538D01*
X403134Y973609D01*
Y973959D01*
X403106Y974030D01*
X403080Y974057D01*
G02Y976111I1096J1027D01*
G01X403106Y976138D01*
X403134Y976209D01*
Y976559D01*
X403106Y976630D01*
X403080Y976657D01*
G02X402674Y977684I1096J1027D01*
G37*
G36*
G01X416476Y979611D02*
G02Y976607I0J-1502D01*
G02X415449Y977013I0J1502D01*
G01X415422Y977039D01*
X415351Y977067D01*
X415001D01*
X414930Y977039D01*
X414903Y977013D01*
G02X412849I-1027J1096D01*
G01X412822Y977039D01*
X412751Y977067D01*
X412401D01*
X412330Y977039D01*
X412303Y977013D01*
G02X411276Y976607I-1027J1096D01*
G02Y979611I0J1502D01*
G02X412303Y979205I0J-1502D01*
G01X412330Y979179D01*
X412401Y979151D01*
X412751D01*
X412822Y979179D01*
X412849Y979205D01*
G02X414903I1027J-1096D01*
G01X414930Y979179D01*
X415001Y979151D01*
X415351D01*
X415422Y979179D01*
X415449Y979205D01*
G02X416476Y979611I1027J-1096D01*
G37*
G36*
G01X98334Y980330D02*
G02X101338I1502J0D01*
G02X100983Y979360I-1503J0D01*
G01X100957Y979330D01*
X100933Y979254D01*
X100962Y978893D01*
X100999Y978822D01*
X101029Y978797D01*
G02X101560Y977651I-971J-1146D01*
G02X98556I-1502J0D01*
G02X98911Y978621I1503J0D01*
G01X98937Y978651D01*
X98961Y978727D01*
X98932Y979088D01*
X98895Y979159D01*
X98865Y979184D01*
G02X98334Y980330I971J1146D01*
G37*
G36*
G01X102334D02*
G02X105338I1502J0D01*
G02X104937Y979308I-1503J0D01*
G03X104883Y979161I146J-137D01*
G01X104898Y978876D01*
G03X104965Y978736I200J10D01*
G02X105474Y977609I-993J-1127D01*
G02X102470I-1502J0D01*
G02X102871Y978631I1503J0D01*
G03X102925Y978778I-146J137D01*
G01X102910Y979063D01*
G03X102843Y979203I-200J-10D01*
G02X102334Y980330I993J1127D01*
G37*
G36*
G01X872183Y992478D02*
G02Y995482I0J1502D01*
G02X873496Y994710I0J-1503D01*
G03X874170Y994671I349J194D01*
G02X875391Y995298I1221J-875D01*
G02Y992294I0J-1502D01*
G02X874078Y993066I0J1503D01*
G03X873404Y993105I-349J-194D01*
G02X872183Y992478I-1221J875D01*
G37*
G36*
G01X592111Y1012354D02*
G02X595115I1502J0D01*
G02X594554Y1011183I-1503J0D01*
G01X594518Y1011154D01*
X594479Y1011071D01*
X594484Y1010709D01*
G03X594563Y1010552I200J2D01*
G02X595160Y1009354I-905J-1199D01*
G02X592156I-1502J0D01*
G02X592717Y1010525I1503J0D01*
G01X592753Y1010554D01*
X592792Y1010637D01*
X592787Y1010999D01*
G03X592708Y1011156I-200J-2D01*
G02X592111Y1012354I905J1199D01*
G37*
G36*
G01X552694Y1018469D02*
G02X554696Y1020470I2002J-1D01*
G02X556111Y1019884I0J-2001D01*
G01X556734Y1019261D01*
G02X557320Y1017846I-1415J-1415D01*
G01Y1011516D01*
G03X557394Y1011361I200J0D01*
G01X557671Y1011136D01*
X557759Y1011116D01*
X557803Y1011125D01*
G02X558111Y1011157I308J-1470D01*
G01X558112D01*
G02X559218Y1010672I0J-1504D01*
G03X559365Y1010607I148J135D01*
G01X559659D01*
G03X559806Y1010672I-1J200D01*
G02X560912Y1011157I1106J-1019D01*
G02Y1008153I0J-1502D01*
G02X559806Y1008638I0J1504D01*
G03X559659Y1008703I-148J-135D01*
G01X559365D01*
G03X559218Y1008638I1J-200D01*
G02X558112Y1008153I-1106J1019D01*
G01X558111D01*
G02X557803Y1008185I0J1502D01*
G01X557759Y1008194D01*
X557671Y1008174D01*
X557394Y1007949D01*
G03X557320Y1007794I126J-155D01*
G01Y1004711D01*
G02X556734Y1003296I-2001J0D01*
G01X550719Y997280D01*
G03X550660Y997138I141J-142D01*
G01Y975481D01*
G03X550719Y975339I200J0D01*
G01X553653Y972404D01*
G02X554240Y970989I-1415J-1416D01*
G01Y959102D01*
G02X550236I-2002J0D01*
G01Y970077D01*
G03X550177Y970219I-200J0D01*
G01X547243Y973154D01*
G02X546656Y974569I1415J1416D01*
G01Y998050D01*
G02X547243Y999465I2002J-1D01*
G01X553259Y1005481D01*
G03X553318Y1005623I-141J142D01*
G01Y1006167D01*
G03X552926Y1006223I-200J0D01*
G02X551485Y1005146I-1441J426D01*
G02Y1008150I0J1502D01*
G02X552616Y1007636I0J-1501D01*
G01X552658Y1007588D01*
X552777Y1007558D01*
X553188Y1007712D01*
G03X553318Y1007900I-70J187D01*
G01Y1016934D01*
G03X553261Y1017074I-200J0D01*
G02X552694Y1018469I1435J1396D01*
G37*
G36*
G01X592111Y1024954D02*
G02X595115I1502J0D01*
G02X594554Y1023783I-1503J0D01*
G01X594518Y1023754D01*
X594479Y1023671D01*
X594484Y1023309D01*
G03X594563Y1023152I200J2D01*
G02X595160Y1021954I-905J-1199D01*
G02X592156I-1502J0D01*
G02X592717Y1023125I1503J0D01*
G01X592753Y1023154D01*
X592792Y1023237D01*
X592787Y1023599D01*
G03X592708Y1023756I-200J-2D01*
G02X592111Y1024954I905J1199D01*
G37*
G36*
G01X568057Y1032174D02*
G02Y1029170I0J-1502D01*
G02X566872Y1029749I0J1502D01*
G03X566714Y1029826I-158J-123D01*
G01X566400D01*
G03X566242Y1029749I0J-200D01*
G02X565057Y1029170I-1185J923D01*
G02X563906Y1029707I0J1502D01*
G03X563745Y1029778I-153J-129D01*
G01X563383Y1029765D01*
X563302Y1029722D01*
X563275Y1029684D01*
G02X562057Y1029061I-1218J879D01*
G02X560872Y1029640I0J1502D01*
G03X560714Y1029717I-158J-123D01*
G01X560400D01*
G03X560242Y1029640I0J-200D01*
G02X559057Y1029061I-1185J923D01*
G02Y1032065I0J1502D01*
G02X560242Y1031486I0J-1502D01*
G03X560400Y1031409I158J123D01*
G01X560714D01*
G03X560872Y1031486I0J200D01*
G02X562057Y1032065I1185J-923D01*
G02X563208Y1031528I0J-1502D01*
G03X563369Y1031457I153J129D01*
G01X563731Y1031470D01*
X563812Y1031513D01*
X563839Y1031551D01*
G02X565057Y1032174I1218J-879D01*
G02X566242Y1031595I0J-1502D01*
G03X566400Y1031518I158J123D01*
G01X566714D01*
G03X566872Y1031595I0J200D01*
G02X568057Y1032174I1185J-923D01*
G37*
G36*
G01X620090Y1033862D02*
G02X623094I1502J0D01*
G02X622235Y1032504I-1503J0D01*
G03X622211Y1031794I171J-361D01*
G02X622981Y1030482I-733J-1312D01*
G02X619977I-1502J0D01*
G02X620836Y1031840I1503J0D01*
G03X620860Y1032550I-171J361D01*
G02X620090Y1033862I733J1312D01*
G37*
G36*
G01X580465Y1105091D02*
G02X583469I1502J0D01*
G02X582908Y1103920I-1503J0D01*
G01X582872Y1103891D01*
X582833Y1103808D01*
X582838Y1103446D01*
G03X582917Y1103289I200J2D01*
G02X583514Y1102091I-905J-1199D01*
G02X580510I-1502J0D01*
G02X581071Y1103262I1503J0D01*
G01X581107Y1103291D01*
X581146Y1103374D01*
X581141Y1103736D01*
G03X581062Y1103893I-200J-2D01*
G02X580465Y1105091I905J1199D01*
G37*
G36*
G01X44280Y1255138D02*
X44616D01*
X44683Y1255163D01*
X44711Y1255187D01*
G02X46685I987J-1131D01*
G01X46713Y1255163D01*
X46780Y1255138D01*
X47116D01*
X47183Y1255163D01*
X47211Y1255187D01*
G02X48198Y1255557I987J-1131D01*
G02X49700Y1254055I0J-1502D01*
G02X49330Y1253068I-1501J0D01*
G01X49306Y1253040D01*
X49281Y1252973D01*
Y1252637D01*
X49306Y1252570D01*
X49330Y1252542D01*
G02X49700Y1251555I-1131J-987D01*
G02X48198Y1250053I-1502J0D01*
G02X47211Y1250423I0J1501D01*
G01X47183Y1250447D01*
X47116Y1250472D01*
X46780D01*
X46713Y1250447D01*
X46685Y1250423D01*
G02X44711I-987J1131D01*
G01X44683Y1250447D01*
X44616Y1250472D01*
X44280D01*
X44213Y1250447D01*
X44185Y1250423D01*
G02X43198Y1250053I-987J1131D01*
G02X41696Y1251555I0J1502D01*
G02X42066Y1252542I1501J0D01*
G01X42090Y1252570D01*
X42115Y1252637D01*
Y1252973D01*
X42090Y1253040D01*
X42066Y1253068D01*
G02X41696Y1254055I1131J987D01*
G02X43198Y1255557I1502J0D01*
G02X44185Y1255187I0J-1501D01*
G01X44213Y1255163D01*
X44280Y1255138D01*
G37*
G36*
G01X198512Y1349690D02*
X201912D01*
G02Y1346684I0J-1503D01*
G01X198512D01*
G02Y1349690I0J1503D01*
G37*
G36*
G01Y1361602D02*
X201912D01*
G02Y1358596I0J-1503D01*
G01X198512D01*
G02Y1361602I0J1503D01*
G37*
G36*
G01X186272Y1349690D02*
X189672D01*
G02Y1346684I0J-1503D01*
G01X186272D01*
G02Y1349690I0J1503D01*
G37*
G36*
G01Y1361602D02*
X189672D01*
G02Y1358596I0J-1503D01*
G01X186272D01*
G02Y1361602I0J1503D01*
G37*
G36*
G01X174032Y1349690D02*
X177432D01*
G02Y1346684I0J-1503D01*
G01X174032D01*
G02Y1349690I0J1503D01*
G37*
G36*
G01Y1361602D02*
X177432D01*
G02Y1358596I0J-1503D01*
G01X174032D01*
G02Y1361602I0J1503D01*
G37*
G36*
G01X161792D02*
X165192D01*
G02Y1358596I0J-1503D01*
G01X161792D01*
G02Y1361602I0J1503D01*
G37*
G36*
G01Y1349690D02*
X165192D01*
G02Y1346684I0J-1503D01*
G01X161792D01*
G02Y1349690I0J1503D01*
G37*
G36*
G01X149552D02*
X152952D01*
G02Y1346684I0J-1503D01*
G01X149552D01*
G02Y1349690I0J1503D01*
G37*
G36*
G01Y1361602D02*
X152952D01*
G02Y1358596I0J-1503D01*
G01X149552D01*
G02Y1361602I0J1503D01*
G37*
G36*
G01X137312Y1349690D02*
X140712D01*
G02Y1346684I0J-1503D01*
G01X137312D01*
G02Y1349690I0J1503D01*
G37*
G36*
G01Y1361602D02*
X140712D01*
G02Y1358596I0J-1503D01*
G01X137312D01*
G02Y1361602I0J1503D01*
G37*
G36*
G01X125072Y1349690D02*
X128472D01*
G02Y1346684I0J-1503D01*
G01X125072D01*
G02Y1349690I0J1503D01*
G37*
G36*
G01Y1361602D02*
X128472D01*
G02Y1358596I0J-1503D01*
G01X125072D01*
G02Y1361602I0J1503D01*
G37*
G36*
G01X112832D02*
X116232D01*
G02Y1358596I0J-1503D01*
G01X112832D01*
G02Y1361602I0J1503D01*
G37*
G36*
G01Y1349690D02*
X116232D01*
G02Y1346684I0J-1503D01*
G01X112832D01*
G02Y1349690I0J1503D01*
G37*
G36*
G01X100592D02*
X103992D01*
G02Y1346684I0J-1503D01*
G01X100592D01*
G02Y1349690I0J1503D01*
G37*
G36*
G01Y1361602D02*
X103992D01*
G02Y1358596I0J-1503D01*
G01X100592D01*
G02Y1361602I0J1503D01*
G37*
G36*
G01X88352D02*
X91752D01*
G02Y1358596I0J-1503D01*
G01X88352D01*
G02Y1361602I0J1503D01*
G37*
G36*
G01Y1349690D02*
X91752D01*
G02Y1346684I0J-1503D01*
G01X88352D01*
G02Y1349690I0J1503D01*
G37*
G36*
G01X76112D02*
X79512D01*
G02Y1346684I0J-1503D01*
G01X76112D01*
G02Y1349690I0J1503D01*
G37*
G36*
G01Y1361602D02*
X79512D01*
G02Y1358596I0J-1503D01*
G01X76112D01*
G02Y1361602I0J1503D01*
G37*
G36*
G01Y1373888D02*
X79512D01*
G02Y1370882I0J-1503D01*
G01X76112D01*
G02Y1373888I0J1503D01*
G37*
G36*
G01Y1385800D02*
X79512D01*
G02Y1382794I0J-1503D01*
G01X76112D01*
G02Y1385800I0J1503D01*
G37*
G36*
G01X88352D02*
X91752D01*
G02Y1382794I0J-1503D01*
G01X88352D01*
G02Y1385800I0J1503D01*
G37*
G36*
G01X100592D02*
X103992D01*
G02Y1382794I0J-1503D01*
G01X100592D01*
G02Y1385800I0J1503D01*
G37*
G36*
G01X88352Y1373888D02*
X91752D01*
G02Y1370882I0J-1503D01*
G01X88352D01*
G02Y1373888I0J1503D01*
G37*
G36*
G01X100592D02*
X103992D01*
G02Y1370882I0J-1503D01*
G01X100592D01*
G02Y1373888I0J1503D01*
G37*
G36*
G01X112832D02*
X116232D01*
G02Y1370882I0J-1503D01*
G01X112832D01*
G02Y1373888I0J1503D01*
G37*
G36*
G01Y1385800D02*
X116232D01*
G02Y1382794I0J-1503D01*
G01X112832D01*
G02Y1385800I0J1503D01*
G37*
G36*
G01X125072D02*
X128472D01*
G02Y1382794I0J-1503D01*
G01X125072D01*
G02Y1385800I0J1503D01*
G37*
G36*
G01Y1373888D02*
X128472D01*
G02Y1370882I0J-1503D01*
G01X125072D01*
G02Y1373888I0J1503D01*
G37*
G36*
G01X137312D02*
X140712D01*
G02Y1370882I0J-1503D01*
G01X137312D01*
G02Y1373888I0J1503D01*
G37*
G36*
G01Y1385800D02*
X140712D01*
G02Y1382794I0J-1503D01*
G01X137312D01*
G02Y1385800I0J1503D01*
G37*
G36*
G01X149552D02*
X152952D01*
G02Y1382794I0J-1503D01*
G01X149552D01*
G02Y1385800I0J1503D01*
G37*
G36*
G01Y1373888D02*
X152952D01*
G02Y1370882I0J-1503D01*
G01X149552D01*
G02Y1373888I0J1503D01*
G37*
G36*
G01X161792D02*
X165192D01*
G02Y1370882I0J-1503D01*
G01X161792D01*
G02Y1373888I0J1503D01*
G37*
G36*
G01Y1385800D02*
X165192D01*
G02Y1382794I0J-1503D01*
G01X161792D01*
G02Y1385800I0J1503D01*
G37*
G36*
G01X174032Y1373888D02*
X177432D01*
G02Y1370882I0J-1503D01*
G01X174032D01*
G02Y1373888I0J1503D01*
G37*
G36*
G01Y1385800D02*
X177432D01*
G02Y1382794I0J-1503D01*
G01X174032D01*
G02Y1385800I0J1503D01*
G37*
G36*
G01X186272Y1373888D02*
X189672D01*
G02Y1370882I0J-1503D01*
G01X186272D01*
G02Y1373888I0J1503D01*
G37*
G36*
G01Y1385800D02*
X189672D01*
G02Y1382794I0J-1503D01*
G01X186272D01*
G02Y1385800I0J1503D01*
G37*
G36*
G01X198512Y1373888D02*
X201912D01*
G02Y1370882I0J-1503D01*
G01X198512D01*
G02Y1373888I0J1503D01*
G37*
G36*
G01Y1385800D02*
X201912D01*
G02Y1382794I0J-1503D01*
G01X198512D01*
G02Y1385800I0J1503D01*
G37*
G36*
G01Y1398086D02*
X201912D01*
G02Y1395080I0J-1503D01*
G01X198512D01*
G02Y1398086I0J1503D01*
G37*
G36*
G01Y1409998D02*
X201912D01*
G02Y1406992I0J-1503D01*
G01X198512D01*
G02Y1409998I0J1503D01*
G37*
G36*
G01X186272Y1398086D02*
X189672D01*
G02Y1395080I0J-1503D01*
G01X186272D01*
G02Y1398086I0J1503D01*
G37*
G36*
G01Y1409998D02*
X189672D01*
G02Y1406992I0J-1503D01*
G01X186272D01*
G02Y1409998I0J1503D01*
G37*
G36*
G01X174032Y1398086D02*
X177432D01*
G02Y1395080I0J-1503D01*
G01X174032D01*
G02Y1398086I0J1503D01*
G37*
G36*
G01Y1409998D02*
X177432D01*
G02Y1406992I0J-1503D01*
G01X174032D01*
G02Y1409998I0J1503D01*
G37*
G36*
G01X161792Y1398086D02*
X165192D01*
G02Y1395080I0J-1503D01*
G01X161792D01*
G02Y1398086I0J1503D01*
G37*
G36*
G01Y1409998D02*
X165192D01*
G02Y1406992I0J-1503D01*
G01X161792D01*
G02Y1409998I0J1503D01*
G37*
G36*
G01X149552Y1398086D02*
X152952D01*
G02Y1395080I0J-1503D01*
G01X149552D01*
G02Y1398086I0J1503D01*
G37*
G36*
G01Y1409998D02*
X152952D01*
G02Y1406992I0J-1503D01*
G01X149552D01*
G02Y1409998I0J1503D01*
G37*
G36*
G01X137312D02*
X140712D01*
G02Y1406992I0J-1503D01*
G01X137312D01*
G02Y1409998I0J1503D01*
G37*
G36*
G01Y1398086D02*
X140712D01*
G02Y1395080I0J-1503D01*
G01X137312D01*
G02Y1398086I0J1503D01*
G37*
G36*
G01X125072D02*
X128472D01*
G02Y1395080I0J-1503D01*
G01X125072D01*
G02Y1398086I0J1503D01*
G37*
G36*
G01Y1409998D02*
X128472D01*
G02Y1406992I0J-1503D01*
G01X125072D01*
G02Y1409998I0J1503D01*
G37*
G36*
G01X112832Y1398086D02*
X116232D01*
G02Y1395080I0J-1503D01*
G01X112832D01*
G02Y1398086I0J1503D01*
G37*
G36*
G01X100592D02*
X103992D01*
G02Y1395080I0J-1503D01*
G01X100592D01*
G02Y1398086I0J1503D01*
G37*
G36*
G01X112832Y1409998D02*
X116232D01*
G02Y1406992I0J-1503D01*
G01X112832D01*
G02Y1409998I0J1503D01*
G37*
G36*
G01X100592D02*
X103992D01*
G02Y1406992I0J-1503D01*
G01X100592D01*
G02Y1409998I0J1503D01*
G37*
G36*
G01X88352Y1398086D02*
X91752D01*
G02Y1395080I0J-1503D01*
G01X88352D01*
G02Y1398086I0J1503D01*
G37*
G36*
G01Y1409998D02*
X91752D01*
G02Y1406992I0J-1503D01*
G01X88352D01*
G02Y1409998I0J1503D01*
G37*
G36*
G01X26772Y1559218D02*
X20472D01*
G02Y1575428I0J8105D01*
G01X26772D01*
G02Y1559218I0J-8105D01*
G37*
G36*
G01X216125Y1441832D02*
X219525D01*
G02Y1438226I0J-1803D01*
G01X216125D01*
G02Y1441832I0J1803D01*
G37*
G36*
G01X108270Y1464825D02*
Y1465951D01*
G02X108472Y1466154I202J1D01*
G01X111292D01*
G02X111494Y1465951I-1J-203D01*
G01Y1464825D01*
G03X111522Y1464722I200J-1D01*
G02X111794Y1463741I-1640J-983D01*
G02X111522Y1462760I-1912J2D01*
G03X111494Y1462657I172J-102D01*
G01Y1459706D01*
G03X111522Y1459603I200J-1D01*
G02X111794Y1458622I-1640J-983D01*
G02X111522Y1457641I-1912J2D01*
G03X111494Y1457538I172J-102D01*
G01Y1456413D01*
G02X111292Y1456210I-202J-1D01*
G01X108472D01*
G02X108270Y1456413I1J203D01*
G01Y1457538D01*
G03X108242Y1457641I-200J1D01*
G02X107970Y1458622I1640J983D01*
G02X108242Y1459603I1912J-2D01*
G03X108270Y1459706I-172J102D01*
G01Y1462657D01*
G03X108242Y1462760I-200J1D01*
G02X107970Y1463741I1640J983D01*
G02X108242Y1464722I1912J-2D01*
G03X108270Y1464825I-172J102D01*
G37*
G36*
G01X125592D02*
Y1465951D01*
G02X125795Y1466154I203J0D01*
G01X128615D01*
G02X128818Y1465951I0J-203D01*
G01Y1464825D01*
G03X128846Y1464722I200J-1D01*
G02Y1462760I-1642J-981D01*
G03X128818Y1462657I172J-102D01*
G01Y1459706D01*
G03X128846Y1459603I200J-1D01*
G02Y1457641I-1642J-981D01*
G03X128818Y1457538I172J-102D01*
G01Y1456413D01*
G02X128615Y1456210I-203J0D01*
G01X125795D01*
G02X125592Y1456413I0J203D01*
G01Y1457538D01*
G03X125564Y1457641I-200J1D01*
G02Y1459603I1642J981D01*
G03X125592Y1459706I-172J102D01*
G01Y1462657D01*
G03X125564Y1462760I-200J1D01*
G02Y1464722I1642J981D01*
G03X125592Y1464825I-172J102D01*
G37*
G36*
G01X142916D02*
Y1465951D01*
G02X143118Y1466154I202J1D01*
G01X145938D01*
G02X146140Y1465951I-1J-203D01*
G01Y1464825D01*
G03X146168Y1464722I200J-1D01*
G02X146440Y1463741I-1640J-983D01*
G02X146168Y1462760I-1912J2D01*
G03X146140Y1462657I172J-102D01*
G01Y1459706D01*
G03X146168Y1459603I200J-1D01*
G02X146440Y1458622I-1640J-983D01*
G02X146168Y1457641I-1912J2D01*
G03X146140Y1457538I172J-102D01*
G01Y1456413D01*
G02X145938Y1456210I-202J-1D01*
G01X143118D01*
G02X142916Y1456413I1J203D01*
G01Y1457538D01*
G03X142888Y1457641I-200J1D01*
G02X142616Y1458622I1640J983D01*
G02X142888Y1459603I1912J-2D01*
G03X142916Y1459706I-172J102D01*
G01Y1462657D01*
G03X142888Y1462760I-200J1D01*
G02X142616Y1463741I1640J983D01*
G02X142888Y1464722I1912J-2D01*
G03X142916Y1464825I-172J102D01*
G37*
G36*
G01X160238D02*
Y1465951D01*
G02X160440Y1466154I202J1D01*
G01X163260D01*
G02X163462Y1465951I-1J-203D01*
G01Y1464825D01*
G03X163490Y1464722I200J-1D01*
G02X163762Y1463741I-1640J-983D01*
G02X163490Y1462760I-1912J2D01*
G03X163462Y1462657I172J-102D01*
G01Y1459706D01*
G03X163490Y1459603I200J-1D01*
G02X163762Y1458622I-1640J-983D01*
G02X163490Y1457641I-1912J2D01*
G03X163462Y1457538I172J-102D01*
G01Y1456413D01*
G02X163260Y1456210I-202J-1D01*
G01X160440D01*
G02X160238Y1456413I1J203D01*
G01Y1457538D01*
G03X160210Y1457641I-200J1D01*
G02X159938Y1458622I1640J983D01*
G02X160210Y1459603I1912J-2D01*
G03X160238Y1459706I-172J102D01*
G01Y1462657D01*
G03X160210Y1462760I-200J1D01*
G02X159938Y1463741I1640J983D01*
G02X160210Y1464722I1912J-2D01*
G03X160238Y1464825I-172J102D01*
G37*
G36*
G01X177560D02*
Y1465951D01*
G02X177763Y1466154I203J0D01*
G01X180583D01*
G02X180786Y1465951I0J-203D01*
G01Y1464825D01*
G03X180814Y1464722I200J-1D01*
G02Y1462760I-1642J-981D01*
G03X180786Y1462657I172J-102D01*
G01Y1459706D01*
G03X180814Y1459603I200J-1D01*
G02Y1457641I-1642J-981D01*
G03X180786Y1457538I172J-102D01*
G01Y1456413D01*
G02X180583Y1456210I-203J0D01*
G01X177763D01*
G02X177560Y1456413I0J203D01*
G01Y1457538D01*
G03X177532Y1457641I-200J1D01*
G02Y1459603I1642J981D01*
G03X177560Y1459706I-172J102D01*
G01Y1462657D01*
G03X177532Y1462760I-200J1D01*
G02Y1464722I1642J981D01*
G03X177560Y1464825I-172J102D01*
G37*
G36*
G01X116930Y1469155D02*
Y1470281D01*
G02X117133Y1470484I203J0D01*
G01X119953D01*
G02X120156Y1470281I0J-203D01*
G01Y1469155D01*
G03X120184Y1469052I200J-1D01*
G02Y1467090I-1642J-981D01*
G03X120156Y1466987I172J-102D01*
G01Y1464037D01*
G03X120184Y1463934I200J-1D01*
G02Y1461972I-1642J-981D01*
G03X120156Y1461869I172J-102D01*
G01Y1460743D01*
G02X119953Y1460540I-203J0D01*
G01X117133D01*
G02X116930Y1460743I0J203D01*
G01Y1461869D01*
G03X116902Y1461972I-200J1D01*
G02Y1463934I1642J981D01*
G03X116930Y1464037I-172J102D01*
G01Y1466987D01*
G03X116902Y1467090I-200J1D01*
G02Y1469052I1642J981D01*
G03X116930Y1469155I-172J102D01*
G37*
G36*
G01X134254D02*
Y1470281D01*
G02X134456Y1470484I202J1D01*
G01X137276D01*
G02X137478Y1470281I-1J-203D01*
G01Y1469155D01*
G03X137506Y1469052I200J-1D01*
G02X137778Y1468071I-1640J-983D01*
G02X137506Y1467090I-1912J2D01*
G03X137478Y1466987I172J-102D01*
G01Y1464037D01*
G03X137506Y1463934I200J-1D01*
G02X137778Y1462953I-1640J-983D01*
G02X137506Y1461972I-1912J2D01*
G03X137478Y1461869I172J-102D01*
G01Y1460743D01*
G02X137276Y1460540I-202J-1D01*
G01X134456D01*
G02X134254Y1460743I1J203D01*
G01Y1461869D01*
G03X134226Y1461972I-200J1D01*
G02X133954Y1462953I1640J983D01*
G02X134226Y1463934I1912J-2D01*
G03X134254Y1464037I-172J102D01*
G01Y1466987D01*
G03X134226Y1467090I-200J1D01*
G02X133954Y1468071I1640J983D01*
G02X134226Y1469052I1912J-2D01*
G03X134254Y1469155I-172J102D01*
G37*
G36*
G01X151576D02*
Y1470281D01*
G02X151779Y1470484I203J0D01*
G01X154599D01*
G02X154802Y1470281I0J-203D01*
G01Y1469155D01*
G03X154830Y1469052I200J-1D01*
G02Y1467090I-1642J-981D01*
G03X154802Y1466987I172J-102D01*
G01Y1464037D01*
G03X154830Y1463934I200J-1D01*
G02Y1461972I-1642J-981D01*
G03X154802Y1461869I172J-102D01*
G01Y1460743D01*
G02X154599Y1460540I-203J0D01*
G01X151779D01*
G02X151576Y1460743I0J203D01*
G01Y1461869D01*
G03X151548Y1461972I-200J1D01*
G02Y1463934I1642J981D01*
G03X151576Y1464037I-172J102D01*
G01Y1466987D01*
G03X151548Y1467090I-200J1D01*
G02Y1469052I1642J981D01*
G03X151576Y1469155I-172J102D01*
G37*
G36*
G01X168900D02*
Y1470281D01*
G02X169102Y1470484I202J1D01*
G01X171922D01*
G02X172124Y1470281I-1J-203D01*
G01Y1469155D01*
G03X172152Y1469052I200J-1D01*
G02X172424Y1468071I-1640J-983D01*
G02X172152Y1467090I-1912J2D01*
G03X172124Y1466987I172J-102D01*
G01Y1464037D01*
G03X172152Y1463934I200J-1D01*
G02X172424Y1462953I-1640J-983D01*
G02X172152Y1461972I-1912J2D01*
G03X172124Y1461869I172J-102D01*
G01Y1460743D01*
G02X171922Y1460540I-202J-1D01*
G01X169102D01*
G02X168900Y1460743I1J203D01*
G01Y1461869D01*
G03X168872Y1461972I-200J1D01*
G02X168600Y1462953I1640J983D01*
G02X168872Y1463934I1912J-2D01*
G03X168900Y1464037I-172J102D01*
G01Y1466987D01*
G03X168872Y1467090I-200J1D01*
G02X168600Y1468071I1640J983D01*
G02X168872Y1469052I1912J-2D01*
G03X168900Y1469155I-172J102D01*
G37*
G36*
G01X186222D02*
Y1470281D01*
G02X186425Y1470484I203J0D01*
G01X189245D01*
G02X189448Y1470281I0J-203D01*
G01Y1469155D01*
G03X189476Y1469052I200J-1D01*
G02Y1467090I-1642J-981D01*
G03X189448Y1466987I172J-102D01*
G01Y1464037D01*
G03X189476Y1463934I200J-1D01*
G02Y1461972I-1642J-981D01*
G03X189448Y1461869I172J-102D01*
G01Y1460743D01*
G02X189245Y1460540I-203J0D01*
G01X186425D01*
G02X186222Y1460743I0J203D01*
G01Y1461869D01*
G03X186194Y1461972I-200J1D01*
G02Y1463934I1642J981D01*
G03X186222Y1464037I-172J102D01*
G01Y1466987D01*
G03X186194Y1467090I-200J1D01*
G02Y1469052I1642J981D01*
G03X186222Y1469155I-172J102D01*
G37*
G36*
G01X108270Y1480179D02*
Y1481305D01*
G02X108472Y1481508I202J1D01*
G01X111292D01*
G02X111494Y1481305I-1J-203D01*
G01Y1480179D01*
G03X111522Y1480076I200J-1D01*
G02X111794Y1479095I-1640J-983D01*
G02X111522Y1478114I-1912J2D01*
G03X111494Y1478011I172J-102D01*
G01Y1475061D01*
G03X111522Y1474958I200J-1D01*
G02X111794Y1473977I-1640J-983D01*
G02X111522Y1472996I-1912J2D01*
G03X111494Y1472893I172J-102D01*
G01Y1471767D01*
G02X111292Y1471564I-202J-1D01*
G01X108472D01*
G02X108270Y1471767I1J203D01*
G01Y1472893D01*
G03X108242Y1472996I-200J1D01*
G02X107970Y1473977I1640J983D01*
G02X108242Y1474958I1912J-2D01*
G03X108270Y1475061I-172J102D01*
G01Y1478011D01*
G03X108242Y1478114I-200J1D01*
G02X107970Y1479095I1640J983D01*
G02X108242Y1480076I1912J-2D01*
G03X108270Y1480179I-172J102D01*
G37*
G36*
G01X125592D02*
Y1481305D01*
G02X125795Y1481508I203J0D01*
G01X128615D01*
G02X128818Y1481305I0J-203D01*
G01Y1480179D01*
G03X128846Y1480076I200J-1D01*
G02Y1478114I-1642J-981D01*
G03X128818Y1478011I172J-102D01*
G01Y1475061D01*
G03X128846Y1474958I200J-1D01*
G02Y1472996I-1642J-981D01*
G03X128818Y1472893I172J-102D01*
G01Y1471767D01*
G02X128615Y1471564I-203J0D01*
G01X125795D01*
G02X125592Y1471767I0J203D01*
G01Y1472893D01*
G03X125564Y1472996I-200J1D01*
G02Y1474958I1642J981D01*
G03X125592Y1475061I-172J102D01*
G01Y1478011D01*
G03X125564Y1478114I-200J1D01*
G02Y1480076I1642J981D01*
G03X125592Y1480179I-172J102D01*
G37*
G36*
G01X142916D02*
Y1481305D01*
G02X143118Y1481508I202J1D01*
G01X145938D01*
G02X146140Y1481305I-1J-203D01*
G01Y1480179D01*
G03X146168Y1480076I200J-1D01*
G02X146440Y1479095I-1640J-983D01*
G02X146168Y1478114I-1912J2D01*
G03X146140Y1478011I172J-102D01*
G01Y1475061D01*
G03X146168Y1474958I200J-1D01*
G02X146440Y1473977I-1640J-983D01*
G02X146168Y1472996I-1912J2D01*
G03X146140Y1472893I172J-102D01*
G01Y1471767D01*
G02X145938Y1471564I-202J-1D01*
G01X143118D01*
G02X142916Y1471767I1J203D01*
G01Y1472893D01*
G03X142888Y1472996I-200J1D01*
G02X142616Y1473977I1640J983D01*
G02X142888Y1474958I1912J-2D01*
G03X142916Y1475061I-172J102D01*
G01Y1478011D01*
G03X142888Y1478114I-200J1D01*
G02X142616Y1479095I1640J983D01*
G02X142888Y1480076I1912J-2D01*
G03X142916Y1480179I-172J102D01*
G37*
G36*
G01X160238D02*
Y1481305D01*
G02X160440Y1481508I202J1D01*
G01X163260D01*
G02X163462Y1481305I-1J-203D01*
G01Y1480179D01*
G03X163490Y1480076I200J-1D01*
G02X163762Y1479095I-1640J-983D01*
G02X163490Y1478114I-1912J2D01*
G03X163462Y1478011I172J-102D01*
G01Y1475061D01*
G03X163490Y1474958I200J-1D01*
G02X163762Y1473977I-1640J-983D01*
G02X163490Y1472996I-1912J2D01*
G03X163462Y1472893I172J-102D01*
G01Y1471767D01*
G02X163260Y1471564I-202J-1D01*
G01X160440D01*
G02X160238Y1471767I1J203D01*
G01Y1472893D01*
G03X160210Y1472996I-200J1D01*
G02X159938Y1473977I1640J983D01*
G02X160210Y1474958I1912J-2D01*
G03X160238Y1475061I-172J102D01*
G01Y1478011D01*
G03X160210Y1478114I-200J1D01*
G02X159938Y1479095I1640J983D01*
G02X160210Y1480076I1912J-2D01*
G03X160238Y1480179I-172J102D01*
G37*
G36*
G01X177560D02*
Y1481305D01*
G02X177763Y1481508I203J0D01*
G01X180583D01*
G02X180786Y1481305I0J-203D01*
G01Y1480179D01*
G03X180814Y1480076I200J-1D01*
G02Y1478114I-1642J-981D01*
G03X180786Y1478011I172J-102D01*
G01Y1475061D01*
G03X180814Y1474958I200J-1D01*
G02Y1472996I-1642J-981D01*
G03X180786Y1472893I172J-102D01*
G01Y1471767D01*
G02X180583Y1471564I-203J0D01*
G01X177763D01*
G02X177560Y1471767I0J203D01*
G01Y1472893D01*
G03X177532Y1472996I-200J1D01*
G02Y1474958I1642J981D01*
G03X177560Y1475061I-172J102D01*
G01Y1478011D01*
G03X177532Y1478114I-200J1D01*
G02Y1480076I1642J981D01*
G03X177560Y1480179I-172J102D01*
G37*
G36*
G01X116930Y1484510D02*
Y1485635D01*
G02X117133Y1485838I203J0D01*
G01X119953D01*
G02X120156Y1485635I0J-203D01*
G01Y1484510D01*
G03X120184Y1484407I200J-1D01*
G02Y1482445I-1642J-981D01*
G03X120156Y1482342I172J-102D01*
G01Y1479392D01*
G03X120184Y1479289I200J-1D01*
G02Y1477327I-1642J-981D01*
G03X120156Y1477224I172J-102D01*
G01Y1476097D01*
G02X119953Y1475894I-203J0D01*
G01X117133D01*
G02X116930Y1476097I0J203D01*
G01Y1477224D01*
G03X116902Y1477327I-200J1D01*
G02Y1479289I1642J981D01*
G03X116930Y1479392I-172J102D01*
G01Y1482342D01*
G03X116902Y1482445I-200J1D01*
G02Y1484407I1642J981D01*
G03X116930Y1484510I-172J102D01*
G37*
G36*
G01X134254D02*
Y1485635D01*
G02X134456Y1485838I202J1D01*
G01X137276D01*
G02X137478Y1485635I-1J-203D01*
G01Y1484510D01*
G03X137506Y1484407I200J-1D01*
G02X137778Y1483426I-1640J-983D01*
G02X137506Y1482445I-1912J2D01*
G03X137478Y1482342I172J-102D01*
G01Y1479392D01*
G03X137506Y1479289I200J-1D01*
G02X137778Y1478308I-1640J-983D01*
G02X137506Y1477327I-1912J2D01*
G03X137478Y1477224I172J-102D01*
G01Y1476097D01*
G02X137276Y1475894I-202J-1D01*
G01X134456D01*
G02X134254Y1476097I1J203D01*
G01Y1477224D01*
G03X134226Y1477327I-200J1D01*
G02X133954Y1478308I1640J983D01*
G02X134226Y1479289I1912J-2D01*
G03X134254Y1479392I-172J102D01*
G01Y1482342D01*
G03X134226Y1482445I-200J1D01*
G02X133954Y1483426I1640J983D01*
G02X134226Y1484407I1912J-2D01*
G03X134254Y1484510I-172J102D01*
G37*
G36*
G01X151576D02*
Y1485635D01*
G02X151779Y1485838I203J0D01*
G01X154599D01*
G02X154802Y1485635I0J-203D01*
G01Y1484510D01*
G03X154830Y1484407I200J-1D01*
G02Y1482445I-1642J-981D01*
G03X154802Y1482342I172J-102D01*
G01Y1479392D01*
G03X154830Y1479289I200J-1D01*
G02Y1477327I-1642J-981D01*
G03X154802Y1477224I172J-102D01*
G01Y1476097D01*
G02X154599Y1475894I-203J0D01*
G01X151779D01*
G02X151576Y1476097I0J203D01*
G01Y1477224D01*
G03X151548Y1477327I-200J1D01*
G02Y1479289I1642J981D01*
G03X151576Y1479392I-172J102D01*
G01Y1482342D01*
G03X151548Y1482445I-200J1D01*
G02Y1484407I1642J981D01*
G03X151576Y1484510I-172J102D01*
G37*
G36*
G01X168900D02*
Y1485635D01*
G02X169102Y1485838I202J1D01*
G01X171922D01*
G02X172124Y1485635I-1J-203D01*
G01Y1484510D01*
G03X172152Y1484407I200J-1D01*
G02X172424Y1483426I-1640J-983D01*
G02X172152Y1482445I-1912J2D01*
G03X172124Y1482342I172J-102D01*
G01Y1479392D01*
G03X172152Y1479289I200J-1D01*
G02X172424Y1478308I-1640J-983D01*
G02X172152Y1477327I-1912J2D01*
G03X172124Y1477224I172J-102D01*
G01Y1476097D01*
G02X171922Y1475894I-202J-1D01*
G01X169102D01*
G02X168900Y1476097I1J203D01*
G01Y1477224D01*
G03X168872Y1477327I-200J1D01*
G02X168600Y1478308I1640J983D01*
G02X168872Y1479289I1912J-2D01*
G03X168900Y1479392I-172J102D01*
G01Y1482342D01*
G03X168872Y1482445I-200J1D01*
G02X168600Y1483426I1640J983D01*
G02X168872Y1484407I1912J-2D01*
G03X168900Y1484510I-172J102D01*
G37*
G36*
G01X186222D02*
Y1485636D01*
G02X186425Y1485838I203J-1D01*
G01X189245D01*
G02X189448Y1485636I1J-202D01*
G01Y1484510D01*
G03X189476Y1484407I200J-1D01*
G02Y1482445I-1642J-981D01*
G03X189448Y1482342I172J-102D01*
G01Y1479392D01*
G03X189476Y1479289I200J-1D01*
G02Y1477327I-1642J-981D01*
G03X189448Y1477224I172J-102D01*
G01Y1476098D01*
G02X189245Y1475896I-203J1D01*
G01X186425D01*
G02X186222Y1476098I-1J202D01*
G01Y1477224D01*
G03X186194Y1477327I-200J1D01*
G02Y1479289I1642J981D01*
G03X186222Y1479392I-172J102D01*
G01Y1482342D01*
G03X186194Y1482445I-200J1D01*
G02Y1484407I1642J981D01*
G03X186222Y1484510I-172J102D01*
G37*
G36*
G01X219783Y1482034D02*
X222203D01*
G02X223125Y1481652I-1J-1306D01*
G01X225145Y1479632D01*
G03X225225Y1479583I142J141D01*
G01X225226D01*
G02X226282Y1478149I-446J-1434D01*
G02X224780Y1476647I-1502J0D01*
G02X223346Y1477702I0J1502D01*
G01Y1477704D01*
G03X223297Y1477784I-190J-62D01*
G01X221719Y1479363D01*
G03X221577Y1479422I-142J-141D01*
G01X220788D01*
G03X220600Y1479289I0J-200D01*
G01X220566Y1479193D01*
G03X220615Y1478983I188J-67D01*
G02X220625Y1478973I-919J-929D01*
G01X226130Y1473468D01*
G03X226210Y1473419I142J141D01*
G01X226211D01*
G02X227267Y1471985I-446J-1434D01*
G02X225765Y1470483I-1502J0D01*
G02X224331Y1471538I0J1502D01*
G01Y1471540D01*
G03X224282Y1471620I-190J-62D01*
G01X219219Y1476683D01*
G03X219077Y1476742I-142J-141D01*
G01X216857D01*
G03X216715Y1476683I0J-200D01*
G01X209365Y1469334D01*
G03X209306Y1469192I141J-142D01*
G01Y1453599D01*
G02X208924Y1452677I-1306J1D01*
G01X200523Y1444276D01*
G02X199601Y1443894I-923J924D01*
G01X126058D01*
G02X125136Y1444276I1J1306D01*
G01X118666Y1450746D01*
G03X118527Y1450805I-142J-141D01*
G01X118526D01*
G02X116631Y1452717I17J1912D01*
G02X118543Y1454629I1912J0D01*
G02X120455Y1452734I0J-1912D01*
G01Y1452733D01*
G03X120514Y1452594I200J3D01*
G01X126542Y1446565D01*
G03X126684Y1446506I142J141D01*
G01X139746D01*
G03X139931Y1446630I0J200D01*
G01X139955Y1446686D01*
X139931Y1446804D01*
X135989Y1450746D01*
G03X135850Y1450805I-142J-141D01*
G01X135849D01*
G02X133954Y1452717I17J1912D01*
G02X135866Y1454629I1912J0D01*
G02X137778Y1452734I0J-1912D01*
G01Y1452733D01*
G03X137837Y1452594I200J3D01*
G01X142065Y1448365D01*
G03X142207Y1448306I142J141D01*
G01X155269D01*
G03X155454Y1448430I0J200D01*
G01X155478Y1448486D01*
X155454Y1448604D01*
X153312Y1450746D01*
G03X153173Y1450805I-142J-141D01*
G01X153172D01*
G02X151277Y1452717I17J1912D01*
G02X153189Y1454629I1912J0D01*
G02X155101Y1452734I0J-1912D01*
G01Y1452733D01*
G03X155160Y1452594I200J3D01*
G01X157788Y1449965D01*
G03X157930Y1449906I142J141D01*
G01X170992D01*
G03X171177Y1450030I0J200D01*
G01X171201Y1450086D01*
X171177Y1450204D01*
X170635Y1450746D01*
G03X170496Y1450805I-142J-141D01*
G01X170495D01*
G02X168600Y1452717I17J1912D01*
G02X170512Y1454629I1912J0D01*
G02X172424Y1452734I0J-1912D01*
G01Y1452733D01*
G03X172482Y1452594I200J2D01*
G01X173311Y1451765D01*
G03X173453Y1451706I142J141D01*
G01X185198D01*
G03X185355Y1451782I0J200D01*
G01X185579Y1452064D01*
X185599Y1452152D01*
X185588Y1452197D01*
G02X185528Y1452717I2247J523D01*
G02X187835Y1455024I2307J0D01*
G01X194976D01*
G03X195118Y1455083I0J200D01*
G01X198035Y1457999D01*
G03X198094Y1458141I-141J142D01*
G01Y1472458D01*
G02X198769Y1474088I2306J0D01*
G01X215983Y1491302D01*
G02X217614Y1491978I1632J-1631D01*
G02X219845Y1490256I0J-2306D01*
G03X220039Y1490106I194J50D01*
G01X221107D01*
G03X221200Y1490129I0J200D01*
G02X221899Y1490302I700J-1329D01*
G02Y1487298I0J-1502D01*
G02X221200Y1487471I1J1502D01*
G03X221107Y1487494I-93J-177D01*
G01X220325D01*
G03X220183Y1487435I0J-200D01*
G01X218068Y1485319D01*
G03X218010Y1485154I141J-142D01*
G01X218053Y1484796D01*
X218103Y1484719D01*
X218142Y1484695D01*
G02X218384Y1484504I-683J-1114D01*
G01X218385Y1484503D01*
G02X219487Y1483055I-400J-1448D01*
G01Y1483054D01*
G02X219405Y1482565I-1502J1D01*
G01X219389Y1482519D01*
X219402Y1482424D01*
X219620Y1482118D01*
G03X219783Y1482034I163J116D01*
G37*
G36*
G01X108270Y1495533D02*
Y1496659D01*
G02X108472Y1496862I202J1D01*
G01X111292D01*
G02X111494Y1496659I-1J-203D01*
G01Y1495533D01*
G03X111522Y1495430I200J-1D01*
G02X111794Y1494449I-1640J-983D01*
G02X111522Y1493468I-1912J2D01*
G03X111494Y1493365I172J-102D01*
G01Y1490415D01*
G03X111522Y1490312I200J-1D01*
G02X111794Y1489331I-1640J-983D01*
G02X111522Y1488350I-1912J2D01*
G03X111494Y1488247I172J-102D01*
G01Y1487121D01*
G02X111292Y1486918I-202J-1D01*
G01X108472D01*
G02X108270Y1487121I1J203D01*
G01Y1488247D01*
G03X108242Y1488350I-200J1D01*
G02X107970Y1489331I1640J983D01*
G02X108242Y1490312I1912J-2D01*
G03X108270Y1490415I-172J102D01*
G01Y1493365D01*
G03X108242Y1493468I-200J1D01*
G02X107970Y1494449I1640J983D01*
G02X108242Y1495430I1912J-2D01*
G03X108270Y1495533I-172J102D01*
G37*
G36*
G01X125592D02*
Y1496659D01*
G02X125795Y1496862I203J0D01*
G01X128615D01*
G02X128818Y1496659I0J-203D01*
G01Y1495533D01*
G03X128846Y1495430I200J-1D01*
G02Y1493468I-1642J-981D01*
G03X128818Y1493365I172J-102D01*
G01Y1490415D01*
G03X128846Y1490312I200J-1D01*
G02Y1488350I-1642J-981D01*
G03X128818Y1488247I172J-102D01*
G01Y1487121D01*
G02X128615Y1486918I-203J0D01*
G01X125795D01*
G02X125592Y1487121I0J203D01*
G01Y1488247D01*
G03X125564Y1488350I-200J1D01*
G02Y1490312I1642J981D01*
G03X125592Y1490415I-172J102D01*
G01Y1493365D01*
G03X125564Y1493468I-200J1D01*
G02Y1495430I1642J981D01*
G03X125592Y1495533I-172J102D01*
G37*
G36*
G01X142916D02*
Y1496659D01*
G02X143118Y1496862I202J1D01*
G01X145938D01*
G02X146140Y1496659I-1J-203D01*
G01Y1495533D01*
G03X146168Y1495430I200J-1D01*
G02X146440Y1494449I-1640J-983D01*
G02X146168Y1493468I-1912J2D01*
G03X146140Y1493365I172J-102D01*
G01Y1490415D01*
G03X146168Y1490312I200J-1D01*
G02X146440Y1489331I-1640J-983D01*
G02X146168Y1488350I-1912J2D01*
G03X146140Y1488247I172J-102D01*
G01Y1487121D01*
G02X145938Y1486918I-202J-1D01*
G01X143118D01*
G02X142916Y1487121I1J203D01*
G01Y1488247D01*
G03X142888Y1488350I-200J1D01*
G02X142616Y1489331I1640J983D01*
G02X142888Y1490312I1912J-2D01*
G03X142916Y1490415I-172J102D01*
G01Y1493365D01*
G03X142888Y1493468I-200J1D01*
G02X142616Y1494449I1640J983D01*
G02X142888Y1495430I1912J-2D01*
G03X142916Y1495533I-172J102D01*
G37*
G36*
G01X160238D02*
Y1496659D01*
G02X160440Y1496862I202J1D01*
G01X163260D01*
G02X163462Y1496659I-1J-203D01*
G01Y1495533D01*
G03X163490Y1495430I200J-1D01*
G02X163762Y1494449I-1640J-983D01*
G02X163490Y1493468I-1912J2D01*
G03X163462Y1493365I172J-102D01*
G01Y1490415D01*
G03X163490Y1490312I200J-1D01*
G02X163762Y1489331I-1640J-983D01*
G02X163490Y1488350I-1912J2D01*
G03X163462Y1488247I172J-102D01*
G01Y1487121D01*
G02X163260Y1486918I-202J-1D01*
G01X160440D01*
G02X160238Y1487121I1J203D01*
G01Y1488247D01*
G03X160210Y1488350I-200J1D01*
G02X159938Y1489331I1640J983D01*
G02X160210Y1490312I1912J-2D01*
G03X160238Y1490415I-172J102D01*
G01Y1493365D01*
G03X160210Y1493468I-200J1D01*
G02X159938Y1494449I1640J983D01*
G02X160210Y1495430I1912J-2D01*
G03X160238Y1495533I-172J102D01*
G37*
G36*
G01X116930Y1499864D02*
Y1500989D01*
G02X117133Y1501192I203J0D01*
G01X119953D01*
G02X120156Y1500989I0J-203D01*
G01Y1499864D01*
G03X120184Y1499761I200J-1D01*
G02Y1497799I-1642J-981D01*
G03X120156Y1497696I172J-102D01*
G01Y1494746D01*
G03X120184Y1494643I200J-1D01*
G02Y1492681I-1642J-981D01*
G03X120156Y1492578I172J-102D01*
G01Y1491451D01*
G02X119953Y1491248I-203J0D01*
G01X117133D01*
G02X116930Y1491451I0J203D01*
G01Y1492578D01*
G03X116902Y1492681I-200J1D01*
G02Y1494643I1642J981D01*
G03X116930Y1494746I-172J102D01*
G01Y1497696D01*
G03X116902Y1497799I-200J1D01*
G02Y1499761I1642J981D01*
G03X116930Y1499864I-172J102D01*
G37*
G36*
G01X134254D02*
Y1500989D01*
G02X134456Y1501192I202J1D01*
G01X137276D01*
G02X137478Y1500989I-1J-203D01*
G01Y1499864D01*
G03X137506Y1499761I200J-1D01*
G02X137778Y1498780I-1640J-983D01*
G02X137506Y1497799I-1912J2D01*
G03X137478Y1497696I172J-102D01*
G01Y1494746D01*
G03X137506Y1494643I200J-1D01*
G02X137778Y1493662I-1640J-983D01*
G02X137506Y1492681I-1912J2D01*
G03X137478Y1492578I172J-102D01*
G01Y1491451D01*
G02X137276Y1491248I-202J-1D01*
G01X134456D01*
G02X134254Y1491451I1J203D01*
G01Y1492578D01*
G03X134226Y1492681I-200J1D01*
G02X133954Y1493662I1640J983D01*
G02X134226Y1494643I1912J-2D01*
G03X134254Y1494746I-172J102D01*
G01Y1497696D01*
G03X134226Y1497799I-200J1D01*
G02X133954Y1498780I1640J983D01*
G02X134226Y1499761I1912J-2D01*
G03X134254Y1499864I-172J102D01*
G37*
G36*
G01X151576D02*
Y1500989D01*
G02X151779Y1501192I203J0D01*
G01X154599D01*
G02X154802Y1500989I0J-203D01*
G01Y1499864D01*
G03X154830Y1499761I200J-1D01*
G02Y1497799I-1642J-981D01*
G03X154802Y1497696I172J-102D01*
G01Y1494746D01*
G03X154830Y1494643I200J-1D01*
G02Y1492681I-1642J-981D01*
G03X154802Y1492578I172J-102D01*
G01Y1491451D01*
G02X154599Y1491248I-203J0D01*
G01X151779D01*
G02X151576Y1491451I0J203D01*
G01Y1492578D01*
G03X151548Y1492681I-200J1D01*
G02Y1494643I1642J981D01*
G03X151576Y1494746I-172J102D01*
G01Y1497696D01*
G03X151548Y1497799I-200J1D01*
G02Y1499761I1642J981D01*
G03X151576Y1499864I-172J102D01*
G37*
G36*
G01X168900D02*
Y1500989D01*
G02X169102Y1501192I202J1D01*
G01X171922D01*
G02X172124Y1500989I-1J-203D01*
G01Y1499864D01*
G03X172152Y1499761I200J-1D01*
G02X172424Y1498780I-1640J-983D01*
G02X172152Y1497799I-1912J2D01*
G03X172124Y1497696I172J-102D01*
G01Y1494746D01*
G03X172152Y1494643I200J-1D01*
G02X172424Y1493662I-1640J-983D01*
G02X172152Y1492681I-1912J2D01*
G03X172124Y1492578I172J-102D01*
G01Y1491451D01*
G02X171922Y1491248I-202J-1D01*
G01X169102D01*
G02X168900Y1491451I1J203D01*
G01Y1492578D01*
G03X168872Y1492681I-200J1D01*
G02X168600Y1493662I1640J983D01*
G02X168872Y1494643I1912J-2D01*
G03X168900Y1494746I-172J102D01*
G01Y1497696D01*
G03X168872Y1497799I-200J1D01*
G02X168600Y1498780I1640J983D01*
G02X168872Y1499761I1912J-2D01*
G03X168900Y1499864I-172J102D01*
G37*
G36*
G01X6489Y1503336D02*
X9701D01*
G02X11116Y1502749I-1J-2002D01*
G01X14484Y1499381D01*
G02X15070Y1497966I-1415J-1415D01*
G01Y1496109D01*
G03X15145Y1495953I200J0D01*
G01X15426Y1495729D01*
X15514Y1495709D01*
X15558Y1495719D01*
G02X15889Y1495756I331J-1465D01*
G02Y1492752I0J-1502D01*
G02X15558Y1492789I0J1502D01*
G01X15514Y1492799D01*
X15426Y1492779D01*
X15145Y1492555D01*
G03X15070Y1492399I125J-156D01*
G01Y1492122D01*
G03X15129Y1491980I200J0D01*
G01X17719Y1489390D01*
G02X18306Y1487975I-1415J-1416D01*
G01Y1468196D01*
G02X14302I-2002J0D01*
G01Y1487063D01*
G03X14243Y1487205I-200J0D01*
G01X11654Y1489795D01*
G02X11068Y1491210I1415J1415D01*
G01Y1492442D01*
G03X10986Y1492604I-200J0D01*
G01X10725Y1492794D01*
G03X10546Y1492823I-118J-161D01*
G02X10090Y1492752I-456J1431D01*
G01X10089D01*
G02Y1495756I0J1502D01*
G01X10090D01*
G02X10546Y1495685I0J-1502D01*
G03X10725Y1495714I61J190D01*
G01X10986Y1495904D01*
G03X11068Y1496066I-118J162D01*
G01Y1497054D01*
G03X11009Y1497196I-200J0D01*
G01X8931Y1499273D01*
G03X8789Y1499332I-142J-141D01*
G01X6489D01*
G02Y1503336I0J2002D01*
G37*
G36*
G01X108270Y1510888D02*
Y1512014D01*
G02X108472Y1512216I202J0D01*
G01X111292D01*
G02X111494Y1512014I0J-202D01*
G01Y1510888D01*
G03X111522Y1510785I200J-1D01*
G02X111794Y1509804I-1640J-983D01*
G02X111522Y1508823I-1912J2D01*
G03X111494Y1508720I172J-102D01*
G01Y1505769D01*
G03X111522Y1505666I200J-1D01*
G02X111794Y1504685I-1640J-983D01*
G02X111522Y1503704I-1912J2D01*
G03X111494Y1503601I172J-102D01*
G01Y1502476D01*
G02X111292Y1502274I-202J0D01*
G01X108472D01*
G02X108270Y1502476I0J202D01*
G01Y1503601D01*
G03X108242Y1503704I-200J1D01*
G02X107970Y1504685I1640J983D01*
G02X108242Y1505666I1912J-2D01*
G03X108270Y1505769I-172J102D01*
G01Y1508720D01*
G03X108242Y1508823I-200J1D01*
G02X107970Y1509804I1640J983D01*
G02X108242Y1510785I1912J-2D01*
G03X108270Y1510888I-172J102D01*
G37*
G36*
G01X125592D02*
Y1512014D01*
G02X125795Y1512216I203J-1D01*
G01X128615D01*
G02X128818Y1512014I1J-202D01*
G01Y1510888D01*
G03X128846Y1510785I200J-1D01*
G02Y1508823I-1642J-981D01*
G03X128818Y1508720I172J-102D01*
G01Y1505769D01*
G03X128846Y1505666I200J-1D01*
G02Y1503704I-1642J-981D01*
G03X128818Y1503601I172J-102D01*
G01Y1502476D01*
G02X128615Y1502274I-203J1D01*
G01X125795D01*
G02X125592Y1502476I-1J202D01*
G01Y1503601D01*
G03X125564Y1503704I-200J1D01*
G02Y1505666I1642J981D01*
G03X125592Y1505769I-172J102D01*
G01Y1508720D01*
G03X125564Y1508823I-200J1D01*
G02Y1510785I1642J981D01*
G03X125592Y1510888I-172J102D01*
G37*
G36*
G01X142916D02*
Y1512014D01*
G02X143118Y1512216I202J0D01*
G01X145938D01*
G02X146140Y1512014I0J-202D01*
G01Y1510888D01*
G03X146168Y1510785I200J-1D01*
G02X146440Y1509804I-1640J-983D01*
G02X146168Y1508823I-1912J2D01*
G03X146140Y1508720I172J-102D01*
G01Y1505769D01*
G03X146168Y1505666I200J-1D01*
G02X146440Y1504685I-1640J-983D01*
G02X146168Y1503704I-1912J2D01*
G03X146140Y1503601I172J-102D01*
G01Y1502476D01*
G02X145938Y1502274I-202J0D01*
G01X143118D01*
G02X142916Y1502476I0J202D01*
G01Y1503601D01*
G03X142888Y1503704I-200J1D01*
G02X142616Y1504685I1640J983D01*
G02X142888Y1505666I1912J-2D01*
G03X142916Y1505769I-172J102D01*
G01Y1508720D01*
G03X142888Y1508823I-200J1D01*
G02X142616Y1509804I1640J983D01*
G02X142888Y1510785I1912J-2D01*
G03X142916Y1510888I-172J102D01*
G37*
G36*
G01X160238D02*
Y1512014D01*
G02X160440Y1512216I202J0D01*
G01X163260D01*
G02X163462Y1512014I0J-202D01*
G01Y1510888D01*
G03X163490Y1510785I200J-1D01*
G02X163762Y1509804I-1640J-983D01*
G02X163490Y1508823I-1912J2D01*
G03X163462Y1508720I172J-102D01*
G01Y1505769D01*
G03X163490Y1505666I200J-1D01*
G02X163762Y1504685I-1640J-983D01*
G02X163490Y1503704I-1912J2D01*
G03X163462Y1503601I172J-102D01*
G01Y1502476D01*
G02X163260Y1502274I-202J0D01*
G01X160440D01*
G02X160238Y1502476I0J202D01*
G01Y1503601D01*
G03X160210Y1503704I-200J1D01*
G02X159938Y1504685I1640J983D01*
G02X160210Y1505666I1912J-2D01*
G03X160238Y1505769I-172J102D01*
G01Y1508720D01*
G03X160210Y1508823I-200J1D01*
G02X159938Y1509804I1640J983D01*
G02X160210Y1510785I1912J-2D01*
G03X160238Y1510888I-172J102D01*
G37*
G36*
G01X116930Y1515218D02*
Y1516344D01*
G02X117133Y1516546I203J-1D01*
G01X119953D01*
G02X120156Y1516344I1J-202D01*
G01Y1515218D01*
G03X120184Y1515115I200J-1D01*
G02Y1513153I-1642J-981D01*
G03X120156Y1513050I172J-102D01*
G01Y1510100D01*
G03X120184Y1509997I200J-1D01*
G02Y1508035I-1642J-981D01*
G03X120156Y1507932I172J-102D01*
G01Y1506806D01*
G02X119953Y1506604I-203J1D01*
G01X117133D01*
G02X116930Y1506806I-1J202D01*
G01Y1507932D01*
G03X116902Y1508035I-200J1D01*
G02Y1509997I1642J981D01*
G03X116930Y1510100I-172J102D01*
G01Y1513050D01*
G03X116902Y1513153I-200J1D01*
G02Y1515115I1642J981D01*
G03X116930Y1515218I-172J102D01*
G37*
G36*
G01X134254D02*
Y1516344D01*
G02X134456Y1516546I202J0D01*
G01X137276D01*
G02X137478Y1516344I0J-202D01*
G01Y1515218D01*
G03X137506Y1515115I200J-1D01*
G02X137778Y1514134I-1640J-983D01*
G02X137506Y1513153I-1912J2D01*
G03X137478Y1513050I172J-102D01*
G01Y1510100D01*
G03X137506Y1509997I200J-1D01*
G02X137778Y1509016I-1640J-983D01*
G02X137506Y1508035I-1912J2D01*
G03X137478Y1507932I172J-102D01*
G01Y1506806D01*
G02X137276Y1506604I-202J0D01*
G01X134456D01*
G02X134254Y1506806I0J202D01*
G01Y1507932D01*
G03X134226Y1508035I-200J1D01*
G02X133954Y1509016I1640J983D01*
G02X134226Y1509997I1912J-2D01*
G03X134254Y1510100I-172J102D01*
G01Y1513050D01*
G03X134226Y1513153I-200J1D01*
G02X133954Y1514134I1640J983D01*
G02X134226Y1515115I1912J-2D01*
G03X134254Y1515218I-172J102D01*
G37*
G36*
G01X151576D02*
Y1516344D01*
G02X151779Y1516546I203J-1D01*
G01X154599D01*
G02X154802Y1516344I1J-202D01*
G01Y1515218D01*
G03X154830Y1515115I200J-1D01*
G02Y1513153I-1642J-981D01*
G03X154802Y1513050I172J-102D01*
G01Y1510100D01*
G03X154830Y1509997I200J-1D01*
G02Y1508035I-1642J-981D01*
G03X154802Y1507932I172J-102D01*
G01Y1506806D01*
G02X154599Y1506604I-203J1D01*
G01X151779D01*
G02X151576Y1506806I-1J202D01*
G01Y1507932D01*
G03X151548Y1508035I-200J1D01*
G02Y1509997I1642J981D01*
G03X151576Y1510100I-172J102D01*
G01Y1513050D01*
G03X151548Y1513153I-200J1D01*
G02Y1515115I1642J981D01*
G03X151576Y1515218I-172J102D01*
G37*
G36*
G01X168900D02*
Y1516344D01*
G02X169102Y1516546I202J0D01*
G01X171922D01*
G02X172124Y1516344I0J-202D01*
G01Y1515218D01*
G03X172152Y1515115I200J-1D01*
G02X172424Y1514134I-1640J-983D01*
G02X172152Y1513153I-1912J2D01*
G03X172124Y1513050I172J-102D01*
G01Y1510100D01*
G03X172152Y1509997I200J-1D01*
G02X172424Y1509016I-1640J-983D01*
G02X172152Y1508035I-1912J2D01*
G03X172124Y1507932I172J-102D01*
G01Y1506806D01*
G02X171922Y1506604I-202J0D01*
G01X169102D01*
G02X168900Y1506806I0J202D01*
G01Y1507932D01*
G03X168872Y1508035I-200J1D01*
G02X168600Y1509016I1640J983D01*
G02X168872Y1509997I1912J-2D01*
G03X168900Y1510100I-172J102D01*
G01Y1513050D01*
G03X168872Y1513153I-200J1D01*
G02X168600Y1514134I1640J983D01*
G02X168872Y1515115I1912J-2D01*
G03X168900Y1515218I-172J102D01*
G37*
G36*
G01X185499Y1526706D02*
X194001D01*
G02X195631Y1526031I0J-2306D01*
G01X210210Y1511451D01*
G03X210352Y1511392I142J141D01*
G01X224677D01*
G02X226307Y1510717I0J-2306D01*
G01X229612Y1507411D01*
G03X229754Y1507352I142J141D01*
G01X230758D01*
G02Y1502740I0J-2306D01*
G01X228712D01*
G02X228646Y1502741I2J2306D01*
G01X228500Y1502593D01*
G03X228442Y1502451I142J-141D01*
G01Y1502442D01*
G02X226135Y1500136I-2307J1D01*
G01X226134D01*
G02X224504Y1500811I0J2306D01*
G01X222949Y1502367D01*
G03X222807Y1502426I-142J-141D01*
G01X222204D01*
G02X220574Y1503101I0J2306D01*
G01X218993Y1504683D01*
G03X218851Y1504742I-142J-141D01*
G01X208722D01*
G02X207092Y1505417I0J2306D01*
G01X192435Y1520075D01*
G03X192293Y1520134I-142J-141D01*
G01X187817D01*
G03X187675Y1520075I0J-200D01*
G01X186365Y1518765D01*
G03X186306Y1518623I141J-142D01*
G01Y1516746D01*
G03X186506Y1516546I200J0D01*
G01X189245D01*
G02X189448Y1516344I1J-202D01*
G01Y1515218D01*
G03X189476Y1515115I200J-1D01*
G02Y1513153I-1642J-981D01*
G03X189448Y1513050I172J-102D01*
G01Y1510100D01*
G03X189476Y1509997I200J-1D01*
G02Y1508035I-1642J-981D01*
G03X189448Y1507932I172J-102D01*
G01Y1506806D01*
G02X189245Y1506604I-203J1D01*
G01X186506D01*
G03X186306Y1506404I0J-200D01*
G01Y1501240D01*
G03X186398Y1501072I200J0D01*
G01X186726Y1500862D01*
X186826Y1500855D01*
X186873Y1500876D01*
G02X187834Y1501086I961J-2096D01*
G01X187835D01*
G02X188992Y1500775I0J-2308D01*
G03X189092Y1500748I100J173D01*
G01X222843D01*
G02Y1496136I0J-2306D01*
G01X220531D01*
G03X220366Y1496048I1J-200D01*
G01X220180Y1495772D01*
G03X220160Y1495587I166J-112D01*
G01Y1495586D01*
G02X220328Y1494724I-2139J-864D01*
G02X218021Y1492418I-2307J1D01*
G02X216401Y1493082I-1J2307D01*
G03X216261Y1493140I-141J-142D01*
G01X190657D01*
G03X190515Y1493081I0J-200D01*
G01X189466Y1492031D01*
G02X187836Y1491356I-1630J1631D01*
G01X187835D01*
G02X186004Y1492260I0J2306D01*
G01X185978Y1492295D01*
X185902Y1492335D01*
X185558Y1492358D01*
G03X185403Y1492300I-14J-200D01*
G01X180804Y1487700D01*
G02X179173Y1487024I-1632J1631D01*
G02X176866Y1489331I0J2307D01*
G02X177542Y1490962I2307J-1D01*
G01X178300Y1491720D01*
G03X178355Y1491895I-142J141D01*
G01X178299Y1492218D01*
G03X178188Y1492363I-197J-36D01*
G01X178187Y1492364D01*
G02X176866Y1494449I985J2085D01*
G02X177542Y1496080I2307J-1D01*
G01X179577Y1498115D01*
G03X179636Y1498257I-141J142D01*
G01Y1502074D01*
G03X179436Y1502274I-200J0D01*
G01X177763D01*
G02X177560Y1502476I-1J202D01*
G01Y1503601D01*
G03X177532Y1503704I-200J1D01*
G02Y1505666I1642J981D01*
G03X177560Y1505769I-172J102D01*
G01Y1508720D01*
G03X177532Y1508823I-200J1D01*
G02Y1510785I1642J981D01*
G03X177560Y1510888I-172J102D01*
G01Y1512014D01*
G02X177763Y1512216I203J-1D01*
G01X179436D01*
G03X179636Y1512416I0J200D01*
G01Y1520843D01*
G02X180312Y1522474I2307J-1D01*
G01X183869Y1526031D01*
G02X185499Y1526706I1630J-1631D01*
G37*
G36*
G01X108270Y1567187D02*
Y1568313D01*
G02X108472Y1568516I202J1D01*
G01X111292D01*
G02X111494Y1568313I-1J-203D01*
G01Y1567187D01*
G03X111522Y1567084I200J-1D01*
G02X111794Y1566103I-1640J-983D01*
G02X111522Y1565122I-1912J2D01*
G03X111494Y1565019I172J-102D01*
G01Y1562069D01*
G03X111522Y1561966I200J-1D01*
G02X111794Y1560985I-1640J-983D01*
G02X111522Y1560004I-1912J2D01*
G03X111494Y1559901I172J-102D01*
G01Y1558775D01*
G02X111292Y1558572I-202J-1D01*
G01X108472D01*
G02X108270Y1558775I1J203D01*
G01Y1559901D01*
G03X108242Y1560004I-200J1D01*
G02X107970Y1560985I1640J983D01*
G02X108242Y1561966I1912J-2D01*
G03X108270Y1562069I-172J102D01*
G01Y1565019D01*
G03X108242Y1565122I-200J1D01*
G02X107970Y1566103I1640J983D01*
G02X108242Y1567084I1912J-2D01*
G03X108270Y1567187I-172J102D01*
G37*
G36*
G01X125592D02*
Y1568313D01*
G02X125795Y1568516I203J0D01*
G01X128615D01*
G02X128818Y1568313I0J-203D01*
G01Y1567187D01*
G03X128846Y1567084I200J-1D01*
G02Y1565122I-1642J-981D01*
G03X128818Y1565019I172J-102D01*
G01Y1562069D01*
G03X128846Y1561966I200J-1D01*
G02Y1560004I-1642J-981D01*
G03X128818Y1559901I172J-102D01*
G01Y1558775D01*
G02X128615Y1558572I-203J0D01*
G01X125795D01*
G02X125592Y1558775I0J203D01*
G01Y1559901D01*
G03X125564Y1560004I-200J1D01*
G02Y1561966I1642J981D01*
G03X125592Y1562069I-172J102D01*
G01Y1565019D01*
G03X125564Y1565122I-200J1D01*
G02Y1567084I1642J981D01*
G03X125592Y1567187I-172J102D01*
G37*
G36*
G01X142916D02*
Y1568313D01*
G02X143118Y1568516I202J1D01*
G01X145938D01*
G02X146140Y1568313I-1J-203D01*
G01Y1567187D01*
G03X146168Y1567084I200J-1D01*
G02X146440Y1566103I-1640J-983D01*
G02X146168Y1565122I-1912J2D01*
G03X146140Y1565019I172J-102D01*
G01Y1562069D01*
G03X146168Y1561966I200J-1D01*
G02X146440Y1560985I-1640J-983D01*
G02X146168Y1560004I-1912J2D01*
G03X146140Y1559901I172J-102D01*
G01Y1558775D01*
G02X145938Y1558572I-202J-1D01*
G01X143118D01*
G02X142916Y1558775I1J203D01*
G01Y1559901D01*
G03X142888Y1560004I-200J1D01*
G02X142616Y1560985I1640J983D01*
G02X142888Y1561966I1912J-2D01*
G03X142916Y1562069I-172J102D01*
G01Y1565019D01*
G03X142888Y1565122I-200J1D01*
G02X142616Y1566103I1640J983D01*
G02X142888Y1567084I1912J-2D01*
G03X142916Y1567187I-172J102D01*
G37*
G36*
G01X160238D02*
Y1568313D01*
G02X160440Y1568516I202J1D01*
G01X163260D01*
G02X163462Y1568313I-1J-203D01*
G01Y1567187D01*
G03X163490Y1567084I200J-1D01*
G02X163762Y1566103I-1640J-983D01*
G02X163490Y1565122I-1912J2D01*
G03X163462Y1565019I172J-102D01*
G01Y1562069D01*
G03X163490Y1561966I200J-1D01*
G02X163762Y1560985I-1640J-983D01*
G02X163490Y1560004I-1912J2D01*
G03X163462Y1559901I172J-102D01*
G01Y1558775D01*
G02X163260Y1558572I-202J-1D01*
G01X160440D01*
G02X160238Y1558775I1J203D01*
G01Y1559901D01*
G03X160210Y1560004I-200J1D01*
G02X159938Y1560985I1640J983D01*
G02X160210Y1561966I1912J-2D01*
G03X160238Y1562069I-172J102D01*
G01Y1565019D01*
G03X160210Y1565122I-200J1D01*
G02X159938Y1566103I1640J983D01*
G02X160210Y1567084I1912J-2D01*
G03X160238Y1567187I-172J102D01*
G37*
G36*
G01X177560D02*
Y1568313D01*
G02X177763Y1568516I203J0D01*
G01X180583D01*
G02X180786Y1568313I0J-203D01*
G01Y1567187D01*
G03X180814Y1567084I200J-1D01*
G02Y1565122I-1642J-981D01*
G03X180786Y1565019I172J-102D01*
G01Y1562069D01*
G03X180814Y1561966I200J-1D01*
G02Y1560004I-1642J-981D01*
G03X180786Y1559901I172J-102D01*
G01Y1558775D01*
G02X180583Y1558572I-203J0D01*
G01X177763D01*
G02X177560Y1558775I0J203D01*
G01Y1559901D01*
G03X177532Y1560004I-200J1D01*
G02Y1561966I1642J981D01*
G03X177560Y1562069I-172J102D01*
G01Y1565019D01*
G03X177532Y1565122I-200J1D01*
G02Y1567084I1642J981D01*
G03X177560Y1567187I-172J102D01*
G37*
G36*
G01X116930Y1571518D02*
Y1572644D01*
G02X117133Y1572846I203J-1D01*
G01X119953D01*
G02X120156Y1572644I1J-202D01*
G01Y1571518D01*
G03X120184Y1571415I200J-1D01*
G02Y1569453I-1642J-981D01*
G03X120156Y1569350I172J-102D01*
G01Y1566399D01*
G03X120184Y1566296I200J-1D01*
G02Y1564334I-1642J-981D01*
G03X120156Y1564231I172J-102D01*
G01Y1563106D01*
G02X119953Y1562904I-203J1D01*
G01X117133D01*
G02X116930Y1563106I-1J202D01*
G01Y1564231D01*
G03X116902Y1564334I-200J1D01*
G02Y1566296I1642J981D01*
G03X116930Y1566399I-172J102D01*
G01Y1569350D01*
G03X116902Y1569453I-200J1D01*
G02Y1571415I1642J981D01*
G03X116930Y1571518I-172J102D01*
G37*
G36*
G01X134254D02*
Y1572644D01*
G02X134456Y1572846I202J0D01*
G01X137276D01*
G02X137478Y1572644I0J-202D01*
G01Y1571518D01*
G03X137506Y1571415I200J-1D01*
G02X137778Y1570434I-1640J-983D01*
G02X137506Y1569453I-1912J2D01*
G03X137478Y1569350I172J-102D01*
G01Y1566399D01*
G03X137506Y1566296I200J-1D01*
G02X137778Y1565315I-1640J-983D01*
G02X137506Y1564334I-1912J2D01*
G03X137478Y1564231I172J-102D01*
G01Y1563106D01*
G02X137276Y1562904I-202J0D01*
G01X134456D01*
G02X134254Y1563106I0J202D01*
G01Y1564231D01*
G03X134226Y1564334I-200J1D01*
G02X133954Y1565315I1640J983D01*
G02X134226Y1566296I1912J-2D01*
G03X134254Y1566399I-172J102D01*
G01Y1569350D01*
G03X134226Y1569453I-200J1D01*
G02X133954Y1570434I1640J983D01*
G02X134226Y1571415I1912J-2D01*
G03X134254Y1571518I-172J102D01*
G37*
G36*
G01X151576D02*
Y1572644D01*
G02X151779Y1572846I203J-1D01*
G01X154599D01*
G02X154802Y1572644I1J-202D01*
G01Y1571518D01*
G03X154830Y1571415I200J-1D01*
G02Y1569453I-1642J-981D01*
G03X154802Y1569350I172J-102D01*
G01Y1566399D01*
G03X154830Y1566296I200J-1D01*
G02Y1564334I-1642J-981D01*
G03X154802Y1564231I172J-102D01*
G01Y1563106D01*
G02X154599Y1562904I-203J1D01*
G01X151779D01*
G02X151576Y1563106I-1J202D01*
G01Y1564231D01*
G03X151548Y1564334I-200J1D01*
G02Y1566296I1642J981D01*
G03X151576Y1566399I-172J102D01*
G01Y1569350D01*
G03X151548Y1569453I-200J1D01*
G02Y1571415I1642J981D01*
G03X151576Y1571518I-172J102D01*
G37*
G36*
G01X168900D02*
Y1572644D01*
G02X169102Y1572846I202J0D01*
G01X171922D01*
G02X172124Y1572644I0J-202D01*
G01Y1571518D01*
G03X172152Y1571415I200J-1D01*
G02X172424Y1570434I-1640J-983D01*
G02X172152Y1569453I-1912J2D01*
G03X172124Y1569350I172J-102D01*
G01Y1566399D01*
G03X172152Y1566296I200J-1D01*
G02X172424Y1565315I-1640J-983D01*
G02X172152Y1564334I-1912J2D01*
G03X172124Y1564231I172J-102D01*
G01Y1563106D01*
G02X171922Y1562904I-202J0D01*
G01X169102D01*
G02X168900Y1563106I0J202D01*
G01Y1564231D01*
G03X168872Y1564334I-200J1D01*
G02X168600Y1565315I1640J983D01*
G02X168872Y1566296I1912J-2D01*
G03X168900Y1566399I-172J102D01*
G01Y1569350D01*
G03X168872Y1569453I-200J1D01*
G02X168600Y1570434I1640J983D01*
G02X168872Y1571415I1912J-2D01*
G03X168900Y1571518I-172J102D01*
G37*
G36*
G01X108270Y1582541D02*
Y1583667D01*
G02X108472Y1583870I202J1D01*
G01X111292D01*
G02X111494Y1583667I-1J-203D01*
G01Y1582541D01*
G03X111522Y1582438I200J-1D01*
G02X111794Y1581457I-1640J-983D01*
G02X111522Y1580476I-1912J2D01*
G03X111494Y1580373I172J-102D01*
G01Y1577423D01*
G03X111522Y1577320I200J-1D01*
G02X111794Y1576339I-1640J-983D01*
G02X111522Y1575358I-1912J2D01*
G03X111494Y1575255I172J-102D01*
G01Y1574129D01*
G02X111292Y1573926I-202J-1D01*
G01X108472D01*
G02X108270Y1574129I1J203D01*
G01Y1575255D01*
G03X108242Y1575358I-200J1D01*
G02X107970Y1576339I1640J983D01*
G02X108242Y1577320I1912J-2D01*
G03X108270Y1577423I-172J102D01*
G01Y1580373D01*
G03X108242Y1580476I-200J1D01*
G02X107970Y1581457I1640J983D01*
G02X108242Y1582438I1912J-2D01*
G03X108270Y1582541I-172J102D01*
G37*
G36*
G01X125592D02*
Y1583667D01*
G02X125795Y1583870I203J0D01*
G01X128615D01*
G02X128818Y1583667I0J-203D01*
G01Y1582541D01*
G03X128846Y1582438I200J-1D01*
G02Y1580476I-1642J-981D01*
G03X128818Y1580373I172J-102D01*
G01Y1577423D01*
G03X128846Y1577320I200J-1D01*
G02Y1575358I-1642J-981D01*
G03X128818Y1575255I172J-102D01*
G01Y1574129D01*
G02X128615Y1573926I-203J0D01*
G01X125795D01*
G02X125592Y1574129I0J203D01*
G01Y1575255D01*
G03X125564Y1575358I-200J1D01*
G02Y1577320I1642J981D01*
G03X125592Y1577423I-172J102D01*
G01Y1580373D01*
G03X125564Y1580476I-200J1D01*
G02Y1582438I1642J981D01*
G03X125592Y1582541I-172J102D01*
G37*
G36*
G01X142916D02*
Y1583667D01*
G02X143118Y1583870I202J1D01*
G01X145938D01*
G02X146140Y1583667I-1J-203D01*
G01Y1582541D01*
G03X146168Y1582438I200J-1D01*
G02X146440Y1581457I-1640J-983D01*
G02X146168Y1580476I-1912J2D01*
G03X146140Y1580373I172J-102D01*
G01Y1577423D01*
G03X146168Y1577320I200J-1D01*
G02X146440Y1576339I-1640J-983D01*
G02X146168Y1575358I-1912J2D01*
G03X146140Y1575255I172J-102D01*
G01Y1574129D01*
G02X145938Y1573926I-202J-1D01*
G01X143118D01*
G02X142916Y1574129I1J203D01*
G01Y1575255D01*
G03X142888Y1575358I-200J1D01*
G02X142616Y1576339I1640J983D01*
G02X142888Y1577320I1912J-2D01*
G03X142916Y1577423I-172J102D01*
G01Y1580373D01*
G03X142888Y1580476I-200J1D01*
G02X142616Y1581457I1640J983D01*
G02X142888Y1582438I1912J-2D01*
G03X142916Y1582541I-172J102D01*
G37*
G36*
G01X160238D02*
Y1583667D01*
G02X160440Y1583870I202J1D01*
G01X163260D01*
G02X163462Y1583667I-1J-203D01*
G01Y1582541D01*
G03X163490Y1582438I200J-1D01*
G02X163762Y1581457I-1640J-983D01*
G02X163490Y1580476I-1912J2D01*
G03X163462Y1580373I172J-102D01*
G01Y1577423D01*
G03X163490Y1577320I200J-1D01*
G02X163762Y1576339I-1640J-983D01*
G02X163490Y1575358I-1912J2D01*
G03X163462Y1575255I172J-102D01*
G01Y1574129D01*
G02X163260Y1573926I-202J-1D01*
G01X160440D01*
G02X160238Y1574129I1J203D01*
G01Y1575255D01*
G03X160210Y1575358I-200J1D01*
G02X159938Y1576339I1640J983D01*
G02X160210Y1577320I1912J-2D01*
G03X160238Y1577423I-172J102D01*
G01Y1580373D01*
G03X160210Y1580476I-200J1D01*
G02X159938Y1581457I1640J983D01*
G02X160210Y1582438I1912J-2D01*
G03X160238Y1582541I-172J102D01*
G37*
G36*
G01X177560D02*
Y1583667D01*
G02X177763Y1583870I203J0D01*
G01X180583D01*
G02X180786Y1583667I0J-203D01*
G01Y1582541D01*
G03X180814Y1582438I200J-1D01*
G02Y1580476I-1642J-981D01*
G03X180786Y1580373I172J-102D01*
G01Y1577423D01*
G03X180814Y1577320I200J-1D01*
G02Y1575358I-1642J-981D01*
G03X180786Y1575255I172J-102D01*
G01Y1574129D01*
G02X180583Y1573926I-203J0D01*
G01X177763D01*
G02X177560Y1574129I0J203D01*
G01Y1575255D01*
G03X177532Y1575358I-200J1D01*
G02Y1577320I1642J981D01*
G03X177560Y1577423I-172J102D01*
G01Y1580373D01*
G03X177532Y1580476I-200J1D01*
G02Y1582438I1642J981D01*
G03X177560Y1582541I-172J102D01*
G37*
G36*
G01X56517Y1584436D02*
X56811D01*
G03X56958Y1584501I-1J200D01*
G02X59170I1106J-1017D01*
G03X59317Y1584436I148J135D01*
G01X59611D01*
G03X59758Y1584501I-1J200D01*
G02X60864Y1584986I1106J-1019D01*
G02Y1581982I0J-1502D01*
G02X59758Y1582467I0J1504D01*
G03X59611Y1582532I-148J-135D01*
G01X59317D01*
G03X59170Y1582467I1J-200D01*
G02X56958I-1106J1017D01*
G03X56811Y1582532I-148J-135D01*
G01X56517D01*
G03X56370Y1582467I1J-200D01*
G02X55264Y1581982I-1106J1019D01*
G02Y1584986I0J1502D01*
G02X56370Y1584501I0J-1504D01*
G03X56517Y1584436I148J135D01*
G37*
G36*
G01X116930Y1586872D02*
Y1587998D01*
G02X117133Y1588200I203J-1D01*
G01X119953D01*
G02X120156Y1587998I1J-202D01*
G01Y1586872D01*
G03X120184Y1586769I200J-1D01*
G02Y1584807I-1642J-981D01*
G03X120156Y1584704I172J-102D01*
G01Y1581754D01*
G03X120184Y1581651I200J-1D01*
G02Y1579689I-1642J-981D01*
G03X120156Y1579586I172J-102D01*
G01Y1578460D01*
G02X119953Y1578258I-203J1D01*
G01X117133D01*
G02X116930Y1578460I-1J202D01*
G01Y1579586D01*
G03X116902Y1579689I-200J1D01*
G02Y1581651I1642J981D01*
G03X116930Y1581754I-172J102D01*
G01Y1584704D01*
G03X116902Y1584807I-200J1D01*
G02Y1586769I1642J981D01*
G03X116930Y1586872I-172J102D01*
G37*
G36*
G01X134254D02*
Y1587998D01*
G02X134456Y1588200I202J0D01*
G01X137276D01*
G02X137478Y1587998I0J-202D01*
G01Y1586872D01*
G03X137506Y1586769I200J-1D01*
G02X137778Y1585788I-1640J-983D01*
G02X137506Y1584807I-1912J2D01*
G03X137478Y1584704I172J-102D01*
G01Y1581754D01*
G03X137506Y1581651I200J-1D01*
G02X137778Y1580670I-1640J-983D01*
G02X137506Y1579689I-1912J2D01*
G03X137478Y1579586I172J-102D01*
G01Y1578460D01*
G02X137276Y1578258I-202J0D01*
G01X134456D01*
G02X134254Y1578460I0J202D01*
G01Y1579586D01*
G03X134226Y1579689I-200J1D01*
G02X133954Y1580670I1640J983D01*
G02X134226Y1581651I1912J-2D01*
G03X134254Y1581754I-172J102D01*
G01Y1584704D01*
G03X134226Y1584807I-200J1D01*
G02X133954Y1585788I1640J983D01*
G02X134226Y1586769I1912J-2D01*
G03X134254Y1586872I-172J102D01*
G37*
G36*
G01X151576D02*
Y1587998D01*
G02X151779Y1588200I203J-1D01*
G01X154599D01*
G02X154802Y1587998I1J-202D01*
G01Y1586872D01*
G03X154830Y1586769I200J-1D01*
G02Y1584807I-1642J-981D01*
G03X154802Y1584704I172J-102D01*
G01Y1581754D01*
G03X154830Y1581651I200J-1D01*
G02Y1579689I-1642J-981D01*
G03X154802Y1579586I172J-102D01*
G01Y1578460D01*
G02X154599Y1578258I-203J1D01*
G01X151779D01*
G02X151576Y1578460I-1J202D01*
G01Y1579586D01*
G03X151548Y1579689I-200J1D01*
G02Y1581651I1642J981D01*
G03X151576Y1581754I-172J102D01*
G01Y1584704D01*
G03X151548Y1584807I-200J1D01*
G02Y1586769I1642J981D01*
G03X151576Y1586872I-172J102D01*
G37*
G36*
G01X168900D02*
Y1587998D01*
G02X169102Y1588200I202J0D01*
G01X171922D01*
G02X172124Y1587998I0J-202D01*
G01Y1586872D01*
G03X172152Y1586769I200J-1D01*
G02X172424Y1585788I-1640J-983D01*
G02X172152Y1584807I-1912J2D01*
G03X172124Y1584704I172J-102D01*
G01Y1581754D01*
G03X172152Y1581651I200J-1D01*
G02X172424Y1580670I-1640J-983D01*
G02X172152Y1579689I-1912J2D01*
G03X172124Y1579586I172J-102D01*
G01Y1578460D01*
G02X171922Y1578258I-202J0D01*
G01X169102D01*
G02X168900Y1578460I0J202D01*
G01Y1579586D01*
G03X168872Y1579689I-200J1D01*
G02X168600Y1580670I1640J983D01*
G02X168872Y1581651I1912J-2D01*
G03X168900Y1581754I-172J102D01*
G01Y1584704D01*
G03X168872Y1584807I-200J1D01*
G02X168600Y1585788I1640J983D01*
G02X168872Y1586769I1912J-2D01*
G03X168900Y1586872I-172J102D01*
G37*
G36*
G01X108270Y1597895D02*
Y1599021D01*
G02X108472Y1599224I202J1D01*
G01X111292D01*
G02X111494Y1599021I-1J-203D01*
G01Y1597895D01*
G03X111522Y1597792I200J-1D01*
G02X111794Y1596811I-1640J-983D01*
G02X111522Y1595830I-1912J2D01*
G03X111494Y1595727I172J-102D01*
G01Y1592777D01*
G03X111522Y1592674I200J-1D01*
G02X111794Y1591693I-1640J-983D01*
G02X111522Y1590712I-1912J2D01*
G03X111494Y1590609I172J-102D01*
G01Y1589483D01*
G02X111292Y1589280I-202J-1D01*
G01X108472D01*
G02X108270Y1589483I1J203D01*
G01Y1590609D01*
G03X108242Y1590712I-200J1D01*
G02X107970Y1591693I1640J983D01*
G02X108242Y1592674I1912J-2D01*
G03X108270Y1592777I-172J102D01*
G01Y1595727D01*
G03X108242Y1595830I-200J1D01*
G02X107970Y1596811I1640J983D01*
G02X108242Y1597792I1912J-2D01*
G03X108270Y1597895I-172J102D01*
G37*
G36*
G01X125592D02*
Y1599021D01*
G02X125795Y1599224I203J0D01*
G01X128615D01*
G02X128818Y1599021I0J-203D01*
G01Y1597895D01*
G03X128846Y1597792I200J-1D01*
G02Y1595830I-1642J-981D01*
G03X128818Y1595727I172J-102D01*
G01Y1592777D01*
G03X128846Y1592674I200J-1D01*
G02Y1590712I-1642J-981D01*
G03X128818Y1590609I172J-102D01*
G01Y1589483D01*
G02X128615Y1589280I-203J0D01*
G01X125795D01*
G02X125592Y1589483I0J203D01*
G01Y1590609D01*
G03X125564Y1590712I-200J1D01*
G02Y1592674I1642J981D01*
G03X125592Y1592777I-172J102D01*
G01Y1595727D01*
G03X125564Y1595830I-200J1D01*
G02Y1597792I1642J981D01*
G03X125592Y1597895I-172J102D01*
G37*
G36*
G01X142916D02*
Y1599021D01*
G02X143118Y1599224I202J1D01*
G01X145938D01*
G02X146140Y1599021I-1J-203D01*
G01Y1597895D01*
G03X146168Y1597792I200J-1D01*
G02X146440Y1596811I-1640J-983D01*
G02X146168Y1595830I-1912J2D01*
G03X146140Y1595727I172J-102D01*
G01Y1592777D01*
G03X146168Y1592674I200J-1D01*
G02X146440Y1591693I-1640J-983D01*
G02X146168Y1590712I-1912J2D01*
G03X146140Y1590609I172J-102D01*
G01Y1589483D01*
G02X145938Y1589280I-202J-1D01*
G01X143118D01*
G02X142916Y1589483I1J203D01*
G01Y1590609D01*
G03X142888Y1590712I-200J1D01*
G02X142616Y1591693I1640J983D01*
G02X142888Y1592674I1912J-2D01*
G03X142916Y1592777I-172J102D01*
G01Y1595727D01*
G03X142888Y1595830I-200J1D01*
G02X142616Y1596811I1640J983D01*
G02X142888Y1597792I1912J-2D01*
G03X142916Y1597895I-172J102D01*
G37*
G36*
G01X160238D02*
Y1599021D01*
G02X160440Y1599224I202J1D01*
G01X163260D01*
G02X163462Y1599021I-1J-203D01*
G01Y1597895D01*
G03X163490Y1597792I200J-1D01*
G02X163762Y1596811I-1640J-983D01*
G02X163490Y1595830I-1912J2D01*
G03X163462Y1595727I172J-102D01*
G01Y1592777D01*
G03X163490Y1592674I200J-1D01*
G02X163762Y1591693I-1640J-983D01*
G02X163490Y1590712I-1912J2D01*
G03X163462Y1590609I172J-102D01*
G01Y1589483D01*
G02X163260Y1589280I-202J-1D01*
G01X160440D01*
G02X160238Y1589483I1J203D01*
G01Y1590609D01*
G03X160210Y1590712I-200J1D01*
G02X159938Y1591693I1640J983D01*
G02X160210Y1592674I1912J-2D01*
G03X160238Y1592777I-172J102D01*
G01Y1595727D01*
G03X160210Y1595830I-200J1D01*
G02X159938Y1596811I1640J983D01*
G02X160210Y1597792I1912J-2D01*
G03X160238Y1597895I-172J102D01*
G37*
G36*
G01X116930Y1602226D02*
Y1603352D01*
G02X117133Y1603554I203J-1D01*
G01X119953D01*
G02X120156Y1603352I1J-202D01*
G01Y1602226D01*
G03X120184Y1602123I200J-1D01*
G02Y1600161I-1642J-981D01*
G03X120156Y1600058I172J-102D01*
G01Y1597108D01*
G03X120184Y1597005I200J-1D01*
G02Y1595043I-1642J-981D01*
G03X120156Y1594940I172J-102D01*
G01Y1593814D01*
G02X119953Y1593612I-203J1D01*
G01X117133D01*
G02X116930Y1593814I-1J202D01*
G01Y1594940D01*
G03X116902Y1595043I-200J1D01*
G02Y1597005I1642J981D01*
G03X116930Y1597108I-172J102D01*
G01Y1600058D01*
G03X116902Y1600161I-200J1D01*
G02Y1602123I1642J981D01*
G03X116930Y1602226I-172J102D01*
G37*
G36*
G01X134254D02*
Y1603352D01*
G02X134456Y1603554I202J0D01*
G01X137276D01*
G02X137478Y1603352I0J-202D01*
G01Y1602226D01*
G03X137506Y1602123I200J-1D01*
G02X137778Y1601142I-1640J-983D01*
G02X137506Y1600161I-1912J2D01*
G03X137478Y1600058I172J-102D01*
G01Y1597108D01*
G03X137506Y1597005I200J-1D01*
G02X137778Y1596024I-1640J-983D01*
G02X137506Y1595043I-1912J2D01*
G03X137478Y1594940I172J-102D01*
G01Y1593814D01*
G02X137276Y1593612I-202J0D01*
G01X134456D01*
G02X134254Y1593814I0J202D01*
G01Y1594940D01*
G03X134226Y1595043I-200J1D01*
G02X133954Y1596024I1640J983D01*
G02X134226Y1597005I1912J-2D01*
G03X134254Y1597108I-172J102D01*
G01Y1600058D01*
G03X134226Y1600161I-200J1D01*
G02X133954Y1601142I1640J983D01*
G02X134226Y1602123I1912J-2D01*
G03X134254Y1602226I-172J102D01*
G37*
G36*
G01X151576D02*
Y1603352D01*
G02X151779Y1603554I203J-1D01*
G01X154599D01*
G02X154802Y1603352I1J-202D01*
G01Y1602226D01*
G03X154830Y1602123I200J-1D01*
G02Y1600161I-1642J-981D01*
G03X154802Y1600058I172J-102D01*
G01Y1597108D01*
G03X154830Y1597005I200J-1D01*
G02Y1595043I-1642J-981D01*
G03X154802Y1594940I172J-102D01*
G01Y1593814D01*
G02X154599Y1593612I-203J1D01*
G01X151779D01*
G02X151576Y1593814I-1J202D01*
G01Y1594940D01*
G03X151548Y1595043I-200J1D01*
G02Y1597005I1642J981D01*
G03X151576Y1597108I-172J102D01*
G01Y1600058D01*
G03X151548Y1600161I-200J1D01*
G02Y1602123I1642J981D01*
G03X151576Y1602226I-172J102D01*
G37*
G36*
G01X168900D02*
Y1603352D01*
G02X169102Y1603554I202J0D01*
G01X171922D01*
G02X172124Y1603352I0J-202D01*
G01Y1602226D01*
G03X172152Y1602123I200J-1D01*
G02X172424Y1601142I-1640J-983D01*
G02X172152Y1600161I-1912J2D01*
G03X172124Y1600058I172J-102D01*
G01Y1597108D01*
G03X172152Y1597005I200J-1D01*
G02X172424Y1596024I-1640J-983D01*
G02X172152Y1595043I-1912J2D01*
G03X172124Y1594940I172J-102D01*
G01Y1593814D01*
G02X171922Y1593612I-202J0D01*
G01X169102D01*
G02X168900Y1593814I0J202D01*
G01Y1594940D01*
G03X168872Y1595043I-200J1D01*
G02X168600Y1596024I1640J983D01*
G02X168872Y1597005I1912J-2D01*
G03X168900Y1597108I-172J102D01*
G01Y1600058D01*
G03X168872Y1600161I-200J1D01*
G02X168600Y1601142I1640J983D01*
G02X168872Y1602123I1912J-2D01*
G03X168900Y1602226I-172J102D01*
G37*
G36*
G01X108270Y1613250D02*
Y1614376D01*
G02X108472Y1614578I202J0D01*
G01X111292D01*
G02X111494Y1614376I0J-202D01*
G01Y1613250D01*
G03X111522Y1613147I200J-1D01*
G02X111794Y1612166I-1640J-983D01*
G02X111522Y1611185I-1912J2D01*
G03X111494Y1611082I172J-102D01*
G01Y1608132D01*
G03X111522Y1608029I200J-1D01*
G02X111794Y1607048I-1640J-983D01*
G02X111522Y1606067I-1912J2D01*
G03X111494Y1605964I172J-102D01*
G01Y1604838D01*
G02X111292Y1604636I-202J0D01*
G01X108472D01*
G02X108270Y1604838I0J202D01*
G01Y1605964D01*
G03X108242Y1606067I-200J1D01*
G02X107970Y1607048I1640J983D01*
G02X108242Y1608029I1912J-2D01*
G03X108270Y1608132I-172J102D01*
G01Y1611082D01*
G03X108242Y1611185I-200J1D01*
G02X107970Y1612166I1640J983D01*
G02X108242Y1613147I1912J-2D01*
G03X108270Y1613250I-172J102D01*
G37*
G36*
G01X125592D02*
Y1614376D01*
G02X125795Y1614578I203J-1D01*
G01X128615D01*
G02X128818Y1614376I1J-202D01*
G01Y1613250D01*
G03X128846Y1613147I200J-1D01*
G02Y1611185I-1642J-981D01*
G03X128818Y1611082I172J-102D01*
G01Y1608132D01*
G03X128846Y1608029I200J-1D01*
G02Y1606067I-1642J-981D01*
G03X128818Y1605964I172J-102D01*
G01Y1604838D01*
G02X128615Y1604636I-203J1D01*
G01X125795D01*
G02X125592Y1604838I-1J202D01*
G01Y1605964D01*
G03X125564Y1606067I-200J1D01*
G02Y1608029I1642J981D01*
G03X125592Y1608132I-172J102D01*
G01Y1611082D01*
G03X125564Y1611185I-200J1D01*
G02Y1613147I1642J981D01*
G03X125592Y1613250I-172J102D01*
G37*
G36*
G01X142916D02*
Y1614376D01*
G02X143118Y1614578I202J0D01*
G01X145938D01*
G02X146140Y1614376I0J-202D01*
G01Y1613250D01*
G03X146168Y1613147I200J-1D01*
G02X146440Y1612166I-1640J-983D01*
G02X146168Y1611185I-1912J2D01*
G03X146140Y1611082I172J-102D01*
G01Y1608132D01*
G03X146168Y1608029I200J-1D01*
G02X146440Y1607048I-1640J-983D01*
G02X146168Y1606067I-1912J2D01*
G03X146140Y1605964I172J-102D01*
G01Y1604838D01*
G02X145938Y1604636I-202J0D01*
G01X143118D01*
G02X142916Y1604838I0J202D01*
G01Y1605964D01*
G03X142888Y1606067I-200J1D01*
G02X142616Y1607048I1640J983D01*
G02X142888Y1608029I1912J-2D01*
G03X142916Y1608132I-172J102D01*
G01Y1611082D01*
G03X142888Y1611185I-200J1D01*
G02X142616Y1612166I1640J983D01*
G02X142888Y1613147I1912J-2D01*
G03X142916Y1613250I-172J102D01*
G37*
G36*
G01X160238D02*
Y1614376D01*
G02X160440Y1614578I202J0D01*
G01X163260D01*
G02X163462Y1614376I0J-202D01*
G01Y1613250D01*
G03X163490Y1613147I200J-1D01*
G02X163762Y1612166I-1640J-983D01*
G02X163490Y1611185I-1912J2D01*
G03X163462Y1611082I172J-102D01*
G01Y1608132D01*
G03X163490Y1608029I200J-1D01*
G02X163762Y1607048I-1640J-983D01*
G02X163490Y1606067I-1912J2D01*
G03X163462Y1605964I172J-102D01*
G01Y1604838D01*
G02X163260Y1604636I-202J0D01*
G01X160440D01*
G02X160238Y1604838I0J202D01*
G01Y1605964D01*
G03X160210Y1606067I-200J1D01*
G02X159938Y1607048I1640J983D01*
G02X160210Y1608029I1912J-2D01*
G03X160238Y1608132I-172J102D01*
G01Y1611082D01*
G03X160210Y1611185I-200J1D01*
G02X159938Y1612166I1640J983D01*
G02X160210Y1613147I1912J-2D01*
G03X160238Y1613250I-172J102D01*
G37*
G36*
G01X116930Y1617580D02*
Y1618706D01*
G02X117133Y1618908I203J-1D01*
G01X119953D01*
G02X120156Y1618706I1J-202D01*
G01Y1617580D01*
G03X120184Y1617477I200J-1D01*
G02Y1615515I-1642J-981D01*
G03X120156Y1615412I172J-102D01*
G01Y1612462D01*
G03X120184Y1612359I200J-1D01*
G02Y1610397I-1642J-981D01*
G03X120156Y1610294I172J-102D01*
G01Y1609168D01*
G02X119953Y1608966I-203J1D01*
G01X117133D01*
G02X116930Y1609168I-1J202D01*
G01Y1610294D01*
G03X116902Y1610397I-200J1D01*
G02Y1612359I1642J981D01*
G03X116930Y1612462I-172J102D01*
G01Y1615412D01*
G03X116902Y1615515I-200J1D01*
G02Y1617477I1642J981D01*
G03X116930Y1617580I-172J102D01*
G37*
G36*
G01X134254D02*
Y1618706D01*
G02X134456Y1618908I202J0D01*
G01X137276D01*
G02X137478Y1618706I0J-202D01*
G01Y1617580D01*
G03X137506Y1617477I200J-1D01*
G02X137778Y1616496I-1640J-983D01*
G02X137506Y1615515I-1912J2D01*
G03X137478Y1615412I172J-102D01*
G01Y1612462D01*
G03X137506Y1612359I200J-1D01*
G02X137778Y1611378I-1640J-983D01*
G02X137506Y1610397I-1912J2D01*
G03X137478Y1610294I172J-102D01*
G01Y1609168D01*
G02X137276Y1608966I-202J0D01*
G01X134456D01*
G02X134254Y1609168I0J202D01*
G01Y1610294D01*
G03X134226Y1610397I-200J1D01*
G02X133954Y1611378I1640J983D01*
G02X134226Y1612359I1912J-2D01*
G03X134254Y1612462I-172J102D01*
G01Y1615412D01*
G03X134226Y1615515I-200J1D01*
G02X133954Y1616496I1640J983D01*
G02X134226Y1617477I1912J-2D01*
G03X134254Y1617580I-172J102D01*
G37*
G36*
G01X151576D02*
Y1618706D01*
G02X151779Y1618908I203J-1D01*
G01X154599D01*
G02X154802Y1618706I1J-202D01*
G01Y1617580D01*
G03X154830Y1617477I200J-1D01*
G02Y1615515I-1642J-981D01*
G03X154802Y1615412I172J-102D01*
G01Y1612462D01*
G03X154830Y1612359I200J-1D01*
G02Y1610397I-1642J-981D01*
G03X154802Y1610294I172J-102D01*
G01Y1609168D01*
G02X154599Y1608966I-203J1D01*
G01X151779D01*
G02X151576Y1609168I-1J202D01*
G01Y1610294D01*
G03X151548Y1610397I-200J1D01*
G02Y1612359I1642J981D01*
G03X151576Y1612462I-172J102D01*
G01Y1615412D01*
G03X151548Y1615515I-200J1D01*
G02Y1617477I1642J981D01*
G03X151576Y1617580I-172J102D01*
G37*
G36*
G01X168900D02*
Y1618706D01*
G02X169102Y1618908I202J0D01*
G01X171922D01*
G02X172124Y1618706I0J-202D01*
G01Y1617580D01*
G03X172152Y1617477I200J-1D01*
G02X172424Y1616496I-1640J-983D01*
G02X172152Y1615515I-1912J2D01*
G03X172124Y1615412I172J-102D01*
G01Y1612462D01*
G03X172152Y1612359I200J-1D01*
G02X172424Y1611378I-1640J-983D01*
G02X172152Y1610397I-1912J2D01*
G03X172124Y1610294I172J-102D01*
G01Y1609168D01*
G02X171922Y1608966I-202J0D01*
G01X169102D01*
G02X168900Y1609168I0J202D01*
G01Y1610294D01*
G03X168872Y1610397I-200J1D01*
G02X168600Y1611378I1640J983D01*
G02X168872Y1612359I1912J-2D01*
G03X168900Y1612462I-172J102D01*
G01Y1615412D01*
G03X168872Y1615515I-200J1D01*
G02X168600Y1616496I1640J983D01*
G02X168872Y1617477I1912J-2D01*
G03X168900Y1617580I-172J102D01*
G37*
G36*
G01X135337Y1223444D02*
G02X134930Y1224472I1095J1028D01*
G02X137934I1502J0D01*
G02X136994Y1223079I-1502J0D01*
G03X136852Y1222435I150J-371D01*
G02X137259Y1221407I-1095J-1028D01*
G02X134255I-1502J0D01*
G02X135195Y1222800I1502J0D01*
G03X135337Y1223444I-150J371D01*
G37*
G36*
G01X29030Y1440464D02*
G02X28378Y1441702I849J1238D01*
G02X31382I1502J0D01*
G02X30714Y1440453I-1502J0D01*
G03X30710Y1439790I222J-333D01*
G02X31362Y1438552I-849J-1238D01*
G02X28358I-1502J0D01*
G02X29026Y1439801I1502J0D01*
G03X29030Y1440464I-222J333D01*
G37*
G36*
G01X25000Y1512036D02*
G02X25363Y1513283I2326J-1D01*
G03Y1513497I-169J107D01*
G02X25000Y1514744I1963J1248D01*
G01Y1516476D01*
G02X25451Y1517852I2326J-1D01*
G03X25490Y1517971I-161J119D01*
G01Y1518168D01*
G03X25431Y1518310I-200J0D01*
G01X25317Y1518423D01*
X25261Y1518451D01*
X25230Y1518456D01*
G02X23937Y1519111I353J2300D01*
G01X22712Y1520336D01*
G02X22057Y1521629I1645J1646D01*
G01X22052Y1521660D01*
X22024Y1521716D01*
X21455Y1522285D01*
G03X21313Y1522344I-142J-141D01*
G01X21259D01*
G03X21075Y1522224I-1J-200D01*
G01X20905Y1521835D01*
X20924Y1521718D01*
X20965Y1521674D01*
G02X21361Y1520658I-1106J-1016D01*
G01Y1520657D01*
G02X18357I-1502J0D01*
G01Y1520658D01*
G02X18753Y1521674I1502J0D01*
G01X18794Y1521718D01*
X18813Y1521835D01*
X18643Y1522224D01*
G03X18459Y1522344I-183J-80D01*
G01X15640D01*
G02X13995Y1523026I1J2327D01*
G01X12558Y1524463D01*
G03X12416Y1524522I-142J-141D01*
G01X10243D01*
G03X10101Y1524463I0J-200D01*
G01X9628Y1523990D01*
G02X7983Y1523308I-1646J1645D01*
G02X5656Y1525635I0J2327D01*
G02X6138Y1527052I2327J-1D01*
G01X6159Y1527078D01*
X6180Y1527141D01*
Y1527529D01*
X6159Y1527592D01*
X6138Y1527618D01*
G02X5656Y1529035I1845J1418D01*
G02X7983Y1531362I2327J0D01*
G02X9628Y1530680I-1J-2327D01*
G01X9995Y1530313D01*
G03X10137Y1530254I142J141D01*
G01X13911D01*
G02X15556Y1529573I0J-2327D01*
G01X16993Y1528137D01*
G03X17135Y1528078I142J141D01*
G01X22808D01*
G02X24453Y1527396I-1J-2327D01*
G01X30541Y1521308D01*
G02X31222Y1519663I-1646J-1645D01*
G01Y1500800D01*
G03X31281Y1500658I200J0D01*
G01X31596Y1500343D01*
G03X31878I141J142D01*
G01X31928Y1500393D01*
X31944Y1500530D01*
X31908Y1500589D01*
G02X31687Y1501373I1280J784D01*
G02X33189Y1499871I1502J0D01*
G02X33061Y1499876I-5J1502D01*
G01X32998Y1499881D01*
X32890Y1499819D01*
X32704Y1499421D01*
G03X32744Y1499195I181J-84D01*
G01X56348Y1475591D01*
G02X57030Y1473946I-1645J-1646D01*
G01Y1463663D01*
G02X56348Y1462018I-2327J1D01*
G01X52532Y1458202D01*
G02X50887Y1457520I-1646J1645D01*
G01X39379D01*
G02X37734Y1458202I1J2327D01*
G01X35340Y1460596D01*
G02X34658Y1462241I1645J1646D01*
G01Y1462638D01*
G03X34600Y1462780I-200J1D01*
G01X34180Y1463200D01*
G02X33498Y1464845I1645J1646D01*
G02X35825Y1467172I2327J0D01*
G02X37242Y1466690I-1J-2327D01*
G01X37268Y1466669D01*
X37331Y1466648D01*
X37719D01*
X37782Y1466669D01*
X37808Y1466690D01*
G02X39225Y1467172I1418J-1845D01*
G02X41552Y1464845I0J-2327D01*
G02X41318Y1463828I-2327J0D01*
G01X41295Y1463782D01*
X41300Y1463679D01*
X41508Y1463348D01*
G03X41678Y1463254I170J106D01*
G01X44054D01*
G03X44172Y1463293I-1J200D01*
G02X45549Y1463744I1376J-1875D01*
G01X47279D01*
G02X48655Y1463293I-1J-2327D01*
G03X48657Y1463291I141J139D01*
G01X48683Y1463273D01*
X48741Y1463254D01*
X49392D01*
G03X49534Y1463313I0J200D01*
G01X51237Y1465016D01*
G03X51296Y1465158I-141J142D01*
G01Y1466894D01*
G03X51257Y1467012I-200J-1D01*
G02X50806Y1468389I1875J1376D01*
G01Y1470119D01*
G02X51257Y1471496I2326J1D01*
G03X51296Y1471614I-161J119D01*
G01Y1472451D01*
G03X51237Y1472593I-200J0D01*
G01X48838Y1474992D01*
X48782Y1475020D01*
X48751Y1475025D01*
G02X47458Y1475680I353J2300D01*
G01X46234Y1476904D01*
G02X45609Y1478043I1646J1644D01*
G03X45457Y1478195I-195J-43D01*
G02X44318Y1478820I505J2271D01*
G01X43094Y1480044D01*
G02X42469Y1481183I1646J1644D01*
G03X42317Y1481335I-195J-43D01*
G02X41178Y1481960I505J2271D01*
G01X39954Y1483184D01*
G02X39329Y1484323I1646J1644D01*
G03X39177Y1484475I-195J-43D01*
G02X38038Y1485100I505J2271D01*
G01X36814Y1486324D01*
G02X36189Y1487463I1646J1644D01*
G03X36037Y1487615I-195J-43D01*
G02X34898Y1488240I505J2271D01*
G01X33674Y1489464D01*
G02X33049Y1490603I1646J1644D01*
G03X32897Y1490755I-195J-43D01*
G02X31758Y1491380I505J2271D01*
G01X30534Y1492604D01*
G02X29909Y1493743I1646J1644D01*
G03X29757Y1493895I-195J-43D01*
G02X28618Y1494520I505J2271D01*
G01X27394Y1495744D01*
G02X26739Y1497037I1645J1646D01*
G01X26734Y1497068D01*
X26706Y1497124D01*
X26171Y1497660D01*
G02X25490Y1499305I1646J1645D01*
G01Y1503614D01*
G03X25451Y1503732I-200J-1D01*
G02X25000Y1505109I1875J1376D01*
G01Y1506840D01*
G02X25451Y1508216I2326J-1D01*
G03X25490Y1508335I-161J119D01*
G01Y1508809D01*
G03X25451Y1508928I-200J0D01*
G02X25000Y1510304I1875J1377D01*
G01Y1512036D01*
G37*
G36*
G01X63743Y83717D02*
Y84069D01*
X63715Y84138D01*
X63689Y84166D01*
G02X63283Y85193I1096J1027D01*
G02X66287I1502J0D01*
G02X65881Y84166I-1502J0D01*
G01X65855Y84138D01*
X65827Y84069D01*
Y83717D01*
X65855Y83648D01*
X65881Y83620D01*
G02Y81566I-1096J-1027D01*
G01X65855Y81538D01*
X65827Y81469D01*
Y81117D01*
X65855Y81048D01*
X65881Y81020D01*
G02Y78966I-1096J-1027D01*
G01X65855Y78938D01*
X65827Y78869D01*
Y78517D01*
X65855Y78448D01*
X65881Y78420D01*
G02Y76366I-1096J-1027D01*
G01X65855Y76338D01*
X65827Y76269D01*
Y75917D01*
X65855Y75848D01*
X65881Y75820D01*
G02X66287Y74793I-1096J-1027D01*
G02X63283I-1502J0D01*
G02X63689Y75820I1502J0D01*
G01X63715Y75848D01*
X63743Y75917D01*
Y76269D01*
X63715Y76338D01*
X63689Y76366D01*
G02Y78420I1096J1027D01*
G01X63715Y78448D01*
X63743Y78517D01*
Y78869D01*
X63715Y78938D01*
X63689Y78966D01*
G02Y81020I1096J1027D01*
G01X63715Y81048D01*
X63743Y81117D01*
Y81469D01*
X63715Y81538D01*
X63689Y81566D01*
G02Y83620I1096J1027D01*
G01X63715Y83648D01*
X63743Y83717D01*
G37*
G36*
G01X45408Y84108D02*
Y84460D01*
X45380Y84529D01*
X45354Y84557D01*
G02X44948Y85584I1096J1027D01*
G02X47952I1502J0D01*
G02X47546Y84557I-1502J0D01*
G01X47520Y84529D01*
X47492Y84460D01*
Y84108D01*
X47520Y84039D01*
X47546Y84011D01*
G02Y81957I-1096J-1027D01*
G01X47520Y81929D01*
X47492Y81860D01*
Y81508D01*
X47520Y81439D01*
X47546Y81411D01*
G02Y79357I-1096J-1027D01*
G01X47520Y79329D01*
X47492Y79260D01*
Y78908D01*
X47520Y78839D01*
X47546Y78811D01*
G02Y76757I-1096J-1027D01*
G01X47520Y76729D01*
X47492Y76660D01*
Y76308D01*
X47520Y76239D01*
X47546Y76211D01*
G02X47952Y75184I-1096J-1027D01*
G02X44948I-1502J0D01*
G02X45354Y76211I1502J0D01*
G01X45380Y76239D01*
X45408Y76308D01*
Y76660D01*
X45380Y76729D01*
X45354Y76757D01*
G02Y78811I1096J1027D01*
G01X45380Y78839D01*
X45408Y78908D01*
Y79260D01*
X45380Y79329D01*
X45354Y79357D01*
G02Y81411I1096J1027D01*
G01X45380Y81439D01*
X45408Y81508D01*
Y81860D01*
X45380Y81929D01*
X45354Y81957D01*
G02Y84011I1096J1027D01*
G01X45380Y84039D01*
X45408Y84108D01*
G37*
G36*
G01X10776Y116875D02*
X11118Y117068D01*
X11169Y117139D01*
X11178Y117182D01*
G02X12652Y118396I1474J-288D01*
G02X14106Y117269I0J-1501D01*
G01X14117Y117228D01*
X14169Y117162D01*
X14506Y116984D01*
X14590Y116978D01*
X14630Y116993D01*
G02X15143Y117083I512J-1412D01*
G02Y114079I0J-1502D01*
G02X13689Y115206I0J1501D01*
G01X13678Y115247D01*
X13626Y115313D01*
X13289Y115491D01*
X13205Y115497D01*
X13165Y115482D01*
G02X12652Y115392I-512J1412D01*
G02X12135Y115484I1J1502D01*
G01X12094Y115499D01*
X12007Y115492D01*
X11665Y115299D01*
X11614Y115228D01*
X11605Y115185D01*
G02X10131Y113971I-1474J288D01*
G02Y116975I0J1502D01*
G02X10648Y116883I-1J-1502D01*
G01X10689Y116868D01*
X10776Y116875D01*
G37*
G36*
G01X28937Y137670D02*
X29253Y137881D01*
X29298Y137950D01*
X29305Y137992D01*
G02X30788Y139259I1483J-234D01*
G02Y136255I0J-1502D01*
G02X30520Y136279I-1J1502D01*
G03X30354Y136234I-36J-197D01*
G01X30258Y136151D01*
G03X30189Y135991I131J-151D01*
G02X30190Y135915I-1801J-62D01*
G01Y132515D01*
G02X30189Y132436I-1802J-17D01*
G03X30258Y132276I200J-9D01*
G01X30354Y132193D01*
G03X30520Y132148I130J152D01*
G02X30788Y132172I267J-1478D01*
G02X31775Y131802I0J-1501D01*
G01X31803Y131778D01*
X31870Y131753D01*
X32206D01*
X32273Y131778D01*
X32301Y131802D01*
G02X33288Y132172I987J-1131D01*
G02X34771Y130905I0J-1501D01*
G01X34778Y130863D01*
X34823Y130794D01*
X35139Y130583D01*
X35220Y130569D01*
X35261Y130579D01*
G02X35688Y130630I426J-1751D01*
G02X36036Y130597I5J-1802D01*
G01X36076Y130589D01*
X36154Y130605D01*
X36458Y130814D01*
X36500Y130881D01*
X36507Y130922D01*
G02X37988Y132172I1481J-252D01*
G02Y129168I0J-1502D01*
G02X37807Y129179I0J1502D01*
G03X37649Y129128I-23J-199D01*
G01X37555Y129043D01*
G03X37489Y128888I134J-149D01*
G02X37490Y128828I-1801J-60D01*
G01Y125428D01*
G02X37489Y125365I-1802J-3D01*
G03X37555Y125210I200J-6D01*
G01X37649Y125125D01*
G03X37807Y125074I135J148D01*
G02X37988Y125085I181J-1491D01*
G02Y122081I0J-1502D01*
G02X36507Y123333I0J1502D01*
G01X36500Y123374D01*
X36457Y123441D01*
X36154Y123651D01*
X36076Y123667D01*
X36035Y123659D01*
G02X35688Y123626I-343J1769D01*
G02X35262Y123677I0J1802D01*
G01X35220Y123687D01*
X35139Y123672D01*
X34823Y123462D01*
X34778Y123392D01*
X34772Y123350D01*
G02X33288Y122081I-1484J233D01*
G02X32300Y122451I-1J1502D01*
G01X32273Y122476D01*
X32206Y122501D01*
X31869D01*
X31803Y122476D01*
X31775Y122452D01*
G02X30788Y122082I-987J1131D01*
G02X30520Y122106I-1J1502D01*
G03X30354Y122061I-36J-197D01*
G01X30258Y121978D01*
G03X30189Y121818I131J-151D01*
G02X30190Y121742I-1801J-62D01*
G01Y118342D01*
G02X30189Y118263I-1802J-17D01*
G03X30258Y118103I200J-9D01*
G01X30354Y118020D01*
G03X30520Y117975I130J152D01*
G02X30788Y117999I267J-1478D01*
G02X31775Y117629I0J-1501D01*
G01X31803Y117605D01*
X31870Y117580D01*
X32206D01*
X32273Y117605D01*
X32301Y117629D01*
G02X33288Y117999I987J-1131D01*
G02X34771Y116732I0J-1501D01*
G01X34778Y116690D01*
X34823Y116621D01*
X35139Y116410D01*
X35220Y116396D01*
X35261Y116406D01*
G02X35688Y116458I430J-1751D01*
G02X36036Y116424I0J-1803D01*
G01X36076Y116416D01*
X36154Y116432D01*
X36458Y116641D01*
X36500Y116708D01*
X36507Y116749D01*
G02X37988Y117998I1481J-254D01*
G02Y114994I0J-1502D01*
G02X37807Y115005I0J1502D01*
G03X37649Y114954I-23J-199D01*
G01X37555Y114869D01*
G03X37490Y114714I135J-148D01*
G01Y111255D01*
G02X37489Y111192I-1802J-3D01*
G03X37555Y111037I200J-6D01*
G01X37649Y110952D01*
G03X37807Y110901I135J148D01*
G02X37988Y110912I181J-1491D01*
G02Y107908I0J-1502D01*
G02X36507Y109160I0J1502D01*
G01X36500Y109201D01*
X36457Y109268D01*
X36154Y109478D01*
X36076Y109494D01*
X36035Y109486D01*
G02X35688Y109452I-348J1769D01*
G02X35262Y109504I4J1803D01*
G01X35220Y109514D01*
X35139Y109499D01*
X34823Y109289D01*
X34778Y109219D01*
X34772Y109177D01*
G02X33288Y107908I-1484J233D01*
G02Y110912I0J1502D01*
G02X33556Y110888I1J-1502D01*
G03X33722Y110933I36J197D01*
G01X33818Y111016D01*
G03X33887Y111176I-131J151D01*
G02X33886Y111255I1801J62D01*
G01Y114655D01*
G02X33887Y114731I1802J14D01*
G03X33818Y114891I-200J9D01*
G01X33722Y114974D01*
G03X33556Y115019I-130J-152D01*
G02X33288Y114995I-267J1478D01*
G02X32301Y115365I0J1501D01*
G01X32273Y115389D01*
X32206Y115414D01*
X31870D01*
X31803Y115389D01*
X31775Y115365D01*
G02X30788Y114995I-987J1131D01*
G02X29304Y116264I0J1502D01*
G01X29298Y116306D01*
X29253Y116376D01*
X28937Y116586D01*
X28856Y116601D01*
X28814Y116591D01*
G02X28388Y116540I-426J1751D01*
G02X27962Y116591I0J1802D01*
G01X27920Y116601D01*
X27839Y116586D01*
X27523Y116376D01*
X27478Y116306D01*
X27472Y116264D01*
G02X25988Y114995I-1484J233D01*
G02Y117999I0J1502D01*
G02X26256Y117975I1J-1502D01*
G03X26422Y118020I36J197D01*
G01X26518Y118103D01*
G03X26587Y118263I-131J151D01*
G02X26586Y118342I1801J62D01*
G01Y121742D01*
G02X26587Y121818I1802J14D01*
G03X26518Y121978I-200J9D01*
G01X26422Y122061D01*
G03X26256Y122106I-130J-152D01*
G02X25988Y122082I-267J1478D01*
G02Y125086I0J1502D01*
G02X27471Y123819I0J-1501D01*
G01X27478Y123777D01*
X27523Y123708D01*
X27839Y123497D01*
X27920Y123483D01*
X27961Y123493D01*
G02X28388Y123544I426J-1751D01*
G02X28815Y123493I1J-1802D01*
G01X28856Y123483D01*
X28937Y123497D01*
X29253Y123708D01*
X29298Y123777D01*
X29305Y123819D01*
G02X30788Y125086I1483J-234D01*
G02X31776Y124716I1J-1502D01*
G01X31803Y124691D01*
X31870Y124666D01*
X32207D01*
X32273Y124691D01*
X32301Y124715D01*
G02X33288Y125085I987J-1131D01*
G02X33556Y125061I1J-1502D01*
G03X33722Y125106I36J197D01*
G01X33818Y125189D01*
G03X33887Y125349I-131J151D01*
G02X33886Y125428I1801J62D01*
G01Y128828D01*
G02X33887Y128904I1802J14D01*
G03X33818Y129064I-200J9D01*
G01X33722Y129147D01*
G03X33556Y129192I-130J-152D01*
G02X33288Y129168I-267J1478D01*
G02X32301Y129538I0J1501D01*
G01X32273Y129562D01*
X32206Y129587D01*
X31870D01*
X31803Y129562D01*
X31775Y129538D01*
G02X30788Y129168I-987J1131D01*
G02X29304Y130437I0J1502D01*
G01X29298Y130479D01*
X29253Y130549D01*
X28937Y130759D01*
X28856Y130774D01*
X28814Y130764D01*
G02X28388Y130712I-430J1751D01*
G02X27962Y130764I4J1803D01*
G01X27920Y130774D01*
X27839Y130759D01*
X27523Y130549D01*
X27478Y130479D01*
X27472Y130437D01*
G02X25988Y129168I-1484J233D01*
G02Y132172I0J1502D01*
G02X26256Y132148I1J-1502D01*
G03X26422Y132193I36J197D01*
G01X26518Y132276D01*
G03X26587Y132436I-131J151D01*
G02X26586Y132515I1801J62D01*
G01Y135915D01*
G02X26587Y135991I1802J14D01*
G03X26518Y136151I-200J9D01*
G01X26422Y136234D01*
G03X26256Y136279I-130J-152D01*
G02X25988Y136255I-267J1478D01*
G02Y139259I0J1502D01*
G02X27471Y137992I0J-1501D01*
G01X27478Y137950D01*
X27523Y137881D01*
X27839Y137670D01*
X27920Y137656D01*
X27961Y137666D01*
G02X28388Y137718I430J-1751D01*
G02X28815Y137666I-3J-1803D01*
G01X28856Y137656D01*
X28937Y137670D01*
G37*
G36*
G01X27859Y150805D02*
X27543D01*
G03X27386Y150728I1J-200D01*
G02X26201Y150149I-1185J923D01*
G02Y153153I0J1502D01*
G02X27386Y152574I0J-1502D01*
G03X27543Y152497I158J123D01*
G01X27859D01*
G03X28016Y152574I-1J200D01*
G02X29201Y153153I1185J-923D01*
G02Y150149I0J-1502D01*
G02X28016Y150728I0J1502D01*
G03X27859Y150805I-158J-123D01*
G37*
G36*
G01X14102Y196259D02*
X14438D01*
X14505Y196284D01*
X14533Y196308D01*
G02X15520Y196678I987J-1131D01*
G02X16626Y196193I1J-1502D01*
G03X16773Y196128I148J135D01*
G01X17067D01*
G03X17214Y196193I-1J200D01*
G02X18320Y196678I1105J-1017D01*
G02Y193674I0J-1502D01*
G02X17214Y194159I-1J1502D01*
G03X17067Y194224I-148J-135D01*
G01X16773D01*
G03X16626Y194159I1J-200D01*
G02X15520Y193674I-1105J1017D01*
G02X14533Y194044I0J1501D01*
G01X14505Y194068D01*
X14438Y194093D01*
X14102D01*
X14035Y194068D01*
X14007Y194044D01*
G02X12033I-987J1131D01*
G01X12005Y194068D01*
X11938Y194093D01*
X11602D01*
X11535Y194068D01*
X11507Y194044D01*
G02X10520Y193674I-987J1131D01*
G02Y196678I0J1502D01*
G02X11507Y196308I0J-1501D01*
G01X11535Y196284D01*
X11602Y196259D01*
X11938D01*
X12005Y196284D01*
X12033Y196308D01*
G02X14007I987J-1131D01*
G01X14035Y196284D01*
X14102Y196259D01*
G37*
G36*
G01X11798Y202310D02*
X11462D01*
X11395Y202285D01*
X11367Y202261D01*
G02X10380Y201891I-987J1131D01*
G02Y204895I0J1502D01*
G02X11367Y204525I0J-1501D01*
G01X11395Y204501D01*
X11462Y204476D01*
X11798D01*
X11865Y204501D01*
X11893Y204525D01*
G02X12880Y204895I987J-1131D01*
G02X14377Y203517I0J-1502D01*
G01X14380Y203474D01*
X14421Y203400D01*
X14728Y203168D01*
X14809Y203149D01*
X14852Y203157D01*
G02X15139Y203185I289J-1474D01*
G02X16641Y201683I0J-1502D01*
G02X16156Y200577I-1502J-1D01*
G03X16091Y200430I135J-148D01*
G01Y200136D01*
G03X16156Y199989I200J1D01*
G02X16641Y198883I-1017J-1105D01*
G02X13637I-1502J0D01*
G02X14122Y199989I1502J1D01*
G03X14187Y200136I-135J148D01*
G01Y200430D01*
G03X14122Y200577I-200J-1D01*
G02X13642Y201559I1017J1105D01*
G01X13639Y201602D01*
X13598Y201676D01*
X13291Y201908D01*
X13210Y201927D01*
X13167Y201919D01*
G02X12880Y201891I-289J1474D01*
G02X11893Y202261I0J1501D01*
G01X11865Y202285D01*
X11798Y202310D01*
G37*
G36*
G01X17986Y205755D02*
X17650D01*
X17583Y205730D01*
X17555Y205706D01*
G02X16568Y205336I-987J1131D01*
G02Y208340I0J1502D01*
G02X17555Y207970I0J-1501D01*
G01X17583Y207946D01*
X17650Y207921D01*
X17986D01*
X18053Y207946D01*
X18081Y207970D01*
G02X19068Y208340I987J-1131D01*
G02Y205336I0J-1502D01*
G02X18081Y205706I0J1501D01*
G01X18053Y205730D01*
X17986Y205755D01*
G37*
G36*
G01X11806Y217133D02*
X11512D01*
G03X11365Y217068I1J-200D01*
G02X10259Y216583I-1105J1017D01*
G02Y219587I0J1502D01*
G02X11365Y219102I1J-1502D01*
G03X11512Y219037I148J135D01*
G01X11806D01*
G03X11953Y219102I-1J200D01*
G02X13059Y219587I1105J-1017D01*
G02Y216583I0J-1502D01*
G02X11953Y217068I-1J1502D01*
G03X11806Y217133I-148J-135D01*
G37*
G36*
G01X18489Y220552D02*
Y220888D01*
X18464Y220955D01*
X18440Y220983D01*
G02X18070Y221970I1131J987D01*
G02X21074I1502J0D01*
G02X20704Y220983I-1501J0D01*
G01X20680Y220955D01*
X20655Y220888D01*
Y220552D01*
X20680Y220485D01*
X20704Y220457D01*
G02Y218483I-1131J-987D01*
G01X20680Y218455D01*
X20655Y218388D01*
Y218052D01*
X20680Y217985D01*
X20704Y217957D01*
G02X21074Y216970I-1131J-987D01*
G02X19572Y215468I-1502J0D01*
G02X18717Y215735I0J1502D01*
G01X18683Y215759D01*
X18602Y215775D01*
X18235Y215696D01*
X18168Y215648D01*
X18147Y215612D01*
G02X16859Y214883I-1288J773D01*
G02Y217887I0J1502D01*
G02X17714Y217620I0J-1502D01*
G01X17748Y217596D01*
X17829Y217580D01*
X18196Y217659D01*
X18263Y217707D01*
X18284Y217743D01*
G02X18440Y217957I1287J-774D01*
G01X18464Y217985D01*
X18489Y218052D01*
Y218388D01*
X18464Y218455D01*
X18440Y218483D01*
G02Y220457I1131J987D01*
G01X18464Y220485D01*
X18489Y220552D01*
G37*
G36*
G01X30290Y266201D02*
X29889Y266257D01*
X29803Y266230D01*
X29770Y266199D01*
G02X28740Y265790I-1030J1092D01*
G02Y268794I0J1502D01*
G02X30034Y268055I0J-1502D01*
G01X30057Y268016D01*
X30132Y267965D01*
X30533Y267909D01*
X30619Y267936D01*
X30652Y267967D01*
G02X31682Y268376I1030J-1092D01*
G02Y265372I0J-1502D01*
G02X30388Y266111I0J1502D01*
G01X30365Y266150D01*
X30290Y266201D01*
G37*
G36*
G01X46865Y92378D02*
G02X46862Y92473I1499J95D01*
G02X48364Y90971I1502J0D01*
G02X47987Y91019I0J1502D01*
G03X47487Y90607I-101J-387D01*
G02X47490Y90512I-1499J-95D01*
G02X45988Y92014I-1502J0D01*
G02X46365Y91966I0J-1502D01*
G03X46865Y92378I101J387D01*
G37*
G36*
G01X12779Y94009D02*
X12774Y94049D01*
G02X12762Y94236I1490J189D01*
G02X15766I1502J0D01*
G02X14441Y92744I-1503J0D01*
G01X14401Y92740D01*
X14332Y92701D01*
X14107Y92414D01*
X14086Y92337D01*
X14091Y92297D01*
G02X14103Y92110I-1490J-189D01*
G02X11099I-1502J0D01*
G02X11114Y92325I1502J3D01*
G01X11122Y92375D01*
X11089Y92467D01*
X10772Y92759D01*
X10678Y92784D01*
X10629Y92772D01*
G02X10292Y92734I-336J1464D01*
G02X11794Y94236I0J1502D01*
G02X11779Y94021I-1502J-3D01*
G01X11771Y93971D01*
X11804Y93879D01*
X12121Y93587D01*
X12215Y93562D01*
X12264Y93574D01*
G02X12424Y93602I339J-1464D01*
G01X12464Y93606D01*
X12533Y93645D01*
X12758Y93932D01*
X12779Y94009D01*
G37*
G36*
G01X55045Y101849D02*
G02X54462Y103037I919J1188D01*
G02X57466I1502J0D01*
G02X56810Y101796I-1502J0D01*
G03X56790Y101149I225J-331D01*
G02X57373Y99961I-919J-1188D01*
G02X54369I-1502J0D01*
G02X55025Y101202I1502J0D01*
G03X55045Y101849I-225J331D01*
G37*
G36*
G01X34346Y105329D02*
X34306Y105360D01*
G02X33705Y106561I901J1202D01*
G02X36709I1502J0D01*
G02X35983Y105275I-1502J0D01*
G01X35940Y105249D01*
X35889Y105164D01*
X35867Y104732D01*
X35909Y104643D01*
X35949Y104612D01*
G02X36504Y103779I-901J-1202D01*
G01X36516Y103731D01*
X36582Y103658D01*
X36985Y103509D01*
X37081Y103522D01*
X37122Y103550D01*
G02X37988Y103825I866J-1226D01*
G02Y100821I0J-1502D01*
G02X36532Y101955I0J1502D01*
G01X36520Y102003D01*
X36454Y102076D01*
X36051Y102225D01*
X35955Y102212D01*
X35914Y102184D01*
G02X35048Y101909I-866J1226D01*
G02X33546Y103411I0J1502D01*
G02X34272Y104697I1502J0D01*
G01X34315Y104723D01*
X34366Y104808D01*
X34388Y105240D01*
X34346Y105329D01*
G37*
G36*
G01X8225Y137689D02*
G02X7555Y138939I831J1250D01*
G02X10559I1502J0D01*
G02X9909Y137702I-1502J0D01*
G03X9914Y137039I227J-330D01*
G02X10584Y135789I-831J-1250D01*
G02X7580I-1502J0D01*
G02X8230Y137026I1502J0D01*
G03X8225Y137689I-227J330D01*
G37*
G36*
G01X10043Y160888D02*
G02X9464Y162073I923J1185D01*
G02X12468I1502J0D01*
G02X11889Y160888I-1502J0D01*
G03X11812Y160731I123J-158D01*
G01Y160415D01*
G03X11889Y160258I200J1D01*
G02X12468Y159073I-923J-1185D01*
G02X11778Y157809I-1503J0D01*
G03X11686Y157641I108J-168D01*
G01Y157305D01*
G03X11778Y157137I200J0D01*
G02X12468Y155873I-813J-1264D01*
G02X11889Y154688I-1502J0D01*
G03X11812Y154531I123J-158D01*
G01Y154215D01*
G03X11889Y154058I200J1D01*
G02X11934Y154021I-931J-1178D01*
G03X12092Y153976I129J153D01*
G01X12218Y153995D01*
G03X12357Y154083I-28J198D01*
G02X13615Y154765I1258J-819D01*
G02X14916Y154014I0J-1502D01*
G03X15089Y153914I173J100D01*
G01X15435D01*
G03X15608Y154014I0J200D01*
G02X16909Y154765I1301J-751D01*
G02Y151761I0J-1502D01*
G02X15608Y152512I0J1502D01*
G03X15435Y152612I-173J-100D01*
G01X15089D01*
G03X14916Y152512I0J-200D01*
G02X13615Y151761I-1301J751D01*
G02X12724Y152054I0J1501D01*
G01X12692Y152077D01*
X12617Y152096D01*
X12258Y152043D01*
X12192Y152004D01*
X12167Y151971D01*
G02X10966Y151371I-1201J902D01*
G02X9464Y152873I0J1502D01*
G02X10043Y154058I1502J0D01*
G03X10120Y154215I-123J158D01*
G01Y154531D01*
G03X10043Y154688I-200J-1D01*
G02X9464Y155873I923J1185D01*
G02X10154Y157137I1503J0D01*
G03X10246Y157305I-108J168D01*
G01Y157641D01*
G03X10154Y157809I-200J0D01*
G02X9464Y159073I813J1264D01*
G02X10043Y160258I1502J0D01*
G03X10120Y160415I-123J158D01*
G01Y160731D01*
G03X10043Y160888I-200J-1D01*
G37*
G36*
G01X20698Y234870D02*
G02X20028Y236121I833J1251D01*
G02X23032I1502J0D01*
G02X22382Y234884I-1502J0D01*
G03X22388Y234222I227J-329D01*
G02X23058Y232971I-833J-1251D01*
G02X20054I-1502J0D01*
G02X20704Y234208I1502J0D01*
G03X20698Y234870I-227J329D01*
G37*
G36*
G01X29803Y246230D02*
X29770Y246199D01*
G02X28740Y245790I-1030J1092D01*
G02Y248794I0J1502D01*
G02X30034Y248055I0J-1502D01*
G01X30057Y248016D01*
X30132Y247965D01*
X30533Y247909D01*
X30619Y247936D01*
X30652Y247967D01*
G02X31682Y248376I1030J-1092D01*
G02X33184Y246874I0J-1502D01*
G02X33068Y246295I-1503J0D01*
G01X33046Y246242D01*
X33064Y246131D01*
X33372Y245773D01*
X33479Y245739D01*
X33535Y245753D01*
G02X33902Y245799I369J-1456D01*
G02X32400Y244297I0J-1502D01*
G02X32516Y244876I1503J0D01*
G01X32538Y244929D01*
X32520Y245040D01*
X32212Y245398D01*
X32105Y245432D01*
X32049Y245418D01*
G02X31682Y245372I-369J1456D01*
G02X30388Y246111I0J1502D01*
G01X30365Y246150D01*
X30290Y246201D01*
X29889Y246257D01*
X29803Y246230D01*
G37*
G36*
G01X146948Y1138210D02*
G02Y1135604I0J-1303D01*
G01X143208D01*
G02Y1138210I0J1303D01*
G01X146948D01*
G37*
G36*
G01X165649Y1134470D02*
G02Y1131864I0J-1303D01*
G01X161909D01*
G02Y1134470I0J1303D01*
G01X165649D01*
G37*
G36*
G01X154429D02*
G02Y1131864I0J-1303D01*
G01X150689D01*
G02Y1134470I0J1303D01*
G01X154429D01*
G37*
G36*
G01X173129Y1138210D02*
G02Y1135604I0J-1303D01*
G01X169389D01*
G02Y1138210I0J1303D01*
G01X173129D01*
G37*
G36*
G01X102572Y1008703D02*
X102278D01*
G03X102131Y1008638I1J-200D01*
G02X101025Y1008153I-1105J1017D01*
G02Y1011157I0J1502D01*
G02X102131Y1010672I1J-1502D01*
G03X102278Y1010607I148J135D01*
G01X102572D01*
G03X102719Y1010672I-1J200D01*
G02X103825Y1011157I1105J-1017D01*
G02Y1008153I0J-1502D01*
G02X102719Y1008638I-1J1502D01*
G03X102572Y1008703I-148J-135D01*
G37*
G36*
G01X135705Y1010637D02*
X135699Y1011046D01*
X135658Y1011127D01*
X135621Y1011156D01*
G02X135024Y1012354I905J1199D01*
G02X138028I1502J0D01*
G02X137467Y1011183I-1503J0D01*
G01X137431Y1011154D01*
X137392Y1011071D01*
X137398Y1010662D01*
X137439Y1010581D01*
X137476Y1010552D01*
G02X138073Y1009354I-905J-1199D01*
G02X135069I-1502J0D01*
G02X135630Y1010525I1503J0D01*
G01X135666Y1010554D01*
X135705Y1010637D01*
G37*
G36*
G01Y1023237D02*
X135699Y1023646D01*
X135658Y1023727D01*
X135621Y1023756D01*
G02X135024Y1024954I905J1199D01*
G02X138028I1502J0D01*
G02X137467Y1023783I-1503J0D01*
G01X137431Y1023754D01*
X137392Y1023671D01*
X137398Y1023262D01*
X137439Y1023181D01*
X137476Y1023152D01*
G02X138073Y1021954I-905J-1199D01*
G02X135069I-1502J0D01*
G02X135630Y1023125I1503J0D01*
G01X135666Y1023154D01*
X135705Y1023237D01*
G37*
G36*
G01X87452Y1024880D02*
X87426Y1025259D01*
X87387Y1025334D01*
X87354Y1025360D01*
G02X86785Y1026537I933J1177D01*
G02X89789I1502J0D01*
G02X89372Y1025498I-1503J0D01*
G01X89342Y1025467D01*
X89314Y1025388D01*
X89340Y1025009D01*
X89379Y1024934D01*
X89412Y1024908D01*
G02X89981Y1023731I-933J-1177D01*
G02X86977I-1502J0D01*
G02X87394Y1024770I1503J0D01*
G01X87424Y1024801D01*
X87452Y1024880D01*
G37*
G36*
G01X106312Y1031518D02*
X106628D01*
G03X106785Y1031595I-1J200D01*
G02X109155I1185J-923D01*
G03X109312Y1031518I158J123D01*
G01X109628D01*
G03X109785Y1031595I-1J200D01*
G02X110970Y1032174I1185J-923D01*
G02Y1029170I0J-1502D01*
G02X109785Y1029749I0J1502D01*
G03X109628Y1029826I-158J-123D01*
G01X109312D01*
G03X109155Y1029749I1J-200D01*
G02X106785I-1185J923D01*
G03X106628Y1029826I-158J-123D01*
G01X106312D01*
G03X106155Y1029749I1J-200D01*
G02X103785I-1185J923D01*
G03X103628Y1029826I-158J-123D01*
G01X103312D01*
G03X103155Y1029749I1J-200D01*
G02X101970Y1029170I-1185J923D01*
G02Y1032174I0J1502D01*
G02X103155Y1031595I0J-1502D01*
G03X103312Y1031518I158J123D01*
G01X103628D01*
G03X103785Y1031595I-1J200D01*
G02X106155I1185J-923D01*
G03X106312Y1031518I158J123D01*
G37*
G36*
G01X61263Y1085998D02*
Y1086314D01*
G03X61186Y1086471I-200J-1D01*
G02X60607Y1087656I923J1185D01*
G02X63611I1502J0D01*
G02X63032Y1086471I-1502J0D01*
G03X62955Y1086314I123J-158D01*
G01Y1085998D01*
G03X63032Y1085841I200J1D01*
G02X63611Y1084656I-923J-1185D01*
G02X60607I-1502J0D01*
G02X61186Y1085841I1502J0D01*
G03X61263Y1085998I-123J158D01*
G37*
G36*
G01X25045Y1102377D02*
X25397D01*
X25466Y1102405D01*
X25494Y1102431D01*
G02X27548I1027J-1096D01*
G01X27576Y1102405D01*
X27645Y1102377D01*
X27997D01*
X28066Y1102405D01*
X28094Y1102431D01*
G02X29121Y1102837I1027J-1096D01*
G02X30623Y1101335I0J-1502D01*
G02X30230Y1100322I-1502J0D01*
G01X30204Y1100294D01*
X30177Y1100225D01*
Y1099879D01*
X30204Y1099810D01*
X30230Y1099782D01*
G02X30623Y1098769I-1109J-1013D01*
G02X29121Y1097267I-1502J0D01*
G02X28094Y1097673I0J1502D01*
G01X28066Y1097699D01*
X27997Y1097727D01*
X27645D01*
X27576Y1097699D01*
X27548Y1097673D01*
G02X25494I-1027J1096D01*
G01X25466Y1097699D01*
X25397Y1097727D01*
X25045D01*
X24976Y1097699D01*
X24948Y1097673D01*
G02X22894I-1027J1096D01*
G01X22866Y1097699D01*
X22797Y1097727D01*
X22445D01*
X22376Y1097699D01*
X22348Y1097673D01*
G02X21321Y1097267I-1027J1096D01*
G02X19819Y1098769I0J1502D01*
G02X20212Y1099782I1502J0D01*
G01X20238Y1099810D01*
X20265Y1099879D01*
Y1100225D01*
X20238Y1100294D01*
X20212Y1100322D01*
G02X19819Y1101335I1109J1013D01*
G02X21321Y1102837I1502J0D01*
G02X22348Y1102431I0J-1502D01*
G01X22376Y1102405D01*
X22445Y1102377D01*
X22797D01*
X22866Y1102405D01*
X22894Y1102431D01*
G02X24948I1027J-1096D01*
G01X24976Y1102405D01*
X25045Y1102377D01*
G37*
G36*
G01X124059Y1103374D02*
X124053Y1103783D01*
X124012Y1103864D01*
X123975Y1103893D01*
G02X123378Y1105091I905J1199D01*
G02X126382I1502J0D01*
G02X125821Y1103920I-1503J0D01*
G01X125785Y1103891D01*
X125746Y1103808D01*
X125752Y1103399D01*
X125793Y1103318D01*
X125830Y1103289D01*
G02X126427Y1102091I-905J-1199D01*
G02X123423I-1502J0D01*
G02X123984Y1103262I1503J0D01*
G01X124020Y1103291D01*
X124059Y1103374D01*
G37*
G36*
G01X43383Y1106142D02*
X43735D01*
X43804Y1106170D01*
X43832Y1106196D01*
G02X44859Y1106602I1027J-1096D01*
G02X45925Y1106158I0J-1502D01*
G01X45953Y1106129D01*
X46027Y1106099D01*
X46391D01*
X46465Y1106129D01*
X46493Y1106158D01*
G02X47559Y1106602I1066J-1058D01*
G02Y1103598I0J-1502D01*
G02X46493Y1104042I0J1502D01*
G01X46465Y1104071D01*
X46391Y1104101D01*
X46027D01*
X45953Y1104071D01*
X45925Y1104042D01*
G02X44859Y1103598I-1066J1058D01*
G02X43832Y1104004I0J1502D01*
G01X43804Y1104030D01*
X43735Y1104058D01*
X43383D01*
X43314Y1104030D01*
X43286Y1104004D01*
G02X41232I-1027J1096D01*
G01X41204Y1104030D01*
X41135Y1104058D01*
X40783D01*
X40714Y1104030D01*
X40686Y1104004D01*
G02X39659Y1103598I-1027J1096D01*
G02Y1106602I0J1502D01*
G02X40686Y1106196I0J-1502D01*
G01X40714Y1106170D01*
X40783Y1106142D01*
X41135D01*
X41204Y1106170D01*
X41232Y1106196D01*
G02X43286I1027J-1096D01*
G01X43314Y1106170D01*
X43383Y1106142D01*
G37*
G36*
G01X60105D02*
X60457D01*
X60526Y1106170D01*
X60554Y1106196D01*
G02X61581Y1106602I1027J-1096D01*
G02X62647Y1106158I0J-1502D01*
G01X62675Y1106129D01*
X62749Y1106099D01*
X63113D01*
X63187Y1106129D01*
X63215Y1106158D01*
G02X64281Y1106602I1066J-1058D01*
G02Y1103598I0J-1502D01*
G02X63215Y1104042I0J1502D01*
G01X63187Y1104071D01*
X63113Y1104101D01*
X62749D01*
X62675Y1104071D01*
X62647Y1104042D01*
G02X61581Y1103598I-1066J1058D01*
G02X60554Y1104004I0J1502D01*
G01X60526Y1104030D01*
X60457Y1104058D01*
X60105D01*
X60036Y1104030D01*
X60008Y1104004D01*
G02X57954I-1027J1096D01*
G01X57926Y1104030D01*
X57857Y1104058D01*
X57505D01*
X57436Y1104030D01*
X57408Y1104004D01*
G02X56381Y1103598I-1027J1096D01*
G02Y1106602I0J1502D01*
G02X57408Y1106196I0J-1502D01*
G01X57436Y1106170D01*
X57505Y1106142D01*
X57857D01*
X57926Y1106170D01*
X57954Y1106196D01*
G02X60008I1027J-1096D01*
G01X60036Y1106170D01*
X60105Y1106142D01*
G37*
G36*
G01X12620Y1112632D02*
X12984D01*
X13058Y1112662D01*
X13086Y1112691D01*
G02X14152Y1113135I1066J-1058D01*
G02X15139Y1112765I0J-1501D01*
G01X15167Y1112741D01*
X15234Y1112716D01*
X15570D01*
X15637Y1112741D01*
X15665Y1112765D01*
G02X16652Y1113135I987J-1131D01*
G02Y1110131I0J-1502D01*
G02X15665Y1110501I0J1501D01*
G01X15637Y1110525D01*
X15570Y1110550D01*
X15234D01*
X15167Y1110525D01*
X15139Y1110501D01*
G02X14152Y1110131I-987J1131D01*
G02X13086Y1110575I0J1502D01*
G01X13058Y1110604D01*
X12984Y1110634D01*
X12620D01*
X12546Y1110604D01*
X12518Y1110575D01*
G02X11452Y1110131I-1066J1058D01*
G02X10425Y1110537I0J1502D01*
G01X10397Y1110563D01*
X10328Y1110591D01*
X9976D01*
X9907Y1110563D01*
X9879Y1110537D01*
G02X8852Y1110131I-1027J1096D01*
G02Y1113135I0J1502D01*
G02X9879Y1112729I0J-1502D01*
G01X9907Y1112703D01*
X9976Y1112675D01*
X10328D01*
X10397Y1112703D01*
X10425Y1112729D01*
G02X11452Y1113135I1027J-1096D01*
G02X12518Y1112691I0J-1502D01*
G01X12546Y1112662D01*
X12620Y1112632D01*
G37*
G36*
G01X28398Y1112675D02*
X28750D01*
X28819Y1112703D01*
X28847Y1112729D01*
G02X29874Y1113135I1027J-1096D01*
G02X30940Y1112691I0J-1502D01*
G01X30968Y1112662D01*
X31042Y1112632D01*
X31406D01*
X31480Y1112662D01*
X31508Y1112691D01*
G02X32574Y1113135I1066J-1058D01*
G02Y1110131I0J-1502D01*
G02X31508Y1110575I0J1502D01*
G01X31480Y1110604D01*
X31406Y1110634D01*
X31042D01*
X30968Y1110604D01*
X30940Y1110575D01*
G02X29874Y1110131I-1066J1058D01*
G02X28847Y1110537I0J1502D01*
G01X28819Y1110563D01*
X28750Y1110591D01*
X28398D01*
X28329Y1110563D01*
X28301Y1110537D01*
G02X26247I-1027J1096D01*
G01X26219Y1110563D01*
X26150Y1110591D01*
X25798D01*
X25729Y1110563D01*
X25701Y1110537D01*
G02X24674Y1110131I-1027J1096D01*
G02Y1113135I0J1502D01*
G02X25701Y1112729I0J-1502D01*
G01X25729Y1112703D01*
X25798Y1112675D01*
X26150D01*
X26219Y1112703D01*
X26247Y1112729D01*
G02X28301I1027J-1096D01*
G01X28329Y1112703D01*
X28398Y1112675D01*
G37*
G36*
G01X43383Y1115842D02*
X43735D01*
X43804Y1115870D01*
X43832Y1115896D01*
G02X44859Y1116302I1027J-1096D01*
G02X45925Y1115858I0J-1502D01*
G01X45953Y1115829D01*
X46027Y1115799D01*
X46391D01*
X46465Y1115829D01*
X46493Y1115858D01*
G02X47559Y1116302I1066J-1058D01*
G02Y1113298I0J-1502D01*
G02X46493Y1113742I0J1502D01*
G01X46465Y1113771D01*
X46391Y1113801D01*
X46027D01*
X45953Y1113771D01*
X45925Y1113742D01*
G02X44859Y1113298I-1066J1058D01*
G02X43832Y1113704I0J1502D01*
G01X43804Y1113730D01*
X43735Y1113758D01*
X43383D01*
X43314Y1113730D01*
X43286Y1113704D01*
G02X41232I-1027J1096D01*
G01X41204Y1113730D01*
X41135Y1113758D01*
X40783D01*
X40714Y1113730D01*
X40686Y1113704D01*
G02X39659Y1113298I-1027J1096D01*
G02Y1116302I0J1502D01*
G02X40686Y1115896I0J-1502D01*
G01X40714Y1115870D01*
X40783Y1115842D01*
X41135D01*
X41204Y1115870D01*
X41232Y1115896D01*
G02X43286I1027J-1096D01*
G01X43314Y1115870D01*
X43383Y1115842D01*
G37*
G36*
G01X60205D02*
X60557D01*
X60626Y1115870D01*
X60654Y1115896D01*
G02X61681Y1116302I1027J-1096D01*
G02X62747Y1115858I0J-1502D01*
G01X62775Y1115829D01*
X62849Y1115799D01*
X63213D01*
X63287Y1115829D01*
X63315Y1115858D01*
G02X64381Y1116302I1066J-1058D01*
G02Y1113298I0J-1502D01*
G02X63315Y1113742I0J1502D01*
G01X63287Y1113771D01*
X63213Y1113801D01*
X62849D01*
X62775Y1113771D01*
X62747Y1113742D01*
G02X61681Y1113298I-1066J1058D01*
G02X60654Y1113704I0J1502D01*
G01X60626Y1113730D01*
X60557Y1113758D01*
X60205D01*
X60136Y1113730D01*
X60108Y1113704D01*
G02X58054I-1027J1096D01*
G01X58026Y1113730D01*
X57957Y1113758D01*
X57605D01*
X57536Y1113730D01*
X57508Y1113704D01*
G02X56481Y1113298I-1027J1096D01*
G02Y1116302I0J1502D01*
G02X57508Y1115896I0J-1502D01*
G01X57536Y1115870D01*
X57605Y1115842D01*
X57957D01*
X58026Y1115870D01*
X58054Y1115896D01*
G02X60108I1027J-1096D01*
G01X60136Y1115870D01*
X60205Y1115842D01*
G37*
G36*
G01X124059Y1115974D02*
X124053Y1116383D01*
X124012Y1116464D01*
X123975Y1116493D01*
G02X123378Y1117691I905J1199D01*
G02X126382I1502J0D01*
G02X125821Y1116520I-1503J0D01*
G01X125785Y1116491D01*
X125746Y1116408D01*
X125752Y1115999D01*
X125793Y1115918D01*
X125830Y1115889D01*
G02X126427Y1114691I-905J-1199D01*
G02X123423I-1502J0D01*
G02X123984Y1115862I1503J0D01*
G01X124020Y1115891D01*
X124059Y1115974D01*
G37*
G36*
G01X12720Y1122332D02*
X13084D01*
X13158Y1122362D01*
X13186Y1122391D01*
G02X14252Y1122835I1066J-1058D01*
G02X15239Y1122465I0J-1501D01*
G01X15267Y1122441D01*
X15334Y1122416D01*
X15670D01*
X15737Y1122441D01*
X15765Y1122465D01*
G02X16752Y1122835I987J-1131D01*
G02Y1119831I0J-1502D01*
G02X15765Y1120201I0J1501D01*
G01X15737Y1120225D01*
X15670Y1120250D01*
X15334D01*
X15267Y1120225D01*
X15239Y1120201D01*
G02X14252Y1119831I-987J1131D01*
G02X13186Y1120275I0J1502D01*
G01X13158Y1120304D01*
X13084Y1120334D01*
X12720D01*
X12646Y1120304D01*
X12618Y1120275D01*
G02X11552Y1119831I-1066J1058D01*
G02X10525Y1120237I0J1502D01*
G01X10497Y1120263D01*
X10428Y1120291D01*
X10076D01*
X10007Y1120263D01*
X9979Y1120237D01*
G02X8952Y1119831I-1027J1096D01*
G02Y1122835I0J1502D01*
G02X9979Y1122429I0J-1502D01*
G01X10007Y1122403D01*
X10076Y1122375D01*
X10428D01*
X10497Y1122403D01*
X10525Y1122429D01*
G02X11552Y1122835I1027J-1096D01*
G02X12618Y1122391I0J-1502D01*
G01X12646Y1122362D01*
X12720Y1122332D01*
G37*
G36*
G01X28398Y1122375D02*
X28750D01*
X28819Y1122403D01*
X28847Y1122429D01*
G02X29874Y1122835I1027J-1096D01*
G02X30940Y1122391I0J-1502D01*
G01X30968Y1122362D01*
X31042Y1122332D01*
X31406D01*
X31480Y1122362D01*
X31508Y1122391D01*
G02X32574Y1122835I1066J-1058D01*
G02Y1119831I0J-1502D01*
G02X31508Y1120275I0J1502D01*
G01X31480Y1120304D01*
X31406Y1120334D01*
X31042D01*
X30968Y1120304D01*
X30940Y1120275D01*
G02X29874Y1119831I-1066J1058D01*
G02X28847Y1120237I0J1502D01*
G01X28819Y1120263D01*
X28750Y1120291D01*
X28398D01*
X28329Y1120263D01*
X28301Y1120237D01*
G02X26247I-1027J1096D01*
G01X26219Y1120263D01*
X26150Y1120291D01*
X25798D01*
X25729Y1120263D01*
X25701Y1120237D01*
G02X24674Y1119831I-1027J1096D01*
G02Y1122835I0J1502D01*
G02X25701Y1122429I0J-1502D01*
G01X25729Y1122403D01*
X25798Y1122375D01*
X26150D01*
X26219Y1122403D01*
X26247Y1122429D01*
G02X28301I1027J-1096D01*
G01X28329Y1122403D01*
X28398Y1122375D01*
G37*
G36*
G01X124059Y1128574D02*
X124053Y1128983D01*
X124012Y1129064D01*
X123975Y1129093D01*
G02X123378Y1130291I905J1199D01*
G02X126382I1502J0D01*
G02X125821Y1129120I-1503J0D01*
G01X125785Y1129091D01*
X125746Y1129008D01*
X125752Y1128599D01*
X125793Y1128518D01*
X125830Y1128489D01*
G02X126427Y1127291I-905J-1199D01*
G02X123423I-1502J0D01*
G02X123984Y1128462I1503J0D01*
G01X124020Y1128491D01*
X124059Y1128574D01*
G37*
G36*
G01X15670Y1129250D02*
X15334D01*
X15267Y1129225D01*
X15239Y1129201D01*
G02X14252Y1128831I-987J1131D01*
G02Y1131835I0J1502D01*
G02X15239Y1131465I0J-1501D01*
G01X15267Y1131441D01*
X15334Y1131416D01*
X15670D01*
X15737Y1131441D01*
X15765Y1131465D01*
G02X16752Y1131835I987J-1131D01*
G02Y1128831I0J-1502D01*
G02X15765Y1129201I0J1501D01*
G01X15737Y1129225D01*
X15670Y1129250D01*
G37*
G36*
G01X23506Y1129334D02*
X23142D01*
X23068Y1129304D01*
X23040Y1129275D01*
G02X21974Y1128831I-1066J1058D01*
G02Y1131835I0J1502D01*
G02X23040Y1131391I0J-1502D01*
G01X23068Y1131362D01*
X23142Y1131332D01*
X23506D01*
X23580Y1131362D01*
X23608Y1131391D01*
G02X24674Y1131835I1066J-1058D01*
G02Y1128831I0J-1502D01*
G02X23608Y1129275I0J1502D01*
G01X23580Y1129304D01*
X23506Y1129334D01*
G37*
G36*
G01X49965Y1132605D02*
X49629D01*
X49562Y1132580D01*
X49534Y1132556D01*
G02X48547Y1132186I-987J1131D01*
G02Y1135190I0J1502D01*
G02X49534Y1134820I0J-1501D01*
G01X49562Y1134796D01*
X49629Y1134771D01*
X49965D01*
X50032Y1134796D01*
X50060Y1134820D01*
G02X51047Y1135190I987J-1131D01*
G02Y1132186I0J-1502D01*
G02X50060Y1132556I0J1501D01*
G01X50032Y1132580D01*
X49965Y1132605D01*
G37*
G36*
G01X56815D02*
X56479D01*
X56412Y1132580D01*
X56384Y1132556D01*
G02X55397Y1132186I-987J1131D01*
G02Y1135190I0J1502D01*
G02X56384Y1134820I0J-1501D01*
G01X56412Y1134796D01*
X56479Y1134771D01*
X56815D01*
X56882Y1134796D01*
X56910Y1134820D01*
G02X57897Y1135190I987J-1131D01*
G02Y1132186I0J-1502D01*
G02X56910Y1132556I0J1501D01*
G01X56882Y1132580D01*
X56815Y1132605D01*
G37*
G36*
G01X15724Y1137622D02*
X15388D01*
X15321Y1137597D01*
X15293Y1137573D01*
G02X14306Y1137203I-987J1131D01*
G02Y1140207I0J1502D01*
G02X15293Y1139837I0J-1501D01*
G01X15321Y1139813D01*
X15388Y1139788D01*
X15724D01*
X15791Y1139813D01*
X15819Y1139837D01*
G02X16806Y1140207I987J-1131D01*
G02Y1137203I0J-1502D01*
G02X15819Y1137573I0J1501D01*
G01X15791Y1137597D01*
X15724Y1137622D01*
G37*
G36*
G01X22627D02*
X22291D01*
X22224Y1137597D01*
X22196Y1137573D01*
G02X21209Y1137203I-987J1131D01*
G02Y1140207I0J1502D01*
G02X22196Y1139837I0J-1501D01*
G01X22224Y1139813D01*
X22291Y1139788D01*
X22627D01*
X22694Y1139813D01*
X22722Y1139837D01*
G02X23709Y1140207I987J-1131D01*
G02Y1137203I0J-1502D01*
G02X22722Y1137573I0J1501D01*
G01X22694Y1137597D01*
X22627Y1137622D01*
G37*
G36*
G01X124059Y1153774D02*
X124053Y1154183D01*
X124012Y1154264D01*
X123975Y1154293D01*
G02X123378Y1155491I905J1199D01*
G02X126382I1502J0D01*
G02X125821Y1154320I-1503J0D01*
G01X125785Y1154291D01*
X125746Y1154208D01*
X125752Y1153799D01*
X125793Y1153718D01*
X125830Y1153689D01*
G02X126427Y1152491I-905J-1199D01*
G02X123423I-1502J0D01*
G02X123984Y1153662I1503J0D01*
G01X124020Y1153691D01*
X124059Y1153774D01*
G37*
G36*
G01X92457Y1005787D02*
G02X91128Y1004985I-1329J700D01*
G02Y1007989I0J1502D01*
G02X92382Y1007314I0J-1502D01*
G03X93069Y1007348I333J221D01*
G02X94398Y1008150I1329J-700D01*
G02Y1005146I0J-1502D01*
G02X93144Y1005821I0J1502D01*
G03X92457Y1005787I-333J-221D01*
G37*
G36*
G01X159786Y1055428D02*
G02X159231Y1056594I947J1166D01*
G02X162235I1502J0D01*
G02X161596Y1055365I-1501J0D01*
G03X161574Y1054727I230J-327D01*
G02X162129Y1053561I-947J-1166D01*
G02X159125I-1502J0D01*
G02X159764Y1054790I1501J0D01*
G03X159786Y1055428I-230J327D01*
G37*
G36*
G01X164705Y1066788D02*
G02X166188Y1068053I1483J-237D01*
G02Y1065049I0J-1502D01*
G02X165304Y1065336I-1J1502D01*
G03X164674Y1065076I-235J-323D01*
G02X163191Y1063811I-1483J237D01*
G02Y1066815I0J1502D01*
G02X164075Y1066528I1J-1502D01*
G03X164705Y1066788I235J323D01*
G37*
G36*
G01X169611Y1079626D02*
G02X169389Y1079605I-224J1181D01*
G02X170591Y1080807I0J1202D01*
G02X170570Y1080584I-1202J1D01*
G03X171037Y1080117I393J-74D01*
G02X171259Y1080138I224J-1181D01*
G02X170057Y1078936I0J-1202D01*
G02X170078Y1079159I1202J-1D01*
G03X169611Y1079626I-393J74D01*
G37*
G36*
G01X173351Y1109547D02*
G02X173129Y1109526I-224J1181D01*
G02X174331Y1110728I0J1202D01*
G02X174310Y1110506I-1202J2D01*
G03X174777Y1110039I393J-74D01*
G02X174999Y1110060I224J-1181D01*
G02X173797Y1108858I0J-1202D01*
G02X173818Y1109080I1202J-2D01*
G03X173351Y1109547I-393J74D01*
G37*
G36*
G01X213099Y1110457D02*
X213090Y1110506D01*
G02X213069Y1110728I1181J224D01*
G02X215473I1202J0D01*
G02X215452Y1110506I-1202J2D01*
G01X215443Y1110457D01*
X215472Y1110364D01*
X215777Y1110059D01*
X215870Y1110030D01*
X215919Y1110039D01*
G02X216141Y1110060I224J-1181D01*
G02X214939Y1108858I0J-1202D01*
G02X214960Y1109080I1202J-2D01*
G01X214969Y1109129D01*
X214940Y1109222D01*
X214635Y1109527D01*
X214542Y1109556D01*
X214493Y1109547D01*
G02X214271Y1109526I-224J1181D01*
G02X214049Y1109547I2J1202D01*
G01X214000Y1109556D01*
X213907Y1109527D01*
X213602Y1109222D01*
X213573Y1109129D01*
X213582Y1109080D01*
G02X213603Y1108858I-1181J-224D01*
G02X212401Y1110060I-1202J0D01*
G02X212623Y1110039I-2J-1202D01*
G01X212672Y1110030D01*
X212765Y1110059D01*
X213070Y1110364D01*
X213099Y1110457D01*
G37*
G36*
G01X183178Y1114197D02*
X183169Y1114246D01*
G02X183148Y1114468I1181J224D01*
G02X184350Y1113266I1202J0D01*
G02X184128Y1113287I2J1202D01*
G01X184079Y1113296D01*
X183986Y1113267D01*
X183681Y1112962D01*
X183652Y1112869D01*
X183661Y1112820D01*
G02X183682Y1112598I-1181J-224D01*
G02X181278I-1202J0D01*
G02X181299Y1112820I1202J-2D01*
G01X181308Y1112869D01*
X181279Y1112962D01*
X180974Y1113267D01*
X180881Y1113296D01*
X180832Y1113287D01*
G02X180610Y1113266I-224J1181D01*
G02X180388Y1113287I2J1202D01*
G01X180339Y1113296D01*
X180246Y1113267D01*
X179941Y1112962D01*
X179912Y1112869D01*
X179921Y1112820D01*
G02X179942Y1112598I-1181J-224D01*
G02X177538I-1202J0D01*
G02X177559Y1112820I1202J-2D01*
G01X177568Y1112869D01*
X177539Y1112962D01*
X177234Y1113267D01*
X177141Y1113296D01*
X177092Y1113287D01*
G02X176870Y1113266I-224J1181D01*
G02X178072Y1114468I0J1202D01*
G02X178051Y1114246I-1202J2D01*
G01X178042Y1114197D01*
X178071Y1114104D01*
X178376Y1113799D01*
X178469Y1113770D01*
X178518Y1113779D01*
G02X178740Y1113800I224J-1181D01*
G02X178962Y1113779I-2J-1202D01*
G01X179011Y1113770D01*
X179104Y1113799D01*
X179409Y1114104D01*
X179438Y1114197D01*
X179429Y1114246D01*
G02X179408Y1114468I1181J224D01*
G02X181812I1202J0D01*
G02X181791Y1114246I-1202J2D01*
G01X181782Y1114197D01*
X181811Y1114104D01*
X182116Y1113799D01*
X182209Y1113770D01*
X182258Y1113779D01*
G02X182480Y1113800I224J-1181D01*
G02X182702Y1113779I-2J-1202D01*
G01X182751Y1113770D01*
X182844Y1113799D01*
X183149Y1114104D01*
X183178Y1114197D01*
G37*
G36*
G01X123812Y1141649D02*
G02X122972Y1142997I662J1348D01*
G02X125976I1502J0D01*
G02X125492Y1141893I-1501J0D01*
G03X125587Y1141239I271J-295D01*
G02X126427Y1139891I-662J-1348D01*
G02X123423I-1502J0D01*
G02X123907Y1140995I1501J0D01*
G03X123812Y1141649I-271J295D01*
G37*
G36*
G01X98137Y186629D02*
G02X101141I1502J0D01*
G02X100138Y185212I-1502J0D01*
G01X100137D01*
G03X100015Y185090I67J-189D01*
G01X99912Y184796D01*
G03X99929Y184625I188J-68D01*
G01X99930Y184624D01*
G02X100155Y183834I-1277J-791D01*
G02X97151I-1502J0D01*
G02X98154Y185251I1502J0D01*
G01X98155D01*
G03X98277Y185373I-67J189D01*
G01X98380Y185667D01*
G03X98363Y185838I-188J68D01*
G01X98362Y185839D01*
G02X98137Y186629I1277J791D01*
G37*
G36*
G01X91100Y143321D02*
G02X90835Y144172I1237J852D01*
G02X93839I1502J0D01*
G02X92696Y142713I-1503J0D01*
G03X92461Y142098I95J-389D01*
G02X92726Y141247I-1237J-852D01*
G02X89722I-1502J0D01*
G02X90865Y142706I1503J0D01*
G03X91100Y143321I-95J389D01*
G37*
G36*
G01X75768Y223294D02*
Y223630D01*
X75743Y223697D01*
X75719Y223725D01*
G02X75349Y224712I1131J987D01*
G02X78353I1502J0D01*
G02X77983Y223725I-1501J0D01*
G01X77959Y223697D01*
X77934Y223630D01*
Y223294D01*
X77959Y223227D01*
X77983Y223199D01*
G02X78353Y222212I-1131J-987D01*
G02X75349I-1502J0D01*
G02X75719Y223199I1501J0D01*
G01X75743Y223227D01*
X75768Y223294D01*
G37*
G36*
G01X70443Y225189D02*
X70149D01*
G03X70002Y225124I1J-200D01*
G02X68896Y224639I-1105J1017D01*
G02Y227643I0J1502D01*
G02X70002Y227158I1J-1502D01*
G03X70149Y227093I148J135D01*
G01X70443D01*
G03X70590Y227158I-1J200D01*
G02X71696Y227643I1105J-1017D01*
G02Y224639I0J-1502D01*
G02X70590Y225124I-1J1502D01*
G03X70443Y225189I-148J-135D01*
G37*
G36*
G01X53650Y229808D02*
Y230144D01*
X53625Y230211D01*
X53601Y230239D01*
G02X53231Y231226I1131J987D01*
G02X56235I1502J0D01*
G02X55865Y230239I-1501J0D01*
G01X55841Y230211D01*
X55816Y230144D01*
Y229808D01*
X55841Y229741D01*
X55865Y229713D01*
G02Y227739I-1131J-987D01*
G01X55841Y227711D01*
X55816Y227644D01*
Y227308D01*
X55841Y227241D01*
X55865Y227213D01*
G02Y225239I-1131J-987D01*
G01X55841Y225211D01*
X55816Y225144D01*
Y224808D01*
X55841Y224741D01*
X55865Y224713D01*
G02X56235Y223726I-1131J-987D01*
G02X53231I-1502J0D01*
G02X53601Y224713I1501J0D01*
G01X53625Y224741D01*
X53650Y224808D01*
Y225144D01*
X53625Y225211D01*
X53601Y225239D01*
G02Y227213I1131J987D01*
G01X53625Y227241D01*
X53650Y227308D01*
Y227644D01*
X53625Y227711D01*
X53601Y227739D01*
G02Y229713I1131J987D01*
G01X53625Y229741D01*
X53650Y229808D01*
G37*
G36*
G01X64106Y230043D02*
Y230379D01*
X64081Y230446D01*
X64057Y230474D01*
G02X63687Y231461I1131J987D01*
G02X66691I1502J0D01*
G02X66321Y230474I-1501J0D01*
G01X66297Y230446D01*
X66272Y230379D01*
Y230043D01*
X66297Y229976D01*
X66321Y229948D01*
G02Y227974I-1131J-987D01*
G01X66297Y227946D01*
X66272Y227879D01*
Y227543D01*
X66297Y227476D01*
X66321Y227448D01*
G02X66691Y226461I-1131J-987D01*
G02X66206Y225355I-1502J-1D01*
G03X66141Y225208I135J-148D01*
G01Y224914D01*
G03X66206Y224767I200J1D01*
G02X66691Y223661I-1017J-1105D01*
G02X63687I-1502J0D01*
G02X64172Y224767I1502J1D01*
G03X64237Y224914I-135J148D01*
G01Y225208D01*
G03X64172Y225355I-200J-1D01*
G02X63687Y226461I1017J1105D01*
G02X64057Y227448I1501J0D01*
G01X64081Y227476D01*
X64106Y227543D01*
Y227879D01*
X64081Y227946D01*
X64057Y227974D01*
G02Y229948I1131J987D01*
G01X64081Y229976D01*
X64106Y230043D01*
G37*
G36*
G01X72075Y230368D02*
Y230704D01*
X72050Y230771D01*
X72026Y230799D01*
G02X71656Y231786I1131J987D01*
G02X74660I1502J0D01*
G02X74290Y230799I-1501J0D01*
G01X74266Y230771D01*
X74241Y230704D01*
Y230368D01*
X74266Y230301D01*
X74290Y230273D01*
G02X74660Y229286I-1131J-987D01*
G02X71656I-1502J0D01*
G02X72026Y230273I1501J0D01*
G01X72050Y230301D01*
X72075Y230368D01*
G37*
G36*
G01X70221Y237694D02*
X70557D01*
X70624Y237719D01*
X70652Y237743D01*
G02X72626I987J-1131D01*
G01X72654Y237719D01*
X72721Y237694D01*
X73057D01*
X73124Y237719D01*
X73152Y237743D01*
G02X74139Y238113I987J-1131D01*
G02Y235109I0J-1502D01*
G02X73152Y235479I0J1501D01*
G01X73124Y235503D01*
X73057Y235528D01*
X72721D01*
X72654Y235503D01*
X72626Y235479D01*
G02X70652I-987J1131D01*
G01X70624Y235503D01*
X70557Y235528D01*
X70221D01*
X70154Y235503D01*
X70126Y235479D01*
G02X69139Y235109I-987J1131D01*
G02Y238113I0J1502D01*
G02X70126Y237743I0J-1501D01*
G01X70154Y237719D01*
X70221Y237694D01*
G37*
G36*
G01X69923Y249974D02*
X70259D01*
X70326Y249999D01*
X70354Y250023D01*
G02X72328I987J-1131D01*
G01X72356Y249999D01*
X72423Y249974D01*
X72759D01*
X72826Y249999D01*
X72854Y250023D01*
G02X73841Y250393I987J-1131D01*
G02Y247389I0J-1502D01*
G02X72854Y247759I0J1501D01*
G01X72826Y247783D01*
X72759Y247808D01*
X72423D01*
X72356Y247783D01*
X72328Y247759D01*
G02X70354I-987J1131D01*
G01X70326Y247783D01*
X70259Y247808D01*
X69923D01*
X69856Y247783D01*
X69828Y247759D01*
G02X68841Y247389I-987J1131D01*
G02Y250393I0J1502D01*
G02X69828Y250023I0J-1501D01*
G01X69856Y249999D01*
X69923Y249974D01*
G37*
G36*
G01X74218Y190705D02*
G02X73570Y191941I855J1236D01*
G02X76574I1502J0D01*
G02X75821Y190639I-1502J0D01*
G03X75793Y189963I199J-347D01*
G02X76441Y188727I-855J-1236D01*
G02X73437I-1502J0D01*
G02X74190Y190029I1502J0D01*
G03X74218Y190705I-199J347D01*
G37*
G36*
G01X122390Y236121D02*
G02X125394I1502J0D01*
G02X124744Y234884I-1502J0D01*
G03X124750Y234222I227J-329D01*
G02X125420Y232971I-833J-1251D01*
G02X122416I-1502J0D01*
G02X123066Y234208I1502J0D01*
G03X123060Y234870I-227J329D01*
G02X122390Y236121I833J1251D01*
G37*
G36*
G01X123065Y220458D02*
X123066Y220457D01*
G02Y218483I-1131J-987D01*
G01Y218482D01*
X123065D01*
G03X123017Y218352I152J-130D01*
G01Y218088D01*
G03X123065Y217958I200J0D01*
G01X123066Y217957D01*
G02X123436Y216970I-1131J-987D01*
G02X121934Y215468I-1502J0D01*
G02X121079Y215735I0J1502D01*
G01X121045Y215758D01*
X120964Y215775D01*
X120597Y215695D01*
X120530Y215647D01*
X120509Y215612D01*
G02X119221Y214883I-1288J773D01*
G02Y217887I0J1502D01*
G02X120076Y217620I0J-1502D01*
G01X120110Y217597D01*
X120191Y217580D01*
X120558Y217660D01*
X120625Y217708D01*
X120646Y217743D01*
G02X120802Y217956I1285J-777D01*
G03X120803Y217958I-173J88D01*
G03X120851Y218088I-152J130D01*
G01Y218352D01*
G03X120803Y218482I-200J0D01*
G01X120802Y218483D01*
G02Y220457I1131J987D01*
G01Y220458D01*
X120803D01*
G03X120851Y220588I-152J130D01*
G01Y220852D01*
G03X120803Y220982I-200J0D01*
G01X120802Y220983D01*
G02X120432Y221970I1131J987D01*
G02X123436I1502J0D01*
G02X123066Y220983I-1501J0D01*
G01Y220982D01*
X123065D01*
G03X123017Y220852I152J-130D01*
G01Y220588D01*
G03X123065Y220458I200J0D01*
G37*
G36*
G01X188820Y74638D02*
G02Y77642I0J1502D01*
G01X188821D01*
G02X189741Y77327I0J-1502D01*
G03X189896Y77287I123J157D01*
G01X190184Y77334D01*
G03X190318Y77420I-32J197D01*
G01X190319Y77421D01*
G02X191568Y78089I1249J-834D01*
G02Y75085I0J-1502D01*
G01X191567D01*
G02X190647Y75400I0J1502D01*
G03X190492Y75440I-123J-157D01*
G01X190204Y75393D01*
G03X190070Y75307I32J-197D01*
G01X190069Y75306D01*
G02X188820Y74638I-1249J834D01*
G37*
G36*
G01X165645Y85193D02*
G02X168649I1502J0D01*
G02X168243Y84166I-1502J0D01*
G01X168217Y84139D01*
X168189Y84068D01*
Y83718D01*
X168217Y83647D01*
X168243Y83620D01*
G02Y81566I-1096J-1027D01*
G01X168217Y81539D01*
X168189Y81468D01*
Y81118D01*
X168217Y81047D01*
X168243Y81020D01*
G02Y78966I-1096J-1027D01*
G01X168217Y78939D01*
X168189Y78868D01*
Y78518D01*
X168217Y78447D01*
X168243Y78420D01*
G02Y76366I-1096J-1027D01*
G01X168217Y76339D01*
X168189Y76268D01*
Y75918D01*
X168217Y75847D01*
X168243Y75820D01*
G02X168649Y74793I-1096J-1027D01*
G02X165645I-1502J0D01*
G02X166051Y75820I1502J0D01*
G01X166077Y75847D01*
X166105Y75918D01*
Y76268D01*
X166077Y76339D01*
X166051Y76366D01*
G02Y78420I1096J1027D01*
G01X166077Y78447D01*
X166105Y78518D01*
Y78868D01*
X166077Y78939D01*
X166051Y78966D01*
G02Y81020I1096J1027D01*
G01X166077Y81047D01*
X166105Y81118D01*
Y81468D01*
X166077Y81539D01*
X166051Y81566D01*
G02Y83620I1096J1027D01*
G01X166077Y83647D01*
X166105Y83718D01*
Y84068D01*
X166077Y84139D01*
X166051Y84166D01*
G02X165645Y85193I1096J1027D01*
G37*
G36*
G01X147310Y85584D02*
G02X150314I1502J0D01*
G02X149908Y84557I-1502J0D01*
G01X149882Y84530D01*
X149854Y84459D01*
Y84109D01*
X149882Y84038D01*
X149908Y84011D01*
G02Y81957I-1096J-1027D01*
G01X149882Y81930D01*
X149854Y81859D01*
Y81509D01*
X149882Y81438D01*
X149908Y81411D01*
G02Y79357I-1096J-1027D01*
G01X149882Y79330D01*
X149854Y79259D01*
Y78909D01*
X149882Y78838D01*
X149908Y78811D01*
G02Y76757I-1096J-1027D01*
G01X149882Y76730D01*
X149854Y76659D01*
Y76309D01*
X149882Y76238D01*
X149908Y76211D01*
G02X150314Y75184I-1096J-1027D01*
G02X147310I-1502J0D01*
G02X147716Y76211I1502J0D01*
G01X147742Y76238D01*
X147770Y76309D01*
Y76659D01*
X147742Y76730D01*
X147716Y76757D01*
G02Y78811I1096J1027D01*
G01X147742Y78838D01*
X147770Y78909D01*
Y79259D01*
X147742Y79330D01*
X147716Y79357D01*
G02Y81411I1096J1027D01*
G01X147742Y81438D01*
X147770Y81509D01*
Y81859D01*
X147742Y81930D01*
X147716Y81957D01*
G02Y84011I1096J1027D01*
G01X147742Y84038D01*
X147770Y84109D01*
Y84459D01*
X147742Y84530D01*
X147716Y84557D01*
G02X147310Y85584I1096J1027D01*
G37*
G36*
G01X138050Y123626D02*
G02X137625Y123677I1J1802D01*
G01X137622D01*
G03X137466Y123649I-46J-195D01*
G01X137185Y123462D01*
X137140Y123392D01*
X137134Y123350D01*
G02X135650Y122081I-1484J233D01*
G01X135649D01*
G02X134662Y122451I0J1502D01*
G01X134635Y122475D01*
X134567Y122501D01*
X134231D01*
X134164Y122476D01*
X134137Y122452D01*
G02X133150Y122082I-987J1131D01*
G02X132882Y122106I-1J1502D01*
G03X132716Y122060I-35J-197D01*
G01X132620Y121977D01*
G03X132550Y121817I130J-152D01*
G02X132552Y121743I-1800J-86D01*
G01Y118342D01*
G02X132550Y118263I-1802J6D01*
G03X132619Y118104I200J-8D01*
G01X132716Y118020D01*
G03X132883Y117975I130J152D01*
G02X133150Y117999I267J-1478D01*
G02X134137Y117629I0J-1501D01*
G01X134138D01*
Y117628D01*
G03X134268Y117580I130J152D01*
G01X134532D01*
G03X134662Y117628I0J200D01*
G01X134663Y117629D01*
G02X135650Y117999I987J-1131D01*
G02X137133Y116732I0J-1501D01*
G01X137140Y116690D01*
X137184Y116621D01*
X137500Y116411D01*
X137583Y116396D01*
X137623Y116406D01*
G02X138050Y116458I430J-1751D01*
G02X138398Y116424I0J-1803D01*
G01X138438Y116416D01*
X138517Y116432D01*
X138820Y116642D01*
X138862Y116708D01*
X138869Y116749D01*
G02X140350Y117998I1481J-254D01*
G02Y114994I0J-1502D01*
G01X140347D01*
G02X140169Y115005I3J1502D01*
G03X140011Y114954I-23J-199D01*
G01X139917Y114869D01*
G03X139851Y114715I134J-149D01*
G02X139852Y114655I-1801J-60D01*
G01Y111255D01*
G02X139851Y111192I-1802J-3D01*
G03X139916Y111038I200J-6D01*
G01X140011Y110952D01*
G03X140169Y110901I135J148D01*
G02X140347Y110912I181J-1491D01*
G01X140350D01*
G02Y107908I0J-1502D01*
G02X138869Y109160I0J1502D01*
G03X138785Y109292I-197J-33D01*
G01X138516Y109478D01*
X138437Y109494D01*
X138397Y109486D01*
G02X138050Y109452I-348J1769D01*
G02X137625Y109504I5J1802D01*
G01X137622D01*
G03X137466Y109476I-46J-195D01*
G01X137185Y109289D01*
X137140Y109219D01*
X137134Y109177D01*
G02X135650Y107908I-1484J233D01*
G02Y110912I0J1502D01*
G02X135917Y110888I0J-1502D01*
G03X136084Y110933I37J197D01*
G01X136181Y111017D01*
G03X136250Y111176I-131J151D01*
G02X136248Y111255I1800J85D01*
G01Y114656D01*
G02X136250Y114730I1802J-12D01*
G03X136180Y114890I-200J8D01*
G01X136084Y114973D01*
G03X135918Y115019I-131J-151D01*
G02X135650Y114995I-267J1478D01*
G02X134663Y115365I0J1501D01*
G01X134662D01*
Y115366D01*
G03X134532Y115414I-130J-152D01*
G01X134268D01*
G03X134138Y115366I0J-200D01*
G01X134137Y115365D01*
G02X133150Y114995I-987J1131D01*
G02X131666Y116264I0J1502D01*
G01X131660Y116306D01*
X131615Y116376D01*
X131334Y116563D01*
G03X131178Y116591I-110J-167D01*
G01X131176D01*
G02X130750Y116540I-426J1751D01*
G02X130325Y116591I1J1802D01*
G01X130322D01*
G03X130166Y116563I-46J-195D01*
G01X129885Y116376D01*
X129840Y116306D01*
X129834Y116264D01*
G02X128350Y114995I-1484J233D01*
G02Y117999I0J1502D01*
G02X128617Y117975I0J-1502D01*
G03X128784Y118020I37J197D01*
G01X128881Y118104D01*
G03X128950Y118263I-131J151D01*
G02X128948Y118342I1800J85D01*
G01Y121743D01*
G02X128950Y121817I1802J-12D01*
G03X128880Y121977I-200J8D01*
G01X128784Y122060D01*
G03X128618Y122106I-131J-151D01*
G02X128350Y122082I-267J1478D01*
G02Y125086I0J1502D01*
G02X129833Y123819I0J-1501D01*
G01X129840Y123777D01*
X129884Y123708D01*
X130200Y123498D01*
X130283Y123483D01*
X130323Y123493D01*
G02X130750Y123544I426J-1751D01*
G02X131177Y123493I1J-1802D01*
G01X131217Y123483D01*
X131300Y123498D01*
X131581Y123685D01*
G03X131667Y123819I-111J166D01*
G02X133150Y125086I1483J-234D01*
G01X133151D01*
G02X134138Y124716I0J-1502D01*
G01X134165Y124692D01*
X134233Y124666D01*
X134569D01*
X134636Y124691D01*
X134663Y124715D01*
G02X135650Y125085I987J-1131D01*
G02X135917Y125061I0J-1502D01*
G03X136084Y125106I37J197D01*
G01X136181Y125190D01*
G03X136250Y125349I-131J151D01*
G02X136248Y125428I1800J85D01*
G01Y128829D01*
G02X136250Y128903I1802J-12D01*
G03X136180Y129063I-200J8D01*
G01X136084Y129146D01*
G03X135918Y129192I-131J-151D01*
G02X135650Y129168I-267J1478D01*
G02X134663Y129538I0J1501D01*
G01X134662D01*
Y129539D01*
G03X134532Y129587I-130J-152D01*
G01X134268D01*
G03X134138Y129539I0J-200D01*
G01X134137Y129538D01*
G02X133150Y129168I-987J1131D01*
G02X131666Y130437I0J1502D01*
G01X131660Y130479D01*
X131615Y130549D01*
X131334Y130736D01*
G03X131178Y130764I-110J-167D01*
G01X131176D01*
G02X130750Y130712I-430J1751D01*
G02X130325Y130764I5J1802D01*
G01X130322D01*
G03X130166Y130736I-46J-195D01*
G01X129885Y130549D01*
X129840Y130479D01*
X129834Y130437D01*
G02X128350Y129168I-1484J233D01*
G02Y132172I0J1502D01*
G02X128617Y132148I0J-1502D01*
G03X128784Y132193I37J197D01*
G01X128881Y132277D01*
G03X128950Y132436I-131J151D01*
G02X128948Y132515I1800J85D01*
G01Y135916D01*
G02X128950Y135990I1802J-12D01*
G03X128880Y136150I-200J8D01*
G01X128784Y136233D01*
G03X128618Y136279I-131J-151D01*
G02X128350Y136255I-267J1478D01*
G02Y139259I0J1502D01*
G02X129833Y137992I0J-1501D01*
G01X129840Y137950D01*
X129884Y137881D01*
X130200Y137671D01*
X130283Y137656D01*
X130323Y137666D01*
G02X130750Y137718I430J-1751D01*
G02X131177Y137666I-3J-1803D01*
G01X131217Y137656D01*
X131300Y137671D01*
X131581Y137858D01*
G03X131667Y137992I-111J166D01*
G02X133150Y139259I1483J-234D01*
G02Y136255I0J-1502D01*
G02X132882Y136279I-1J1502D01*
G03X132716Y136233I-35J-197D01*
G01X132620Y136150D01*
G03X132550Y135990I130J-152D01*
G02X132552Y135916I-1800J-86D01*
G01Y132515D01*
G02X132550Y132436I-1802J6D01*
G03X132619Y132277I200J-8D01*
G01X132716Y132193D01*
G03X132883Y132148I130J152D01*
G02X133150Y132172I267J-1478D01*
G02X134137Y131802I0J-1501D01*
G01X134138D01*
Y131801D01*
G03X134268Y131753I130J152D01*
G01X134532D01*
G03X134662Y131801I0J200D01*
G01X134663Y131802D01*
G02X135650Y132172I987J-1131D01*
G02X137133Y130905I0J-1501D01*
G01X137140Y130863D01*
X137184Y130794D01*
X137500Y130584D01*
X137583Y130569D01*
X137623Y130579D01*
G02X138050Y130630I426J-1751D01*
G02X138398Y130597I5J-1802D01*
G01X138438Y130589D01*
X138517Y130605D01*
X138820Y130815D01*
X138862Y130881D01*
X138869Y130922D01*
G02X140350Y132172I1481J-252D01*
G02Y129168I0J-1502D01*
G01X140347D01*
G02X140169Y129179I3J1502D01*
G03X140011Y129128I-23J-199D01*
G01X139917Y129043D01*
G03X139851Y128889I134J-149D01*
G02X139852Y128828I-1801J-60D01*
G01Y125428D01*
G02X139851Y125365I-1802J-3D01*
G03X139916Y125211I200J-6D01*
G01X140011Y125125D01*
G03X140169Y125074I135J148D01*
G02X140347Y125085I181J-1491D01*
G01X140350D01*
G02Y122081I0J-1502D01*
G02X138869Y123333I0J1502D01*
G03X138785Y123465I-197J-33D01*
G01X138516Y123651D01*
X138437Y123667D01*
X138397Y123659D01*
G02X138050Y123626I-343J1769D01*
G37*
G36*
G01X117882Y196678D02*
G02X118988Y196193I0J-1504D01*
G03X119135Y196128I148J135D01*
G01X119429D01*
G03X119576Y196193I-1J200D01*
G02X120682Y196678I1106J-1019D01*
G02Y193674I0J-1502D01*
G02X119576Y194159I0J1504D01*
G03X119429Y194224I-148J-135D01*
G01X119135D01*
G03X118988Y194159I1J-200D01*
G02X117882Y193674I-1106J1019D01*
G02X116895Y194044I0J1501D01*
G01X116894D01*
Y194045D01*
G03X116764Y194093I-130J-152D01*
G01X116500D01*
G03X116370Y194045I0J-200D01*
G01X116369Y194044D01*
G02X114395I-987J1131D01*
G01X114394D01*
Y194045D01*
G03X114264Y194093I-130J-152D01*
G01X114000D01*
G03X113870Y194045I0J-200D01*
G01X113869Y194044D01*
G02X112882Y193674I-987J1131D01*
G02Y196678I0J1502D01*
G02X113869Y196308I0J-1501D01*
G01X113870D01*
Y196307D01*
G03X114000Y196259I130J152D01*
G01X114264D01*
G03X114394Y196307I0J200D01*
G01X114395Y196308D01*
G02X116369I987J-1131D01*
G01X116370D01*
Y196307D01*
G03X116500Y196259I130J152D01*
G01X116764D01*
G03X116894Y196307I0J200D01*
G01X116895Y196308D01*
G02X117882Y196678I987J-1131D01*
G37*
G36*
G01X112742Y201891D02*
G02Y204895I0J1502D01*
G02X113729Y204525I0J-1501D01*
G01X113730D01*
Y204524D01*
G03X113860Y204476I130J152D01*
G01X114124D01*
G03X114254Y204524I0J200D01*
G01X114255Y204525D01*
G02X115242Y204895I987J-1131D01*
G02X116739Y203517I0J-1502D01*
G01X116742Y203474D01*
X116783Y203400D01*
X117055Y203194D01*
G03X117214Y203157I121J159D01*
G02X117501Y203185I289J-1474D01*
G02X119003Y201683I0J-1502D01*
G02X118518Y200577I-1504J0D01*
G03X118453Y200430I135J-148D01*
G01Y200136D01*
G03X118518Y199989I200J1D01*
G02X119003Y198883I-1019J-1106D01*
G02X115999I-1502J0D01*
G02X116484Y199989I1504J0D01*
G03X116549Y200136I-135J148D01*
G01Y200430D01*
G03X116484Y200577I-200J-1D01*
G02X116004Y201559I1017J1105D01*
G01X116001Y201602D01*
X115960Y201676D01*
X115688Y201882D01*
G03X115529Y201919I-121J-159D01*
G02X115242Y201891I-289J1474D01*
G02X114255Y202261I0J1501D01*
G01X114254D01*
Y202262D01*
G03X114124Y202310I-130J-152D01*
G01X113860D01*
G03X113730Y202262I0J-200D01*
G01X113729Y202261D01*
G02X112742Y201891I-987J1131D01*
G37*
G36*
G01X118930Y205336D02*
G02Y208340I0J1502D01*
G02X119917Y207970I0J-1501D01*
G01X119918D01*
Y207969D01*
G03X120048Y207921I130J152D01*
G01X120312D01*
G03X120442Y207969I0J200D01*
G01X120443Y207970D01*
G02X121430Y208340I987J-1131D01*
G02Y205336I0J-1502D01*
G02X120443Y205706I0J1501D01*
G01X120442D01*
Y205707D01*
G03X120312Y205755I-130J-152D01*
G01X120048D01*
G03X119918Y205707I0J-200D01*
G01X119917Y205706D01*
G02X118930Y205336I-987J1131D01*
G37*
G36*
G01X114168Y217133D02*
X113874D01*
G03X113727Y217068I1J-200D01*
G02X112621Y216583I-1106J1019D01*
G02Y219587I0J1502D01*
G02X113727Y219102I0J-1504D01*
G03X113874Y219037I148J135D01*
G01X114168D01*
G03X114315Y219102I-1J200D01*
G02X115421Y219587I1106J-1019D01*
G02Y216583I0J-1502D01*
G02X114315Y217068I0J1504D01*
G03X114168Y217133I-148J-135D01*
G37*
G36*
G01X202759Y90701D02*
G02X202089Y91951I831J1250D01*
G02X205093I1502J0D01*
G02X204443Y90714I-1502J0D01*
G03X204448Y90051I227J-330D01*
G02X205118Y88801I-831J-1250D01*
G02X202114I-1502J0D01*
G02X202764Y90038I1502J0D01*
G03X202759Y90701I-227J330D01*
G37*
G36*
G01X151920Y91453D02*
G02X151366Y91347I-554J1395D01*
G02X152868Y92849I0J1502D01*
G02X152822Y92481I-1502J1D01*
G03X153358Y92011I388J-98D01*
G02X153912Y92117I554J-1395D01*
G02X152410Y90615I0J-1502D01*
G02X152456Y90983I1502J-1D01*
G03X151920Y91453I-388J98D01*
G37*
G36*
G01X157407Y101849D02*
G02X156824Y103037I919J1188D01*
G02X159828I1502J0D01*
G02X159172Y101796I-1502J0D01*
G03X159152Y101149I225J-331D01*
G02X159735Y99961I-919J-1188D01*
G02X156731I-1502J0D01*
G02X157387Y101202I1502J0D01*
G03X157407Y101849I-225J331D01*
G37*
G36*
G01X192979Y102731D02*
G02X192687Y103621I1210J890D01*
G02X195691I1502J0D01*
G02X194466Y102145I-1502J0D01*
G03X194217Y101515I73J-393D01*
G02X194509Y100625I-1210J-890D01*
G02X191505I-1502J0D01*
G02X192730Y102101I1502J0D01*
G03X192979Y102731I-73J393D01*
G37*
G36*
G01X136067Y106561D02*
G02X139071I1502J0D01*
G02X138345Y105275I-1502J0D01*
G03X138249Y105114I104J-171D01*
G01X138231Y104782D01*
G03X138311Y104612I200J-10D01*
G02X138866Y103779I-901J-1202D01*
G03X138991Y103641I194J50D01*
G01X139300Y103526D01*
G03X139484Y103550I69J188D01*
G02X140350Y103825I866J-1226D01*
G02Y100821I0J-1502D01*
G02X138894Y101955I0J1502D01*
G03X138769Y102093I-194J-50D01*
G01X138460Y102208D01*
G03X138276Y102184I-69J-188D01*
G02X137410Y101909I-866J1226D01*
G02X135908Y103411I0J1502D01*
G02X136634Y104697I1502J0D01*
G03X136730Y104858I-104J171D01*
G01X136748Y105190D01*
G03X136668Y105360I-200J10D01*
G02X136067Y106561I901J1202D01*
G37*
G36*
G01X123942Y110018D02*
X124256D01*
G03X124414Y110095I0J200D01*
G02X125599Y110674I1185J-923D01*
G02X127101Y109172I0J-1502D01*
G02X126138Y107770I-1502J0D01*
G01X126136D01*
X126096Y107754D01*
X126037Y107694D01*
X125902Y107330D01*
X125908Y107245D01*
X125929Y107207D01*
G02X126108Y106497I-1323J-711D01*
G01Y106495D01*
G02X123104I-1502J0D01*
G02X123242Y107123I1502J-1D01*
G01Y107124D01*
G03X123221Y107327I-182J84D01*
G01X122976Y107653D01*
X122875Y107694D01*
X122820Y107686D01*
G02X122599Y107670I-219J1486D01*
G02Y110674I0J1502D01*
G02X123784Y110095I0J-1502D01*
G03X123942Y110018I158J123D01*
G37*
G36*
G01X123879Y148717D02*
G02X126883I1502J0D01*
G02X125878Y147300I-1501J0D01*
G03X125758Y147183I67J-188D01*
G01X125632Y146857D01*
X125638Y146770D01*
X125659Y146731D01*
G02X125842Y146013I-1319J-719D01*
G01Y146012D01*
G02X125182Y144768I-1502J0D01*
G03X125094Y144603I112J-166D01*
G01Y144271D01*
G03X125182Y144106I200J1D01*
G02X125827Y143074I-842J-1244D01*
G01Y143073D01*
G03X125895Y142950I198J29D01*
G01X126095Y142778D01*
G03X126228Y142730I130J152D01*
G01X126246D01*
G02Y139726I0J-1502D01*
G02X124759Y141016I0J1502D01*
G01Y141017D01*
G03X124691Y141140I-198J-29D01*
G01X124491Y141312D01*
G03X124358Y141360I-130J-152D01*
G01X124340D01*
G02X122838Y142862I0J1502D01*
G02X123498Y144106I1502J0D01*
G03X123586Y144271I-112J166D01*
G01Y144603D01*
G03X123498Y144768I-200J-1D01*
G02X122838Y146012I842J1244D01*
G02X123843Y147429I1501J0D01*
G03X123963Y147546I-67J188D01*
G01X124089Y147872D01*
X124083Y147959D01*
X124062Y147998D01*
G02X123879Y148716I1319J719D01*
G01Y148717D01*
G37*
G36*
G01X178130Y223294D02*
Y223630D01*
X178105Y223697D01*
X178081Y223725D01*
G02X177711Y224712I1131J987D01*
G02X180715I1502J0D01*
G02X180345Y223725I-1501J0D01*
G01X180321Y223697D01*
X180296Y223630D01*
Y223294D01*
X180321Y223227D01*
X180345Y223199D01*
G02X180715Y222212I-1131J-987D01*
G02X177711I-1502J0D01*
G02X178081Y223199I1501J0D01*
G01X178105Y223227D01*
X178130Y223294D01*
G37*
G36*
G01X172805Y225189D02*
X172511D01*
G03X172364Y225124I1J-200D01*
G02X171258Y224639I-1105J1017D01*
G02Y227643I0J1502D01*
G02X172364Y227158I1J-1502D01*
G03X172511Y227093I148J135D01*
G01X172805D01*
G03X172952Y227158I-1J200D01*
G02X174058Y227643I1105J-1017D01*
G02Y224639I0J-1502D01*
G02X172952Y225124I-1J1502D01*
G03X172805Y225189I-148J-135D01*
G37*
G36*
G01X156012Y229808D02*
Y230144D01*
X155987Y230211D01*
X155963Y230239D01*
G02X155593Y231226I1131J987D01*
G02X158597I1502J0D01*
G02X158227Y230239I-1501J0D01*
G01X158203Y230211D01*
X158178Y230144D01*
Y229808D01*
X158203Y229741D01*
X158227Y229713D01*
G02Y227739I-1131J-987D01*
G01X158203Y227711D01*
X158178Y227644D01*
Y227308D01*
X158203Y227241D01*
X158227Y227213D01*
G02Y225239I-1131J-987D01*
G01X158203Y225211D01*
X158178Y225144D01*
Y224808D01*
X158203Y224741D01*
X158227Y224713D01*
G02X158597Y223726I-1131J-987D01*
G02X155593I-1502J0D01*
G02X155963Y224713I1501J0D01*
G01X155987Y224741D01*
X156012Y224808D01*
Y225144D01*
X155987Y225211D01*
X155963Y225239D01*
G02Y227213I1131J987D01*
G01X155987Y227241D01*
X156012Y227308D01*
Y227644D01*
X155987Y227711D01*
X155963Y227739D01*
G02Y229713I1131J987D01*
G01X155987Y229741D01*
X156012Y229808D01*
G37*
G36*
G01X166468Y230043D02*
Y230379D01*
X166443Y230446D01*
X166419Y230474D01*
G02X166049Y231461I1131J987D01*
G02X169053I1502J0D01*
G02X168683Y230474I-1501J0D01*
G01X168659Y230446D01*
X168634Y230379D01*
Y230043D01*
X168659Y229976D01*
X168683Y229948D01*
G02Y227974I-1131J-987D01*
G01X168659Y227946D01*
X168634Y227879D01*
Y227543D01*
X168659Y227476D01*
X168683Y227448D01*
G02X169053Y226461I-1131J-987D01*
G02X168568Y225355I-1502J-1D01*
G03X168503Y225208I135J-148D01*
G01Y224914D01*
G03X168568Y224767I200J1D01*
G02X169053Y223661I-1017J-1105D01*
G02X166049I-1502J0D01*
G02X166534Y224767I1502J1D01*
G03X166599Y224914I-135J148D01*
G01Y225208D01*
G03X166534Y225355I-200J-1D01*
G02X166049Y226461I1017J1105D01*
G02X166419Y227448I1501J0D01*
G01X166443Y227476D01*
X166468Y227543D01*
Y227879D01*
X166443Y227946D01*
X166419Y227974D01*
G02Y229948I1131J987D01*
G01X166443Y229976D01*
X166468Y230043D01*
G37*
G36*
G01X174437Y230368D02*
Y230704D01*
X174412Y230771D01*
X174388Y230799D01*
G02X174018Y231786I1131J987D01*
G02X177022I1502J0D01*
G02X176652Y230799I-1501J0D01*
G01X176628Y230771D01*
X176603Y230704D01*
Y230368D01*
X176628Y230301D01*
X176652Y230273D01*
G02X177022Y229286I-1131J-987D01*
G02X174018I-1502J0D01*
G02X174388Y230273I1501J0D01*
G01X174412Y230301D01*
X174437Y230368D01*
G37*
G36*
G01X172583Y237694D02*
X172919D01*
X172986Y237719D01*
X173014Y237743D01*
G02X174988I987J-1131D01*
G01X175016Y237719D01*
X175083Y237694D01*
X175419D01*
X175486Y237719D01*
X175514Y237743D01*
G02X176501Y238113I987J-1131D01*
G02Y235109I0J-1502D01*
G02X175514Y235479I0J1501D01*
G01X175486Y235503D01*
X175419Y235528D01*
X175083D01*
X175016Y235503D01*
X174988Y235479D01*
G02X173014I-987J1131D01*
G01X172986Y235503D01*
X172919Y235528D01*
X172583D01*
X172516Y235503D01*
X172488Y235479D01*
G02X171501Y235109I-987J1131D01*
G02Y238113I0J1502D01*
G02X172488Y237743I0J-1501D01*
G01X172516Y237719D01*
X172583Y237694D01*
G37*
G36*
G01X132652Y246201D02*
X132251Y246257D01*
X132165Y246230D01*
X132132Y246199D01*
G02X131102Y245790I-1030J1092D01*
G02Y248794I0J1502D01*
G02X132396Y248055I0J-1502D01*
G01X132419Y248016D01*
X132494Y247965D01*
X132895Y247909D01*
X132981Y247936D01*
X133014Y247967D01*
G02X134044Y248376I1030J-1092D01*
G02Y245372I0J-1502D01*
G02X132750Y246111I0J1502D01*
G01X132727Y246150D01*
X132652Y246201D01*
G37*
G36*
G01X172285Y249974D02*
X172621D01*
X172688Y249999D01*
X172716Y250023D01*
G02X174690I987J-1131D01*
G01X174718Y249999D01*
X174785Y249974D01*
X175121D01*
X175188Y249999D01*
X175216Y250023D01*
G02X176203Y250393I987J-1131D01*
G02Y247389I0J-1502D01*
G02X175216Y247759I0J1501D01*
G01X175188Y247783D01*
X175121Y247808D01*
X174785D01*
X174718Y247783D01*
X174690Y247759D01*
G02X172716I-987J1131D01*
G01X172688Y247783D01*
X172621Y247808D01*
X172285D01*
X172218Y247783D01*
X172190Y247759D01*
G02X171203Y247389I-987J1131D01*
G02Y250393I0J1502D01*
G02X172190Y250023I0J-1501D01*
G01X172218Y249999D01*
X172285Y249974D01*
G37*
G36*
G01X176580Y190705D02*
G02X175932Y191941I855J1236D01*
G02X178936I1502J0D01*
G02X178183Y190639I-1502J0D01*
G03X178155Y189963I199J-347D01*
G02X178803Y188727I-855J-1236D01*
G02X175799I-1502J0D01*
G02X176552Y190029I1502J0D01*
G03X176580Y190705I-199J347D01*
G37*
G36*
G01X141703Y1171313D02*
X142095Y1171324D01*
X142171Y1171361D01*
X142200Y1171396D01*
G02X143207Y1171872I1007J-827D01*
G01X146947D01*
G02Y1169268I0J-1302D01*
G01X143207D01*
G02X142200Y1169744I0J1303D01*
G01X142172Y1169778D01*
X142095Y1169816D01*
X141704Y1169826D01*
X141625Y1169792D01*
X141595Y1169759D01*
G02X140707Y1169367I-888J810D01*
G02Y1171771I0J1202D01*
G02X141595Y1171379I0J-1202D01*
G01X141625Y1171347D01*
X141703Y1171313D01*
G37*
G36*
G01X200623Y185330D02*
X200758Y185710D01*
X200748Y185800D01*
X200724Y185839D01*
G02X200499Y186629I1277J791D01*
G02X203503I1502J0D01*
G02X202500Y185212I-1502J0D01*
G01X202456Y185197D01*
X202393Y185133D01*
X202258Y184753D01*
X202268Y184663D01*
X202292Y184624D01*
G02X202517Y183834I-1277J-791D01*
G02X199513I-1502J0D01*
G02X200516Y185251I1502J0D01*
G01X200560Y185266D01*
X200623Y185330D01*
G37*
G36*
G01X356538Y1186651D02*
X356635Y1187039D01*
X356617Y1187126D01*
X356590Y1187162D01*
G02X356294Y1188058I1206J895D01*
G02X359298I1502J0D01*
G02X358439Y1186700I-1503J0D01*
G01X358398Y1186681D01*
X358341Y1186612D01*
X358244Y1186224D01*
X358262Y1186137D01*
X358289Y1186101D01*
G02X358585Y1185205I-1206J-895D01*
G02X355581I-1502J0D01*
G02X356440Y1186563I1503J0D01*
G01X356481Y1186582D01*
X356538Y1186651D01*
G37*
G36*
G01X338582Y1195694D02*
X338224Y1195628D01*
X338159Y1195586D01*
X338136Y1195552D01*
G02X336901Y1194905I-1235J855D01*
G02Y1197909I0J1502D01*
G02X337750Y1197646I0J-1502D01*
G01X337783Y1197623D01*
X337859Y1197607D01*
X338217Y1197673D01*
X338282Y1197715D01*
X338305Y1197749D01*
G02X339540Y1198396I1235J-855D01*
G02Y1195392I0J-1502D01*
G02X338691Y1195655I0J1502D01*
G01X338658Y1195678D01*
X338582Y1195694D01*
G37*
G36*
G01X352636Y1158669D02*
G02X352536Y1158666I-95J1499D01*
G02X354038Y1160168I0J1502D01*
G02X353924Y1159594I-1502J0D01*
G03X354320Y1159043I370J-152D01*
G02X354420Y1159046I95J-1499D01*
G02X352918Y1157544I0J-1502D01*
G02X353032Y1158118I1502J0D01*
G03X352636Y1158669I-370J152D01*
G37*
G36*
G01X341689Y1188868D02*
X341708Y1188921D01*
G02X343121Y1189914I1413J-509D01*
G02Y1186910I0J-1502D01*
G02X341893Y1187548I0J1501D01*
G01X341860Y1187594D01*
X341758Y1187638D01*
X341295Y1187576D01*
X341208Y1187506D01*
X341189Y1187453D01*
G02X339776Y1186460I-1413J509D01*
G02X339582Y1186473I3J1502D01*
G01X339539Y1186478D01*
X339457Y1186453D01*
X339166Y1186197D01*
X339131Y1186119D01*
Y1186075D01*
G02X336127Y1186071I-1502J-4D01*
G02X336142Y1186280I1502J-3D01*
G01X336148Y1186327D01*
X336119Y1186415D01*
X335829Y1186708D01*
X335741Y1186738D01*
X335694Y1186732D01*
G02X335502Y1186720I-190J1490D01*
G02X337004Y1188222I0J1502D01*
G02X336989Y1188013I-1502J3D01*
G01X336983Y1187966D01*
X337012Y1187878D01*
X337302Y1187585D01*
X337390Y1187555D01*
X337437Y1187561D01*
G02X337629Y1187573I190J-1490D01*
G02X337823Y1187560I-3J-1502D01*
G01X337866Y1187555D01*
X337948Y1187580D01*
X338239Y1187836D01*
X338274Y1187914D01*
Y1187958D01*
G02X339776Y1189464I1502J4D01*
G02X341004Y1188826I0J-1501D01*
G01X341037Y1188780D01*
X341139Y1188736D01*
X341602Y1188798D01*
X341689Y1188868D01*
G37*
G36*
G01X299123Y1189000D02*
X299114Y1189049D01*
G02X299093Y1189271I1181J224D01*
G02X300295Y1188069I1202J0D01*
G02X300073Y1188090I2J1202D01*
G01X300024Y1188099D01*
X299931Y1188070D01*
X299626Y1187765D01*
X299597Y1187672D01*
X299606Y1187623D01*
G02X299627Y1187401I-1181J-224D01*
G02X299606Y1187179I-1202J2D01*
G01X299597Y1187130D01*
X299626Y1187037D01*
X299931Y1186732D01*
X300024Y1186703D01*
X300073Y1186712D01*
G02X300295Y1186733I224J-1181D01*
G02X299093Y1185531I0J-1202D01*
G02X299114Y1185753I1202J-2D01*
G01X299123Y1185802D01*
X299094Y1185895D01*
X298789Y1186200D01*
X298696Y1186229D01*
X298647Y1186220D01*
G02X298425Y1186199I-224J1181D01*
G02Y1188603I0J1202D01*
G02X298647Y1188582I-2J-1202D01*
G01X298696Y1188573D01*
X298789Y1188602D01*
X299094Y1188907D01*
X299123Y1189000D01*
G37*
G36*
G01X289772Y1190870D02*
X289763Y1190919D01*
G02X289742Y1191141I1181J224D01*
G02X292146I1202J0D01*
G02X292125Y1190919I-1202J2D01*
G01X292116Y1190870D01*
X292145Y1190777D01*
X292450Y1190472D01*
X292543Y1190443D01*
X292592Y1190452D01*
G02X292814Y1190473I224J-1181D01*
G02X291612Y1189271I0J-1202D01*
G02X291633Y1189493I1202J-2D01*
G01X291642Y1189542D01*
X291613Y1189635D01*
X291308Y1189940D01*
X291215Y1189969D01*
X291166Y1189960D01*
G02X290944Y1189939I-224J1181D01*
G02X290722Y1189960I2J1202D01*
G01X290673Y1189969D01*
X290580Y1189940D01*
X290275Y1189635D01*
X290246Y1189542D01*
X290255Y1189493D01*
G02X290276Y1189271I-1181J-224D01*
G02X289074Y1190473I-1202J0D01*
G02X289296Y1190452I-2J-1202D01*
G01X289345Y1190443D01*
X289438Y1190472D01*
X289743Y1190777D01*
X289772Y1190870D01*
G37*
G36*
G01X358469Y1191769D02*
G02X357297Y1191207I-1172J941D01*
G02Y1194211I0J1502D01*
G02X358673Y1193311I0J-1502D01*
G03X359351Y1193222I366J161D01*
G02X360523Y1193784I1172J-941D01*
G02Y1190780I0J-1502D01*
G02X359147Y1191680I0J1502D01*
G03X358469Y1191769I-366J-161D01*
G37*
G36*
G01X312213Y1198350D02*
X312204Y1198399D01*
G02X312183Y1198621I1181J224D01*
G02X313385Y1197419I1202J0D01*
G02X313163Y1197440I2J1202D01*
G01X313114Y1197449D01*
X313021Y1197420D01*
X312716Y1197115D01*
X312687Y1197022D01*
X312696Y1196973D01*
G02X312717Y1196751I-1181J-224D01*
G02X310313I-1202J0D01*
G02X310334Y1196973I1202J-2D01*
G01X310343Y1197022D01*
X310314Y1197115D01*
X310009Y1197420D01*
X309916Y1197449D01*
X309867Y1197440D01*
G02X309645Y1197419I-224J1181D01*
G02X310847Y1198621I0J1202D01*
G02X310826Y1198399I-1202J2D01*
G01X310817Y1198350D01*
X310846Y1198257D01*
X311151Y1197952D01*
X311244Y1197923D01*
X311293Y1197932D01*
G02X311515Y1197953I224J-1181D01*
G02X311737Y1197932I-2J-1202D01*
G01X311786Y1197923D01*
X311879Y1197952D01*
X312184Y1198257D01*
X312213Y1198350D01*
G37*
G36*
G01X363581Y1213755D02*
X363569Y1213807D01*
G02X363527Y1214158I1460J353D01*
G02X365029Y1212656I1502J0D01*
G02X364678Y1212698I2J1502D01*
G01X364626Y1212710D01*
X364527Y1212682D01*
X364211Y1212366D01*
X364183Y1212267D01*
X364195Y1212215D01*
G02X364237Y1211864I-1460J-353D01*
G02X362735Y1210362I-1502J0D01*
G02X362591Y1210369I1J1502D01*
G01X362546Y1210373D01*
X362462Y1210343D01*
X362180Y1210061D01*
X362150Y1209978D01*
X362154Y1209933D01*
G02X362161Y1209789I-1495J-145D01*
G02X360659Y1211291I-1502J0D01*
G02X360803Y1211284I-1J-1502D01*
G01X360848Y1211280D01*
X360932Y1211310D01*
X361214Y1211592D01*
X361244Y1211675D01*
X361240Y1211720D01*
G02X361233Y1211864I1495J145D01*
G02X362735Y1213366I1502J0D01*
G02X363086Y1213324I-2J-1502D01*
G01X363138Y1213312D01*
X363237Y1213340D01*
X363553Y1213656D01*
X363581Y1213755D01*
G37*
G36*
G01X201452Y1216150D02*
X201403Y1216141D01*
G02X201181Y1216120I-224J1181D01*
G02X202383Y1217322I0J1202D01*
G02X202362Y1217100I-1202J2D01*
G01X202353Y1217051D01*
X202382Y1216958D01*
X202687Y1216653D01*
X202780Y1216624D01*
X202829Y1216633D01*
G02X203051Y1216654I224J-1181D01*
G02X204253Y1215452I0J-1202D01*
G02X204232Y1215230I-1202J2D01*
G01X204223Y1215181D01*
X204252Y1215088D01*
X204557Y1214783D01*
X204650Y1214754D01*
X204699Y1214763D01*
G02X204921Y1214784I224J-1181D01*
G02X203719Y1213582I0J-1202D01*
G02X203740Y1213804I1202J-2D01*
G01X203749Y1213853D01*
X203720Y1213946D01*
X203415Y1214251D01*
X203322Y1214280D01*
X203273Y1214271D01*
G02X203051Y1214250I-224J1181D01*
G02X202829Y1214271I2J1202D01*
G01X202780Y1214280D01*
X202687Y1214251D01*
X202382Y1213946D01*
X202353Y1213853D01*
X202362Y1213804D01*
G02X202383Y1213582I-1181J-224D01*
G02X201181Y1214784I-1202J0D01*
G02X201403Y1214763I-2J-1202D01*
G01X201452Y1214754D01*
X201545Y1214783D01*
X201850Y1215088D01*
X201879Y1215181D01*
X201870Y1215230D01*
G02X201849Y1215452I1181J224D01*
G02X201870Y1215674I1202J-2D01*
G01X201879Y1215723D01*
X201850Y1215816D01*
X201545Y1216121D01*
X201452Y1216150D01*
G37*
G36*
G01X208932D02*
X208883Y1216141D01*
G02X208661Y1216120I-224J1181D01*
G02X209863Y1217322I0J1202D01*
G02X209842Y1217100I-1202J2D01*
G01X209833Y1217051D01*
X209862Y1216958D01*
X210167Y1216653D01*
X210260Y1216624D01*
X210309Y1216633D01*
G02X210531Y1216654I224J-1181D01*
G02Y1214250I0J-1202D01*
G02X210309Y1214271I2J1202D01*
G01X210260Y1214280D01*
X210167Y1214251D01*
X209862Y1213946D01*
X209833Y1213853D01*
X209842Y1213804D01*
G02X209863Y1213582I-1181J-224D01*
G02X209842Y1213360I-1202J2D01*
G01X209833Y1213311D01*
X209862Y1213218D01*
X210167Y1212913D01*
X210260Y1212884D01*
X210309Y1212893D01*
G02X210531Y1212914I224J-1181D01*
G02X209329Y1211712I0J-1202D01*
G02X209350Y1211934I1202J-2D01*
G01X209359Y1211983D01*
X209330Y1212076D01*
X209025Y1212381D01*
X208932Y1212410D01*
X208883Y1212401D01*
G02X208661Y1212380I-224J1181D01*
G02Y1214784I0J1202D01*
G02X208883Y1214763I-2J-1202D01*
G01X208932Y1214754D01*
X209025Y1214783D01*
X209330Y1215088D01*
X209359Y1215181D01*
X209350Y1215230D01*
G02X209329Y1215452I1181J224D01*
G02X209350Y1215674I1202J-2D01*
G01X209359Y1215723D01*
X209330Y1215816D01*
X209025Y1216121D01*
X208932Y1216150D01*
G37*
G36*
G01X218709Y1217051D02*
X218700Y1217100D01*
G02X218679Y1217322I1181J224D01*
G02X221083I1202J0D01*
G02X221062Y1217100I-1202J2D01*
G01X221053Y1217051D01*
X221082Y1216957D01*
X221386Y1216653D01*
X221481Y1216624D01*
X221529Y1216633D01*
G02X221752Y1216654I224J-1181D01*
G02X220550Y1215452I0J-1202D01*
G02X220571Y1215674I1202J-2D01*
G01X220580Y1215723D01*
X220551Y1215817D01*
X220247Y1216121D01*
X220152Y1216150D01*
X220104Y1216141D01*
G02X219881Y1216120I-224J1181D01*
G02X219659Y1216141I2J1202D01*
G01X219610Y1216150D01*
X219517Y1216121D01*
X219212Y1215816D01*
X219183Y1215723D01*
X219192Y1215674D01*
G02X219213Y1215452I-1181J-224D01*
G02X218011Y1216654I-1202J0D01*
G02X218233Y1216633I-2J-1202D01*
G01X218282Y1216624D01*
X218375Y1216653D01*
X218680Y1216958D01*
X218709Y1217051D01*
G37*
G36*
G01X241150D02*
X241141Y1217100D01*
G02X241120Y1217322I1181J224D01*
G02X243524I1202J0D01*
G02X243503Y1217100I-1202J2D01*
G01X243494Y1217051D01*
X243523Y1216958D01*
X243828Y1216653D01*
X243921Y1216624D01*
X243970Y1216633D01*
G02X244192Y1216654I224J-1181D01*
G02X242990Y1215452I0J-1202D01*
G02X243011Y1215674I1202J-2D01*
G01X243020Y1215723D01*
X242991Y1215816D01*
X242686Y1216121D01*
X242593Y1216150D01*
X242544Y1216141D01*
G02X242322Y1216120I-224J1181D01*
G02X242100Y1216141I2J1202D01*
G01X242051Y1216150D01*
X241958Y1216121D01*
X241653Y1215816D01*
X241624Y1215723D01*
X241633Y1215674D01*
G02X241654Y1215452I-1181J-224D01*
G02X239250I-1202J0D01*
G02X239271Y1215674I1202J-2D01*
G01X239280Y1215723D01*
X239251Y1215816D01*
X238946Y1216121D01*
X238853Y1216150D01*
X238804Y1216141D01*
G02X238582Y1216120I-224J1181D01*
G02X238360Y1216141I2J1202D01*
G01X238311Y1216150D01*
X238218Y1216121D01*
X237913Y1215816D01*
X237884Y1215723D01*
X237893Y1215674D01*
G02X237914Y1215452I-1181J-224D01*
G02X236712Y1216654I-1202J0D01*
G02X236934Y1216633I-2J-1202D01*
G01X236983Y1216624D01*
X237076Y1216653D01*
X237381Y1216958D01*
X237410Y1217051D01*
X237401Y1217100D01*
G02X237380Y1217322I1181J224D01*
G02X239784I1202J0D01*
G02X239763Y1217100I-1202J2D01*
G01X239754Y1217051D01*
X239783Y1216958D01*
X240088Y1216653D01*
X240181Y1216624D01*
X240230Y1216633D01*
G02X240452Y1216654I224J-1181D01*
G02X240674Y1216633I-2J-1202D01*
G01X240723Y1216624D01*
X240816Y1216653D01*
X241121Y1216958D01*
X241150Y1217051D01*
G37*
G36*
G01X360838Y1230107D02*
X360834Y1230151D01*
G02X360830Y1230265I1498J110D01*
G02X362332Y1228763I1502J0D01*
G02X362204Y1228768I-5J1502D01*
G01X362159Y1228772D01*
X362077Y1228743D01*
X361798Y1228466D01*
X361767Y1228384D01*
X361771Y1228340D01*
G02X361775Y1228226I-1498J-110D01*
G02X360273Y1226724I-1502J0D01*
G02X360005Y1226748I-1J1502D01*
G01X359956Y1226757D01*
X359863Y1226728D01*
X359560Y1226425D01*
X359531Y1226332D01*
X359540Y1226283D01*
G02X359564Y1226016I-1478J-267D01*
G02X358062Y1227518I-1502J0D01*
G02X358330Y1227494I1J-1502D01*
G01X358379Y1227485D01*
X358472Y1227514D01*
X358775Y1227817D01*
X358804Y1227910D01*
X358795Y1227959D01*
G02X358771Y1228226I1478J267D01*
G02X360273Y1229728I1502J0D01*
G02X360401Y1229723I5J-1502D01*
G01X360446Y1229719D01*
X360528Y1229748D01*
X360807Y1230025D01*
X360838Y1230107D01*
G37*
G36*
G01X226241Y148717D02*
G02X229245I1502J0D01*
G02X228240Y147300I-1501J0D01*
G03X228120Y147183I67J-188D01*
G01X227994Y146857D01*
X228000Y146770D01*
X228021Y146731D01*
G02X228204Y146013I-1319J-719D01*
G01Y146012D01*
G02X227544Y144768I-1502J0D01*
G03X227456Y144603I112J-166D01*
G01Y144271D01*
G03X227544Y144106I200J1D01*
G02X228189Y143074I-842J-1244D01*
G01Y143073D01*
G03X228257Y142950I198J29D01*
G01X228457Y142778D01*
G03X228590Y142730I130J152D01*
G01X228608D01*
G02Y139726I0J-1502D01*
G02X227121Y141016I0J1502D01*
G01Y141017D01*
G03X227053Y141140I-198J-29D01*
G01X226853Y141312D01*
G03X226720Y141360I-130J-152D01*
G01X226702D01*
G02X225200Y142862I0J1502D01*
G02X225860Y144106I1502J0D01*
G03X225948Y144271I-112J166D01*
G01Y144603D01*
G03X225860Y144768I-200J-1D01*
G02X225200Y146012I842J1244D01*
G02X226205Y147429I1501J0D01*
G03X226325Y147546I-67J188D01*
G01X226451Y147872D01*
X226445Y147959D01*
X226424Y147998D01*
G02X226241Y148716I1319J719D01*
G01Y148717D01*
G37*
G36*
G01X226304Y110018D02*
X226618D01*
G03X226776Y110095I0J200D01*
G02X227961Y110674I1185J-923D01*
G02X229463Y109172I0J-1502D01*
G02X228500Y107770I-1502J0D01*
G01X228498D01*
X228458Y107754D01*
X228399Y107694D01*
X228264Y107330D01*
X228270Y107245D01*
X228291Y107207D01*
G02X228470Y106497I-1323J-711D01*
G01Y106495D01*
G02X225466I-1502J0D01*
G02X225604Y107123I1502J-1D01*
G01Y107124D01*
G03X225583Y107327I-182J84D01*
G01X225338Y107653D01*
X225237Y107694D01*
X225182Y107686D01*
G02X224961Y107670I-219J1486D01*
G02Y110674I0J1502D01*
G02X226146Y110095I0J-1502D01*
G03X226304Y110018I158J123D01*
G37*
G36*
G01X238429Y106561D02*
G02X241433I1502J0D01*
G02X240707Y105275I-1502J0D01*
G03X240611Y105114I104J-171D01*
G01X240593Y104782D01*
G03X240673Y104612I200J-10D01*
G02X241228Y103779I-901J-1202D01*
G03X241353Y103641I194J50D01*
G01X241662Y103526D01*
G03X241846Y103550I69J188D01*
G02X242712Y103825I866J-1226D01*
G02Y100821I0J-1502D01*
G02X241256Y101955I0J1502D01*
G03X241131Y102093I-194J-50D01*
G01X240822Y102208D01*
G03X240638Y102184I-69J-188D01*
G02X239772Y101909I-866J1226D01*
G02X238270Y103411I0J1502D01*
G02X238996Y104697I1502J0D01*
G03X239092Y104858I-104J171D01*
G01X239110Y105190D01*
G03X239030Y105360I-200J10D01*
G02X238429Y106561I901J1202D01*
G37*
G36*
G01X295341Y102731D02*
G02X295049Y103621I1210J890D01*
G02X298053I1502J0D01*
G02X296828Y102145I-1502J0D01*
G03X296579Y101515I73J-393D01*
G02X296871Y100625I-1210J-890D01*
G02X293867I-1502J0D01*
G02X295092Y102101I1502J0D01*
G03X295341Y102731I-73J393D01*
G37*
G36*
G01X259769Y101849D02*
G02X259186Y103037I919J1188D01*
G02X262190I1502J0D01*
G02X261534Y101796I-1502J0D01*
G03X261514Y101149I225J-331D01*
G02X262097Y99961I-919J-1188D01*
G02X259093I-1502J0D01*
G02X259749Y101202I1502J0D01*
G03X259769Y101849I-225J331D01*
G37*
G36*
G01X254282Y91453D02*
G02X253728Y91347I-554J1395D01*
G02X255230Y92849I0J1502D01*
G02X255184Y92481I-1502J1D01*
G03X255720Y92011I388J-98D01*
G02X256274Y92117I554J-1395D01*
G02X254772Y90615I0J-1502D01*
G02X254818Y90983I1502J-1D01*
G03X254282Y91453I-388J98D01*
G37*
G36*
G01X305121Y90701D02*
G02X304451Y91951I831J1250D01*
G02X307455I1502J0D01*
G02X306805Y90714I-1502J0D01*
G03X306810Y90051I227J-330D01*
G02X307480Y88801I-831J-1250D01*
G02X304476I-1502J0D01*
G02X305126Y90038I1502J0D01*
G03X305121Y90701I-227J330D01*
G37*
G36*
G01X216530Y217133D02*
X216236D01*
G03X216089Y217068I1J-200D01*
G02X214983Y216583I-1106J1019D01*
G02Y219587I0J1502D01*
G02X216089Y219102I0J-1504D01*
G03X216236Y219037I148J135D01*
G01X216530D01*
G03X216677Y219102I-1J200D01*
G02X217783Y219587I1106J-1019D01*
G02Y216583I0J-1502D01*
G02X216677Y217068I0J1504D01*
G03X216530Y217133I-148J-135D01*
G37*
G36*
G01X221292Y205336D02*
G02Y208340I0J1502D01*
G02X222279Y207970I0J-1501D01*
G01X222280D01*
Y207969D01*
G03X222410Y207921I130J152D01*
G01X222674D01*
G03X222804Y207969I0J200D01*
G01X222805Y207970D01*
G02X223792Y208340I987J-1131D01*
G02Y205336I0J-1502D01*
G02X222805Y205706I0J1501D01*
G01X222804D01*
Y205707D01*
G03X222674Y205755I-130J-152D01*
G01X222410D01*
G03X222280Y205707I0J-200D01*
G01X222279Y205706D01*
G02X221292Y205336I-987J1131D01*
G37*
G36*
G01X215104Y201891D02*
G02Y204895I0J1502D01*
G02X216091Y204525I0J-1501D01*
G01X216092D01*
Y204524D01*
G03X216222Y204476I130J152D01*
G01X216486D01*
G03X216616Y204524I0J200D01*
G01X216617Y204525D01*
G02X217604Y204895I987J-1131D01*
G02X219101Y203517I0J-1502D01*
G01X219104Y203474D01*
X219145Y203400D01*
X219417Y203194D01*
G03X219576Y203157I121J159D01*
G02X219863Y203185I289J-1474D01*
G02X221365Y201683I0J-1502D01*
G02X220880Y200577I-1504J0D01*
G03X220815Y200430I135J-148D01*
G01Y200136D01*
G03X220880Y199989I200J1D01*
G02X221365Y198883I-1019J-1106D01*
G02X218361I-1502J0D01*
G02X218846Y199989I1504J0D01*
G03X218911Y200136I-135J148D01*
G01Y200430D01*
G03X218846Y200577I-200J-1D01*
G02X218366Y201559I1017J1105D01*
G01X218363Y201602D01*
X218322Y201676D01*
X218050Y201882D01*
G03X217891Y201919I-121J-159D01*
G02X217604Y201891I-289J1474D01*
G02X216617Y202261I0J1501D01*
G01X216616D01*
Y202262D01*
G03X216486Y202310I-130J-152D01*
G01X216222D01*
G03X216092Y202262I0J-200D01*
G01X216091Y202261D01*
G02X215104Y201891I-987J1131D01*
G37*
G36*
G01X220244Y196678D02*
G02X221350Y196193I0J-1504D01*
G03X221497Y196128I148J135D01*
G01X221791D01*
G03X221938Y196193I-1J200D01*
G02X223044Y196678I1106J-1019D01*
G02Y193674I0J-1502D01*
G02X221938Y194159I0J1504D01*
G03X221791Y194224I-148J-135D01*
G01X221497D01*
G03X221350Y194159I1J-200D01*
G02X220244Y193674I-1106J1019D01*
G02X219257Y194044I0J1501D01*
G01X219256D01*
Y194045D01*
G03X219126Y194093I-130J-152D01*
G01X218862D01*
G03X218732Y194045I0J-200D01*
G01X218731Y194044D01*
G02X216757I-987J1131D01*
G01X216756D01*
Y194045D01*
G03X216626Y194093I-130J-152D01*
G01X216362D01*
G03X216232Y194045I0J-200D01*
G01X216231Y194044D01*
G02X215244Y193674I-987J1131D01*
G02Y196678I0J1502D01*
G02X216231Y196308I0J-1501D01*
G01X216232D01*
Y196307D01*
G03X216362Y196259I130J152D01*
G01X216626D01*
G03X216756Y196307I0J200D01*
G01X216757Y196308D01*
G02X218731I987J-1131D01*
G01X218732D01*
Y196307D01*
G03X218862Y196259I130J152D01*
G01X219126D01*
G03X219256Y196307I0J200D01*
G01X219257Y196308D01*
G02X220244Y196678I987J-1131D01*
G37*
G36*
G01X240412Y123626D02*
G02X239987Y123677I1J1802D01*
G01X239984D01*
G03X239828Y123649I-46J-195D01*
G01X239547Y123462D01*
X239502Y123392D01*
X239496Y123350D01*
G02X238012Y122081I-1484J233D01*
G01X238011D01*
G02X237024Y122451I0J1502D01*
G01X236997Y122475D01*
X236929Y122501D01*
X236593D01*
X236526Y122476D01*
X236499Y122452D01*
G02X235512Y122082I-987J1131D01*
G02X235244Y122106I-1J1502D01*
G03X235078Y122060I-35J-197D01*
G01X234982Y121977D01*
G03X234912Y121817I130J-152D01*
G02X234914Y121743I-1800J-86D01*
G01Y118342D01*
G02X234912Y118263I-1802J6D01*
G03X234981Y118104I200J-8D01*
G01X235078Y118020D01*
G03X235245Y117975I130J152D01*
G02X235512Y117999I267J-1478D01*
G02X236499Y117629I0J-1501D01*
G01X236500D01*
Y117628D01*
G03X236630Y117580I130J152D01*
G01X236894D01*
G03X237024Y117628I0J200D01*
G01X237025Y117629D01*
G02X238012Y117999I987J-1131D01*
G02X239495Y116732I0J-1501D01*
G01X239502Y116690D01*
X239546Y116621D01*
X239862Y116411D01*
X239945Y116396D01*
X239985Y116406D01*
G02X240412Y116458I430J-1751D01*
G02X240760Y116424I0J-1803D01*
G01X240800Y116416D01*
X240879Y116432D01*
X241182Y116642D01*
X241224Y116708D01*
X241231Y116749D01*
G02X242712Y117998I1481J-254D01*
G02Y114994I0J-1502D01*
G01X242709D01*
G02X242531Y115005I3J1502D01*
G03X242373Y114954I-23J-199D01*
G01X242279Y114869D01*
G03X242213Y114715I134J-149D01*
G02X242214Y114655I-1801J-60D01*
G01Y111255D01*
G02X242213Y111192I-1802J-3D01*
G03X242278Y111038I200J-6D01*
G01X242373Y110952D01*
G03X242531Y110901I135J148D01*
G02X242709Y110912I181J-1491D01*
G01X242712D01*
G02Y107908I0J-1502D01*
G02X241231Y109160I0J1502D01*
G03X241147Y109292I-197J-33D01*
G01X240878Y109478D01*
X240799Y109494D01*
X240759Y109486D01*
G02X240412Y109452I-348J1769D01*
G02X239987Y109504I5J1802D01*
G01X239984D01*
G03X239828Y109476I-46J-195D01*
G01X239547Y109289D01*
X239502Y109219D01*
X239496Y109177D01*
G02X238012Y107908I-1484J233D01*
G02Y110912I0J1502D01*
G02X238279Y110888I0J-1502D01*
G03X238446Y110933I37J197D01*
G01X238543Y111017D01*
G03X238612Y111176I-131J151D01*
G02X238610Y111255I1800J85D01*
G01Y114656D01*
G02X238612Y114730I1802J-12D01*
G03X238542Y114890I-200J8D01*
G01X238446Y114973D01*
G03X238280Y115019I-131J-151D01*
G02X238012Y114995I-267J1478D01*
G02X237025Y115365I0J1501D01*
G01X237024D01*
Y115366D01*
G03X236894Y115414I-130J-152D01*
G01X236630D01*
G03X236500Y115366I0J-200D01*
G01X236499Y115365D01*
G02X235512Y114995I-987J1131D01*
G02X234028Y116264I0J1502D01*
G01X234022Y116306D01*
X233977Y116376D01*
X233696Y116563D01*
G03X233540Y116591I-110J-167D01*
G01X233538D01*
G02X233112Y116540I-426J1751D01*
G02X232687Y116591I1J1802D01*
G01X232684D01*
G03X232528Y116563I-46J-195D01*
G01X232247Y116376D01*
X232202Y116306D01*
X232196Y116264D01*
G02X230712Y114995I-1484J233D01*
G02Y117999I0J1502D01*
G02X230979Y117975I0J-1502D01*
G03X231146Y118020I37J197D01*
G01X231243Y118104D01*
G03X231312Y118263I-131J151D01*
G02X231310Y118342I1800J85D01*
G01Y121743D01*
G02X231312Y121817I1802J-12D01*
G03X231242Y121977I-200J8D01*
G01X231146Y122060D01*
G03X230980Y122106I-131J-151D01*
G02X230712Y122082I-267J1478D01*
G02Y125086I0J1502D01*
G02X232195Y123819I0J-1501D01*
G01X232202Y123777D01*
X232246Y123708D01*
X232562Y123498D01*
X232645Y123483D01*
X232685Y123493D01*
G02X233112Y123544I426J-1751D01*
G02X233539Y123493I1J-1802D01*
G01X233579Y123483D01*
X233662Y123498D01*
X233943Y123685D01*
G03X234029Y123819I-111J166D01*
G02X235512Y125086I1483J-234D01*
G01X235513D01*
G02X236500Y124716I0J-1502D01*
G01X236527Y124692D01*
X236595Y124666D01*
X236931D01*
X236998Y124691D01*
X237025Y124715D01*
G02X238012Y125085I987J-1131D01*
G02X238279Y125061I0J-1502D01*
G03X238446Y125106I37J197D01*
G01X238543Y125190D01*
G03X238612Y125349I-131J151D01*
G02X238610Y125428I1800J85D01*
G01Y128829D01*
G02X238612Y128903I1802J-12D01*
G03X238542Y129063I-200J8D01*
G01X238446Y129146D01*
G03X238280Y129192I-131J-151D01*
G02X238012Y129168I-267J1478D01*
G02X237025Y129538I0J1501D01*
G01X237024D01*
Y129539D01*
G03X236894Y129587I-130J-152D01*
G01X236630D01*
G03X236500Y129539I0J-200D01*
G01X236499Y129538D01*
G02X235512Y129168I-987J1131D01*
G02X234028Y130437I0J1502D01*
G01X234022Y130479D01*
X233977Y130549D01*
X233696Y130736D01*
G03X233540Y130764I-110J-167D01*
G01X233538D01*
G02X233112Y130712I-430J1751D01*
G02X232687Y130764I5J1802D01*
G01X232684D01*
G03X232528Y130736I-46J-195D01*
G01X232247Y130549D01*
X232202Y130479D01*
X232196Y130437D01*
G02X230712Y129168I-1484J233D01*
G02Y132172I0J1502D01*
G02X230979Y132148I0J-1502D01*
G03X231146Y132193I37J197D01*
G01X231243Y132277D01*
G03X231312Y132436I-131J151D01*
G02X231310Y132515I1800J85D01*
G01Y135916D01*
G02X231312Y135990I1802J-12D01*
G03X231242Y136150I-200J8D01*
G01X231146Y136233D01*
G03X230980Y136279I-131J-151D01*
G02X230712Y136255I-267J1478D01*
G02Y139259I0J1502D01*
G02X232195Y137992I0J-1501D01*
G01X232202Y137950D01*
X232246Y137881D01*
X232562Y137671D01*
X232645Y137656D01*
X232685Y137666D01*
G02X233112Y137718I430J-1751D01*
G02X233539Y137666I-3J-1803D01*
G01X233579Y137656D01*
X233662Y137671D01*
X233943Y137858D01*
G03X234029Y137992I-111J166D01*
G02X235512Y139259I1483J-234D01*
G02Y136255I0J-1502D01*
G02X235244Y136279I-1J1502D01*
G03X235078Y136233I-35J-197D01*
G01X234982Y136150D01*
G03X234912Y135990I130J-152D01*
G02X234914Y135916I-1800J-86D01*
G01Y132515D01*
G02X234912Y132436I-1802J6D01*
G03X234981Y132277I200J-8D01*
G01X235078Y132193D01*
G03X235245Y132148I130J152D01*
G02X235512Y132172I267J-1478D01*
G02X236499Y131802I0J-1501D01*
G01X236500D01*
Y131801D01*
G03X236630Y131753I130J152D01*
G01X236894D01*
G03X237024Y131801I0J200D01*
G01X237025Y131802D01*
G02X238012Y132172I987J-1131D01*
G02X239495Y130905I0J-1501D01*
G01X239502Y130863D01*
X239546Y130794D01*
X239862Y130584D01*
X239945Y130569D01*
X239985Y130579D01*
G02X240412Y130630I426J-1751D01*
G02X240760Y130597I5J-1802D01*
G01X240800Y130589D01*
X240879Y130605D01*
X241182Y130815D01*
X241224Y130881D01*
X241231Y130922D01*
G02X242712Y132172I1481J-252D01*
G02Y129168I0J-1502D01*
G01X242709D01*
G02X242531Y129179I3J1502D01*
G03X242373Y129128I-23J-199D01*
G01X242279Y129043D01*
G03X242213Y128889I134J-149D01*
G02X242214Y128828I-1801J-60D01*
G01Y125428D01*
G02X242213Y125365I-1802J-3D01*
G03X242278Y125211I200J-6D01*
G01X242373Y125125D01*
G03X242531Y125074I135J148D01*
G02X242709Y125085I181J-1491D01*
G01X242712D01*
G02Y122081I0J-1502D01*
G02X241231Y123333I0J1502D01*
G03X241147Y123465I-197J-33D01*
G01X240878Y123651D01*
X240799Y123667D01*
X240759Y123659D01*
G02X240412Y123626I-343J1769D01*
G37*
G36*
G01X249672Y85584D02*
G02X252676I1502J0D01*
G02X252270Y84557I-1502J0D01*
G01X252244Y84530D01*
X252216Y84459D01*
Y84109D01*
X252244Y84038D01*
X252270Y84011D01*
G02Y81957I-1096J-1027D01*
G01X252244Y81930D01*
X252216Y81859D01*
Y81509D01*
X252244Y81438D01*
X252270Y81411D01*
G02Y79357I-1096J-1027D01*
G01X252244Y79330D01*
X252216Y79259D01*
Y78909D01*
X252244Y78838D01*
X252270Y78811D01*
G02Y76757I-1096J-1027D01*
G01X252244Y76730D01*
X252216Y76659D01*
Y76309D01*
X252244Y76238D01*
X252270Y76211D01*
G02X252676Y75184I-1096J-1027D01*
G02X249672I-1502J0D01*
G02X250078Y76211I1502J0D01*
G01X250104Y76238D01*
X250132Y76309D01*
Y76659D01*
X250104Y76730D01*
X250078Y76757D01*
G02Y78811I1096J1027D01*
G01X250104Y78838D01*
X250132Y78909D01*
Y79259D01*
X250104Y79330D01*
X250078Y79357D01*
G02Y81411I1096J1027D01*
G01X250104Y81438D01*
X250132Y81509D01*
Y81859D01*
X250104Y81930D01*
X250078Y81957D01*
G02Y84011I1096J1027D01*
G01X250104Y84038D01*
X250132Y84109D01*
Y84459D01*
X250104Y84530D01*
X250078Y84557D01*
G02X249672Y85584I1096J1027D01*
G37*
G36*
G01X268007Y85193D02*
G02X271011I1502J0D01*
G02X270605Y84166I-1502J0D01*
G01X270579Y84139D01*
X270551Y84068D01*
Y83718D01*
X270579Y83647D01*
X270605Y83620D01*
G02Y81566I-1096J-1027D01*
G01X270579Y81539D01*
X270551Y81468D01*
Y81118D01*
X270579Y81047D01*
X270605Y81020D01*
G02Y78966I-1096J-1027D01*
G01X270579Y78939D01*
X270551Y78868D01*
Y78518D01*
X270579Y78447D01*
X270605Y78420D01*
G02Y76366I-1096J-1027D01*
G01X270579Y76339D01*
X270551Y76268D01*
Y75918D01*
X270579Y75847D01*
X270605Y75820D01*
G02X271011Y74793I-1096J-1027D01*
G02X268007I-1502J0D01*
G02X268413Y75820I1502J0D01*
G01X268439Y75847D01*
X268467Y75918D01*
Y76268D01*
X268439Y76339D01*
X268413Y76366D01*
G02Y78420I1096J1027D01*
G01X268439Y78447D01*
X268467Y78518D01*
Y78868D01*
X268439Y78939D01*
X268413Y78966D01*
G02Y81020I1096J1027D01*
G01X268439Y81047D01*
X268467Y81118D01*
Y81468D01*
X268439Y81539D01*
X268413Y81566D01*
G02Y83620I1096J1027D01*
G01X268439Y83647D01*
X268467Y83718D01*
Y84068D01*
X268439Y84139D01*
X268413Y84166D01*
G02X268007Y85193I1096J1027D01*
G37*
G36*
G01X291182Y74638D02*
G02Y77642I0J1502D01*
G01X291183D01*
G02X292103Y77327I0J-1502D01*
G03X292258Y77287I123J157D01*
G01X292546Y77334D01*
G03X292680Y77420I-32J197D01*
G01X292681Y77421D01*
G02X293930Y78089I1249J-834D01*
G02Y75085I0J-1502D01*
G01X293929D01*
G02X293009Y75400I0J1502D01*
G03X292854Y75440I-123J-157D01*
G01X292566Y75393D01*
G03X292432Y75307I32J-197D01*
G01X292431Y75306D01*
G02X291182Y74638I-1249J834D01*
G37*
G36*
G01X224752Y236121D02*
G02X227756I1502J0D01*
G02X227106Y234884I-1502J0D01*
G03X227112Y234222I227J-329D01*
G02X227782Y232971I-833J-1251D01*
G02X224778I-1502J0D01*
G02X225428Y234208I1502J0D01*
G03X225422Y234870I-227J329D01*
G02X224752Y236121I833J1251D01*
G37*
G36*
G01X222794Y221970D02*
G02X225798I1502J0D01*
G02X225428Y220983I-1501J0D01*
G01Y220982D01*
X225427D01*
G03X225379Y220852I152J-130D01*
G01Y220588D01*
G03X225427Y220458I200J0D01*
G01X225428Y220457D01*
G02Y218483I-1131J-987D01*
G01Y218482D01*
X225427D01*
G03X225379Y218352I152J-130D01*
G01Y218088D01*
G03X225427Y217958I200J0D01*
G01X225428Y217957D01*
G02X225798Y216970I-1131J-987D01*
G02X224296Y215468I-1502J0D01*
G02X223441Y215735I0J1502D01*
G01X223407Y215758D01*
X223326Y215775D01*
X222959Y215695D01*
X222892Y215647D01*
X222871Y215612D01*
G02X221583Y214883I-1288J773D01*
G02Y217887I0J1502D01*
G02X222438Y217620I0J-1502D01*
G01X222472Y217597D01*
X222553Y217580D01*
X222920Y217660D01*
X222987Y217708D01*
X223008Y217743D01*
G02X223164Y217956I1285J-777D01*
G03X223165Y217958I-173J88D01*
G03X223213Y218088I-152J130D01*
G01Y218352D01*
G03X223165Y218482I-200J0D01*
G01X223164Y218483D01*
G02Y220457I1131J987D01*
G01Y220458D01*
X223165D01*
G03X223213Y220588I-152J130D01*
G01Y220852D01*
G03X223165Y220982I-200J0D01*
G01X223164Y220983D01*
G02X222794Y221970I1131J987D01*
G37*
G36*
G01X280492Y223294D02*
Y223630D01*
X280467Y223697D01*
X280443Y223725D01*
G02X280073Y224712I1131J987D01*
G02X283077I1502J0D01*
G02X282707Y223725I-1501J0D01*
G01X282683Y223697D01*
X282658Y223630D01*
Y223294D01*
X282683Y223227D01*
X282707Y223199D01*
G02X283077Y222212I-1131J-987D01*
G02X280073I-1502J0D01*
G02X280443Y223199I1501J0D01*
G01X280467Y223227D01*
X280492Y223294D01*
G37*
G36*
G01X275167Y225189D02*
X274873D01*
G03X274726Y225124I1J-200D01*
G02X273620Y224639I-1105J1017D01*
G02Y227643I0J1502D01*
G02X274726Y227158I1J-1502D01*
G03X274873Y227093I148J135D01*
G01X275167D01*
G03X275314Y227158I-1J200D01*
G02X276420Y227643I1105J-1017D01*
G02Y224639I0J-1502D01*
G02X275314Y225124I-1J1502D01*
G03X275167Y225189I-148J-135D01*
G37*
G36*
G01X258374Y229808D02*
Y230144D01*
X258349Y230211D01*
X258325Y230239D01*
G02X257955Y231226I1131J987D01*
G02X260959I1502J0D01*
G02X260589Y230239I-1501J0D01*
G01X260565Y230211D01*
X260540Y230144D01*
Y229808D01*
X260565Y229741D01*
X260589Y229713D01*
G02Y227739I-1131J-987D01*
G01X260565Y227711D01*
X260540Y227644D01*
Y227308D01*
X260565Y227241D01*
X260589Y227213D01*
G02Y225239I-1131J-987D01*
G01X260565Y225211D01*
X260540Y225144D01*
Y224808D01*
X260565Y224741D01*
X260589Y224713D01*
G02X260959Y223726I-1131J-987D01*
G02X257955I-1502J0D01*
G02X258325Y224713I1501J0D01*
G01X258349Y224741D01*
X258374Y224808D01*
Y225144D01*
X258349Y225211D01*
X258325Y225239D01*
G02Y227213I1131J987D01*
G01X258349Y227241D01*
X258374Y227308D01*
Y227644D01*
X258349Y227711D01*
X258325Y227739D01*
G02Y229713I1131J987D01*
G01X258349Y229741D01*
X258374Y229808D01*
G37*
G36*
G01X268830Y230043D02*
Y230379D01*
X268805Y230446D01*
X268781Y230474D01*
G02X268411Y231461I1131J987D01*
G02X271415I1502J0D01*
G02X271045Y230474I-1501J0D01*
G01X271021Y230446D01*
X270996Y230379D01*
Y230043D01*
X271021Y229976D01*
X271045Y229948D01*
G02Y227974I-1131J-987D01*
G01X271021Y227946D01*
X270996Y227879D01*
Y227543D01*
X271021Y227476D01*
X271045Y227448D01*
G02X271415Y226461I-1131J-987D01*
G02X270930Y225355I-1502J-1D01*
G03X270865Y225208I135J-148D01*
G01Y224914D01*
G03X270930Y224767I200J1D01*
G02X271415Y223661I-1017J-1105D01*
G02X268411I-1502J0D01*
G02X268896Y224767I1502J1D01*
G03X268961Y224914I-135J148D01*
G01Y225208D01*
G03X268896Y225355I-200J-1D01*
G02X268411Y226461I1017J1105D01*
G02X268781Y227448I1501J0D01*
G01X268805Y227476D01*
X268830Y227543D01*
Y227879D01*
X268805Y227946D01*
X268781Y227974D01*
G02Y229948I1131J987D01*
G01X268805Y229976D01*
X268830Y230043D01*
G37*
G36*
G01X276799Y230368D02*
Y230704D01*
X276774Y230771D01*
X276750Y230799D01*
G02X276380Y231786I1131J987D01*
G02X279384I1502J0D01*
G02X279014Y230799I-1501J0D01*
G01X278990Y230771D01*
X278965Y230704D01*
Y230368D01*
X278990Y230301D01*
X279014Y230273D01*
G02X279384Y229286I-1131J-987D01*
G02X276380I-1502J0D01*
G02X276750Y230273I1501J0D01*
G01X276774Y230301D01*
X276799Y230368D01*
G37*
G36*
G01X274945Y237694D02*
X275281D01*
X275348Y237719D01*
X275376Y237743D01*
G02X277350I987J-1131D01*
G01X277378Y237719D01*
X277445Y237694D01*
X277781D01*
X277848Y237719D01*
X277876Y237743D01*
G02X278863Y238113I987J-1131D01*
G02Y235109I0J-1502D01*
G02X277876Y235479I0J1501D01*
G01X277848Y235503D01*
X277781Y235528D01*
X277445D01*
X277378Y235503D01*
X277350Y235479D01*
G02X275376I-987J1131D01*
G01X275348Y235503D01*
X275281Y235528D01*
X274945D01*
X274878Y235503D01*
X274850Y235479D01*
G02X273863Y235109I-987J1131D01*
G02Y238113I0J1502D01*
G02X274850Y237743I0J-1501D01*
G01X274878Y237719D01*
X274945Y237694D01*
G37*
G36*
G01X274647Y249974D02*
X274983D01*
X275050Y249999D01*
X275078Y250023D01*
G02X277052I987J-1131D01*
G01X277080Y249999D01*
X277147Y249974D01*
X277483D01*
X277550Y249999D01*
X277578Y250023D01*
G02X278565Y250393I987J-1131D01*
G02Y247389I0J-1502D01*
G02X277578Y247759I0J1501D01*
G01X277550Y247783D01*
X277483Y247808D01*
X277147D01*
X277080Y247783D01*
X277052Y247759D01*
G02X275078I-987J1131D01*
G01X275050Y247783D01*
X274983Y247808D01*
X274647D01*
X274580Y247783D01*
X274552Y247759D01*
G02X273565Y247389I-987J1131D01*
G02Y250393I0J1502D01*
G02X274552Y250023I0J-1501D01*
G01X274580Y249999D01*
X274647Y249974D01*
G37*
G36*
G01X278942Y190705D02*
G02X278294Y191941I855J1236D01*
G02X281298I1502J0D01*
G02X280545Y190639I-1502J0D01*
G03X280517Y189963I199J-347D01*
G02X281165Y188727I-855J-1236D01*
G02X278161I-1502J0D01*
G02X278914Y190029I1502J0D01*
G03X278942Y190705I-199J347D01*
G37*
G36*
G01X302985Y185330D02*
X303120Y185710D01*
X303110Y185800D01*
X303086Y185839D01*
G02X302861Y186629I1277J791D01*
G02X305865I1502J0D01*
G02X304862Y185212I-1502J0D01*
G01X304818Y185197D01*
X304755Y185133D01*
X304620Y184753D01*
X304630Y184663D01*
X304654Y184624D01*
G02X304879Y183834I-1277J-791D01*
G02X301875I-1502J0D01*
G02X302878Y185251I1502J0D01*
G01X302922Y185266D01*
X302985Y185330D01*
G37*
G36*
G01X298997Y191884D02*
X298975Y191837D01*
G02X297622Y190988I-1353J654D01*
G02Y193992I0J1502D01*
G02X298790Y193434I0J-1501D01*
G01X298823Y193394D01*
X298917Y193355D01*
X299356Y193406D01*
X299439Y193465D01*
X299461Y193512D01*
G02X300814Y194361I1353J-654D01*
G02X302316Y192859I0J-1502D01*
G02X302174Y192222I-1502J0D01*
G01X302150Y192171D01*
X302163Y192059D01*
X302451Y191689D01*
X302557Y191649D01*
X302612Y191660D01*
G02X302897Y191687I284J-1475D01*
G02X301395Y190185I0J-1502D01*
G02X301537Y190822I1502J0D01*
G01X301561Y190873D01*
X301548Y190985D01*
X301260Y191355D01*
X301154Y191395D01*
X301099Y191384D01*
G02X300814Y191357I-284J1475D01*
G02X299646Y191915I0J1501D01*
G01X299613Y191955D01*
X299519Y191994D01*
X299080Y191943D01*
X298997Y191884D01*
G37*
G36*
G01X328603Y148717D02*
G02X331607I1502J0D01*
G02X330602Y147300I-1501J0D01*
G03X330482Y147183I67J-188D01*
G01X330356Y146857D01*
X330362Y146770D01*
X330383Y146731D01*
G02X330566Y146013I-1319J-719D01*
G01Y146012D01*
G02X329906Y144768I-1502J0D01*
G03X329818Y144603I112J-166D01*
G01Y144271D01*
G03X329906Y144106I200J1D01*
G02X330551Y143074I-842J-1244D01*
G01Y143073D01*
G03X330619Y142950I198J29D01*
G01X330819Y142778D01*
G03X330952Y142730I130J152D01*
G01X330970D01*
G02Y139726I0J-1502D01*
G02X329483Y141016I0J1502D01*
G01Y141017D01*
G03X329415Y141140I-198J-29D01*
G01X329215Y141312D01*
G03X329082Y141360I-130J-152D01*
G01X329064D01*
G02X327562Y142862I0J1502D01*
G02X328222Y144106I1502J0D01*
G03X328310Y144271I-112J166D01*
G01Y144603D01*
G03X328222Y144768I-200J-1D01*
G02X327562Y146012I842J1244D01*
G02X328567Y147429I1501J0D01*
G03X328687Y147546I-67J188D01*
G01X328813Y147872D01*
X328807Y147959D01*
X328786Y147998D01*
G02X328603Y148716I1319J719D01*
G01Y148717D01*
G37*
G36*
G01X328666Y110018D02*
X328980D01*
G03X329138Y110095I0J200D01*
G02X330323Y110674I1185J-923D01*
G02X331825Y109172I0J-1502D01*
G02X330862Y107770I-1502J0D01*
G01X330860D01*
X330820Y107754D01*
X330761Y107694D01*
X330626Y107330D01*
X330632Y107245D01*
X330653Y107207D01*
G02X330832Y106497I-1323J-711D01*
G01Y106495D01*
G02X327828I-1502J0D01*
G02X327966Y107123I1502J-1D01*
G01Y107124D01*
G03X327945Y107327I-182J84D01*
G01X327700Y107653D01*
X327599Y107694D01*
X327544Y107686D01*
G02X327323Y107670I-219J1486D01*
G02Y110674I0J1502D01*
G02X328508Y110095I0J-1502D01*
G03X328666Y110018I158J123D01*
G37*
G36*
G01X340791Y106561D02*
G02X343795I1502J0D01*
G02X343069Y105275I-1502J0D01*
G03X342973Y105114I104J-171D01*
G01X342955Y104782D01*
G03X343035Y104612I200J-10D01*
G02X343590Y103779I-901J-1202D01*
G03X343715Y103641I194J50D01*
G01X344024Y103526D01*
G03X344208Y103550I69J188D01*
G02X345074Y103825I866J-1226D01*
G02Y100821I0J-1502D01*
G02X343618Y101955I0J1502D01*
G03X343493Y102093I-194J-50D01*
G01X343184Y102208D01*
G03X343000Y102184I-69J-188D01*
G02X342134Y101909I-866J1226D01*
G02X340632Y103411I0J1502D01*
G02X341358Y104697I1502J0D01*
G03X341454Y104858I-104J171D01*
G01X341472Y105190D01*
G03X341392Y105360I-200J10D01*
G02X340791Y106561I901J1202D01*
G37*
G36*
G01X397703Y102731D02*
G02X397411Y103621I1210J890D01*
G02X400415I1502J0D01*
G02X399190Y102145I-1502J0D01*
G03X398941Y101515I73J-393D01*
G02X399233Y100625I-1210J-890D01*
G02X396229I-1502J0D01*
G02X397454Y102101I1502J0D01*
G03X397703Y102731I-73J393D01*
G37*
G36*
G01X362131Y101849D02*
G02X361548Y103037I919J1188D01*
G02X364552I1502J0D01*
G02X363896Y101796I-1502J0D01*
G03X363876Y101149I225J-331D01*
G02X364459Y99961I-919J-1188D01*
G02X361455I-1502J0D01*
G02X362111Y101202I1502J0D01*
G03X362131Y101849I-225J331D01*
G37*
G36*
G01X356644Y91453D02*
G02X356090Y91347I-554J1395D01*
G02X357592Y92849I0J1502D01*
G02X357546Y92481I-1502J1D01*
G03X358082Y92011I388J-98D01*
G02X358636Y92117I554J-1395D01*
G02X357134Y90615I0J-1502D01*
G02X357180Y90983I1502J-1D01*
G03X356644Y91453I-388J98D01*
G37*
G36*
G01X387400Y25890D02*
G02X386446Y27288I547J1398D01*
G02X389450I1502J0D01*
G02X388922Y26144I-1503J0D01*
G03X389035Y25467I259J-305D01*
G02X389989Y24069I-547J-1398D01*
G02X386985I-1502J0D01*
G02X387513Y25213I1503J0D01*
G03X387400Y25890I-259J305D01*
G37*
G36*
G01X318892Y217133D02*
X318598D01*
G03X318451Y217068I1J-200D01*
G02X317345Y216583I-1106J1019D01*
G02Y219587I0J1502D01*
G02X318451Y219102I0J-1504D01*
G03X318598Y219037I148J135D01*
G01X318892D01*
G03X319039Y219102I-1J200D01*
G02X320145Y219587I1106J-1019D01*
G02Y216583I0J-1502D01*
G02X319039Y217068I0J1504D01*
G03X318892Y217133I-148J-135D01*
G37*
G36*
G01X323654Y205336D02*
G02Y208340I0J1502D01*
G02X324641Y207970I0J-1501D01*
G01X324642D01*
Y207969D01*
G03X324772Y207921I130J152D01*
G01X325036D01*
G03X325166Y207969I0J200D01*
G01X325167Y207970D01*
G02X326154Y208340I987J-1131D01*
G02Y205336I0J-1502D01*
G02X325167Y205706I0J1501D01*
G01X325166D01*
Y205707D01*
G03X325036Y205755I-130J-152D01*
G01X324772D01*
G03X324642Y205707I0J-200D01*
G01X324641Y205706D01*
G02X323654Y205336I-987J1131D01*
G37*
G36*
G01X317466Y201891D02*
G02Y204895I0J1502D01*
G02X318453Y204525I0J-1501D01*
G01X318454D01*
Y204524D01*
G03X318584Y204476I130J152D01*
G01X318848D01*
G03X318978Y204524I0J200D01*
G01X318979Y204525D01*
G02X319966Y204895I987J-1131D01*
G02X321463Y203517I0J-1502D01*
G01X321466Y203474D01*
X321507Y203400D01*
X321779Y203194D01*
G03X321938Y203157I121J159D01*
G02X322225Y203185I289J-1474D01*
G02X323727Y201683I0J-1502D01*
G02X323242Y200577I-1504J0D01*
G03X323177Y200430I135J-148D01*
G01Y200136D01*
G03X323242Y199989I200J1D01*
G02X323727Y198883I-1019J-1106D01*
G02X320723I-1502J0D01*
G02X321208Y199989I1504J0D01*
G03X321273Y200136I-135J148D01*
G01Y200430D01*
G03X321208Y200577I-200J-1D01*
G02X320728Y201559I1017J1105D01*
G01X320725Y201602D01*
X320684Y201676D01*
X320412Y201882D01*
G03X320253Y201919I-121J-159D01*
G02X319966Y201891I-289J1474D01*
G02X318979Y202261I0J1501D01*
G01X318978D01*
Y202262D01*
G03X318848Y202310I-130J-152D01*
G01X318584D01*
G03X318454Y202262I0J-200D01*
G01X318453Y202261D01*
G02X317466Y201891I-987J1131D01*
G37*
G36*
G01X322606Y196678D02*
G02X323712Y196193I0J-1504D01*
G03X323859Y196128I148J135D01*
G01X324153D01*
G03X324300Y196193I-1J200D01*
G02X325406Y196678I1106J-1019D01*
G02Y193674I0J-1502D01*
G02X324300Y194159I0J1504D01*
G03X324153Y194224I-148J-135D01*
G01X323859D01*
G03X323712Y194159I1J-200D01*
G02X322606Y193674I-1106J1019D01*
G02X321619Y194044I0J1501D01*
G01X321618D01*
Y194045D01*
G03X321488Y194093I-130J-152D01*
G01X321224D01*
G03X321094Y194045I0J-200D01*
G01X321093Y194044D01*
G02X319119I-987J1131D01*
G01X319118D01*
Y194045D01*
G03X318988Y194093I-130J-152D01*
G01X318724D01*
G03X318594Y194045I0J-200D01*
G01X318593Y194044D01*
G02X317606Y193674I-987J1131D01*
G02Y196678I0J1502D01*
G02X318593Y196308I0J-1501D01*
G01X318594D01*
Y196307D01*
G03X318724Y196259I130J152D01*
G01X318988D01*
G03X319118Y196307I0J200D01*
G01X319119Y196308D01*
G02X321093I987J-1131D01*
G01X321094D01*
Y196307D01*
G03X321224Y196259I130J152D01*
G01X321488D01*
G03X321618Y196307I0J200D01*
G01X321619Y196308D01*
G02X322606Y196678I987J-1131D01*
G37*
G36*
G01X342774Y123626D02*
G02X342349Y123677I1J1802D01*
G01X342346D01*
G03X342190Y123649I-46J-195D01*
G01X341909Y123462D01*
X341864Y123392D01*
X341858Y123350D01*
G02X340374Y122081I-1484J233D01*
G01X340373D01*
G02X339386Y122451I0J1502D01*
G01X339359Y122475D01*
X339291Y122501D01*
X338955D01*
X338888Y122476D01*
X338861Y122452D01*
G02X337874Y122082I-987J1131D01*
G02X337606Y122106I-1J1502D01*
G03X337440Y122060I-35J-197D01*
G01X337344Y121977D01*
G03X337274Y121817I130J-152D01*
G02X337276Y121743I-1800J-86D01*
G01Y118342D01*
G02X337274Y118263I-1802J6D01*
G03X337343Y118104I200J-8D01*
G01X337440Y118020D01*
G03X337607Y117975I130J152D01*
G02X337874Y117999I267J-1478D01*
G02X338861Y117629I0J-1501D01*
G01X338862D01*
Y117628D01*
G03X338992Y117580I130J152D01*
G01X339256D01*
G03X339386Y117628I0J200D01*
G01X339387Y117629D01*
G02X340374Y117999I987J-1131D01*
G02X341857Y116732I0J-1501D01*
G01X341864Y116690D01*
X341908Y116621D01*
X342224Y116411D01*
X342307Y116396D01*
X342347Y116406D01*
G02X342774Y116458I430J-1751D01*
G02X343122Y116424I0J-1803D01*
G01X343162Y116416D01*
X343241Y116432D01*
X343544Y116642D01*
X343586Y116708D01*
X343593Y116749D01*
G02X345074Y117998I1481J-254D01*
G02Y114994I0J-1502D01*
G01X345071D01*
G02X344893Y115005I3J1502D01*
G03X344735Y114954I-23J-199D01*
G01X344641Y114869D01*
G03X344575Y114715I134J-149D01*
G02X344576Y114655I-1801J-60D01*
G01Y111255D01*
G02X344575Y111192I-1802J-3D01*
G03X344640Y111038I200J-6D01*
G01X344735Y110952D01*
G03X344893Y110901I135J148D01*
G02X345071Y110912I181J-1491D01*
G01X345074D01*
G02Y107908I0J-1502D01*
G02X343593Y109160I0J1502D01*
G03X343509Y109292I-197J-33D01*
G01X343240Y109478D01*
X343161Y109494D01*
X343121Y109486D01*
G02X342774Y109452I-348J1769D01*
G02X342349Y109504I5J1802D01*
G01X342346D01*
G03X342190Y109476I-46J-195D01*
G01X341909Y109289D01*
X341864Y109219D01*
X341858Y109177D01*
G02X340374Y107908I-1484J233D01*
G02Y110912I0J1502D01*
G02X340641Y110888I0J-1502D01*
G03X340808Y110933I37J197D01*
G01X340905Y111017D01*
G03X340974Y111176I-131J151D01*
G02X340972Y111255I1800J85D01*
G01Y114656D01*
G02X340974Y114730I1802J-12D01*
G03X340904Y114890I-200J8D01*
G01X340808Y114973D01*
G03X340642Y115019I-131J-151D01*
G02X340374Y114995I-267J1478D01*
G02X339387Y115365I0J1501D01*
G01X339386D01*
Y115366D01*
G03X339256Y115414I-130J-152D01*
G01X338992D01*
G03X338862Y115366I0J-200D01*
G01X338861Y115365D01*
G02X337874Y114995I-987J1131D01*
G02X336390Y116264I0J1502D01*
G01X336384Y116306D01*
X336339Y116376D01*
X336058Y116563D01*
G03X335902Y116591I-110J-167D01*
G01X335900D01*
G02X335474Y116540I-426J1751D01*
G02X335049Y116591I1J1802D01*
G01X335046D01*
G03X334890Y116563I-46J-195D01*
G01X334609Y116376D01*
X334564Y116306D01*
X334558Y116264D01*
G02X333074Y114995I-1484J233D01*
G02Y117999I0J1502D01*
G02X333341Y117975I0J-1502D01*
G03X333508Y118020I37J197D01*
G01X333605Y118104D01*
G03X333674Y118263I-131J151D01*
G02X333672Y118342I1800J85D01*
G01Y121743D01*
G02X333674Y121817I1802J-12D01*
G03X333604Y121977I-200J8D01*
G01X333508Y122060D01*
G03X333342Y122106I-131J-151D01*
G02X333074Y122082I-267J1478D01*
G02Y125086I0J1502D01*
G02X334557Y123819I0J-1501D01*
G01X334564Y123777D01*
X334608Y123708D01*
X334924Y123498D01*
X335007Y123483D01*
X335047Y123493D01*
G02X335474Y123544I426J-1751D01*
G02X335901Y123493I1J-1802D01*
G01X335941Y123483D01*
X336024Y123498D01*
X336305Y123685D01*
G03X336391Y123819I-111J166D01*
G02X337874Y125086I1483J-234D01*
G01X337875D01*
G02X338862Y124716I0J-1502D01*
G01X338889Y124692D01*
X338957Y124666D01*
X339293D01*
X339360Y124691D01*
X339387Y124715D01*
G02X340374Y125085I987J-1131D01*
G02X340641Y125061I0J-1502D01*
G03X340808Y125106I37J197D01*
G01X340905Y125190D01*
G03X340974Y125349I-131J151D01*
G02X340972Y125428I1800J85D01*
G01Y128829D01*
G02X340974Y128903I1802J-12D01*
G03X340904Y129063I-200J8D01*
G01X340808Y129146D01*
G03X340642Y129192I-131J-151D01*
G02X340374Y129168I-267J1478D01*
G02X339387Y129538I0J1501D01*
G01X339386D01*
Y129539D01*
G03X339256Y129587I-130J-152D01*
G01X338992D01*
G03X338862Y129539I0J-200D01*
G01X338861Y129538D01*
G02X337874Y129168I-987J1131D01*
G02X336390Y130437I0J1502D01*
G01X336384Y130479D01*
X336339Y130549D01*
X336058Y130736D01*
G03X335902Y130764I-110J-167D01*
G01X335900D01*
G02X335474Y130712I-430J1751D01*
G02X335049Y130764I5J1802D01*
G01X335046D01*
G03X334890Y130736I-46J-195D01*
G01X334609Y130549D01*
X334564Y130479D01*
X334558Y130437D01*
G02X333074Y129168I-1484J233D01*
G02Y132172I0J1502D01*
G02X333341Y132148I0J-1502D01*
G03X333508Y132193I37J197D01*
G01X333605Y132277D01*
G03X333674Y132436I-131J151D01*
G02X333672Y132515I1800J85D01*
G01Y135916D01*
G02X333674Y135990I1802J-12D01*
G03X333604Y136150I-200J8D01*
G01X333508Y136233D01*
G03X333342Y136279I-131J-151D01*
G02X333074Y136255I-267J1478D01*
G02Y139259I0J1502D01*
G02X334557Y137992I0J-1501D01*
G01X334564Y137950D01*
X334608Y137881D01*
X334924Y137671D01*
X335007Y137656D01*
X335047Y137666D01*
G02X335474Y137718I430J-1751D01*
G02X335901Y137666I-3J-1803D01*
G01X335941Y137656D01*
X336024Y137671D01*
X336305Y137858D01*
G03X336391Y137992I-111J166D01*
G02X337874Y139259I1483J-234D01*
G02Y136255I0J-1502D01*
G02X337606Y136279I-1J1502D01*
G03X337440Y136233I-35J-197D01*
G01X337344Y136150D01*
G03X337274Y135990I130J-152D01*
G02X337276Y135916I-1800J-86D01*
G01Y132515D01*
G02X337274Y132436I-1802J6D01*
G03X337343Y132277I200J-8D01*
G01X337440Y132193D01*
G03X337607Y132148I130J152D01*
G02X337874Y132172I267J-1478D01*
G02X338861Y131802I0J-1501D01*
G01X338862D01*
Y131801D01*
G03X338992Y131753I130J152D01*
G01X339256D01*
G03X339386Y131801I0J200D01*
G01X339387Y131802D01*
G02X340374Y132172I987J-1131D01*
G02X341857Y130905I0J-1501D01*
G01X341864Y130863D01*
X341908Y130794D01*
X342224Y130584D01*
X342307Y130569D01*
X342347Y130579D01*
G02X342774Y130630I426J-1751D01*
G02X343122Y130597I5J-1802D01*
G01X343162Y130589D01*
X343241Y130605D01*
X343544Y130815D01*
X343586Y130881D01*
X343593Y130922D01*
G02X345074Y132172I1481J-252D01*
G02Y129168I0J-1502D01*
G01X345071D01*
G02X344893Y129179I3J1502D01*
G03X344735Y129128I-23J-199D01*
G01X344641Y129043D01*
G03X344575Y128889I134J-149D01*
G02X344576Y128828I-1801J-60D01*
G01Y125428D01*
G02X344575Y125365I-1802J-3D01*
G03X344640Y125211I200J-6D01*
G01X344735Y125125D01*
G03X344893Y125074I135J148D01*
G02X345071Y125085I181J-1491D01*
G01X345074D01*
G02Y122081I0J-1502D01*
G02X343593Y123333I0J1502D01*
G03X343509Y123465I-197J-33D01*
G01X343240Y123651D01*
X343161Y123667D01*
X343121Y123659D01*
G02X342774Y123626I-343J1769D01*
G37*
G36*
G01X352034Y85584D02*
G02X355038I1502J0D01*
G02X354632Y84557I-1502J0D01*
G01X354606Y84530D01*
X354578Y84459D01*
Y84109D01*
X354606Y84038D01*
X354632Y84011D01*
G02Y81957I-1096J-1027D01*
G01X354606Y81930D01*
X354578Y81859D01*
Y81509D01*
X354606Y81438D01*
X354632Y81411D01*
G02Y79357I-1096J-1027D01*
G01X354606Y79330D01*
X354578Y79259D01*
Y78909D01*
X354606Y78838D01*
X354632Y78811D01*
G02Y76757I-1096J-1027D01*
G01X354606Y76730D01*
X354578Y76659D01*
Y76309D01*
X354606Y76238D01*
X354632Y76211D01*
G02X355038Y75184I-1096J-1027D01*
G02X352034I-1502J0D01*
G02X352440Y76211I1502J0D01*
G01X352466Y76238D01*
X352494Y76309D01*
Y76659D01*
X352466Y76730D01*
X352440Y76757D01*
G02Y78811I1096J1027D01*
G01X352466Y78838D01*
X352494Y78909D01*
Y79259D01*
X352466Y79330D01*
X352440Y79357D01*
G02Y81411I1096J1027D01*
G01X352466Y81438D01*
X352494Y81509D01*
Y81859D01*
X352466Y81930D01*
X352440Y81957D01*
G02Y84011I1096J1027D01*
G01X352466Y84038D01*
X352494Y84109D01*
Y84459D01*
X352466Y84530D01*
X352440Y84557D01*
G02X352034Y85584I1096J1027D01*
G37*
G36*
G01X370369Y85193D02*
G02X373373I1502J0D01*
G02X372967Y84166I-1502J0D01*
G01X372941Y84139D01*
X372913Y84068D01*
Y83718D01*
X372941Y83647D01*
X372967Y83620D01*
G02Y81566I-1096J-1027D01*
G01X372941Y81539D01*
X372913Y81468D01*
Y81118D01*
X372941Y81047D01*
X372967Y81020D01*
G02Y78966I-1096J-1027D01*
G01X372941Y78939D01*
X372913Y78868D01*
Y78518D01*
X372941Y78447D01*
X372967Y78420D01*
G02Y76366I-1096J-1027D01*
G01X372941Y76339D01*
X372913Y76268D01*
Y75918D01*
X372941Y75847D01*
X372967Y75820D01*
G02X373373Y74793I-1096J-1027D01*
G02X370369I-1502J0D01*
G02X370775Y75820I1502J0D01*
G01X370801Y75847D01*
X370829Y75918D01*
Y76268D01*
X370801Y76339D01*
X370775Y76366D01*
G02Y78420I1096J1027D01*
G01X370801Y78447D01*
X370829Y78518D01*
Y78868D01*
X370801Y78939D01*
X370775Y78966D01*
G02Y81020I1096J1027D01*
G01X370801Y81047D01*
X370829Y81118D01*
Y81468D01*
X370801Y81539D01*
X370775Y81566D01*
G02Y83620I1096J1027D01*
G01X370801Y83647D01*
X370829Y83718D01*
Y84068D01*
X370801Y84139D01*
X370775Y84166D01*
G02X370369Y85193I1096J1027D01*
G37*
G36*
G01X327114Y236121D02*
G02X330118I1502J0D01*
G02X329468Y234884I-1502J0D01*
G03X329474Y234222I227J-329D01*
G02X330144Y232971I-833J-1251D01*
G02X327140I-1502J0D01*
G02X327790Y234208I1502J0D01*
G03X327784Y234870I-227J329D01*
G02X327114Y236121I833J1251D01*
G37*
G36*
G01X325156Y221970D02*
G02X328160I1502J0D01*
G02X327790Y220983I-1501J0D01*
G01Y220982D01*
X327789D01*
G03X327741Y220852I152J-130D01*
G01Y220588D01*
G03X327789Y220458I200J0D01*
G01X327790Y220457D01*
G02Y218483I-1131J-987D01*
G01Y218482D01*
X327789D01*
G03X327741Y218352I152J-130D01*
G01Y218088D01*
G03X327789Y217958I200J0D01*
G01X327790Y217957D01*
G02X328160Y216970I-1131J-987D01*
G02X326658Y215468I-1502J0D01*
G02X325803Y215735I0J1502D01*
G01X325769Y215758D01*
X325688Y215775D01*
X325321Y215695D01*
X325254Y215647D01*
X325233Y215612D01*
G02X323945Y214883I-1288J773D01*
G02Y217887I0J1502D01*
G02X324800Y217620I0J-1502D01*
G01X324834Y217597D01*
X324915Y217580D01*
X325282Y217660D01*
X325349Y217708D01*
X325370Y217743D01*
G02X325526Y217956I1285J-777D01*
G03X325527Y217958I-173J88D01*
G03X325575Y218088I-152J130D01*
G01Y218352D01*
G03X325527Y218482I-200J0D01*
G01X325526Y218483D01*
G02Y220457I1131J987D01*
G01Y220458D01*
X325527D01*
G03X325575Y220588I-152J130D01*
G01Y220852D01*
G03X325527Y220982I-200J0D01*
G01X325526Y220983D01*
G02X325156Y221970I1131J987D01*
G37*
G36*
G01X382854Y223294D02*
Y223630D01*
X382829Y223697D01*
X382805Y223725D01*
G02X382435Y224712I1131J987D01*
G02X385439I1502J0D01*
G02X385069Y223725I-1501J0D01*
G01X385045Y223697D01*
X385020Y223630D01*
Y223294D01*
X385045Y223227D01*
X385069Y223199D01*
G02X385439Y222212I-1131J-987D01*
G02X382435I-1502J0D01*
G02X382805Y223199I1501J0D01*
G01X382829Y223227D01*
X382854Y223294D01*
G37*
G36*
G01X377529Y225189D02*
X377235D01*
G03X377088Y225124I1J-200D01*
G02X375982Y224639I-1105J1017D01*
G02Y227643I0J1502D01*
G02X377088Y227158I1J-1502D01*
G03X377235Y227093I148J135D01*
G01X377529D01*
G03X377676Y227158I-1J200D01*
G02X378782Y227643I1105J-1017D01*
G02Y224639I0J-1502D01*
G02X377676Y225124I-1J1502D01*
G03X377529Y225189I-148J-135D01*
G37*
G36*
G01X360736Y229808D02*
Y230144D01*
X360711Y230211D01*
X360687Y230239D01*
G02X360317Y231226I1131J987D01*
G02X363321I1502J0D01*
G02X362951Y230239I-1501J0D01*
G01X362927Y230211D01*
X362902Y230144D01*
Y229808D01*
X362927Y229741D01*
X362951Y229713D01*
G02Y227739I-1131J-987D01*
G01X362927Y227711D01*
X362902Y227644D01*
Y227308D01*
X362927Y227241D01*
X362951Y227213D01*
G02Y225239I-1131J-987D01*
G01X362927Y225211D01*
X362902Y225144D01*
Y224808D01*
X362927Y224741D01*
X362951Y224713D01*
G02X363321Y223726I-1131J-987D01*
G02X360317I-1502J0D01*
G02X360687Y224713I1501J0D01*
G01X360711Y224741D01*
X360736Y224808D01*
Y225144D01*
X360711Y225211D01*
X360687Y225239D01*
G02Y227213I1131J987D01*
G01X360711Y227241D01*
X360736Y227308D01*
Y227644D01*
X360711Y227711D01*
X360687Y227739D01*
G02Y229713I1131J987D01*
G01X360711Y229741D01*
X360736Y229808D01*
G37*
G36*
G01X371192Y230043D02*
Y230379D01*
X371167Y230446D01*
X371143Y230474D01*
G02X370773Y231461I1131J987D01*
G02X373777I1502J0D01*
G02X373407Y230474I-1501J0D01*
G01X373383Y230446D01*
X373358Y230379D01*
Y230043D01*
X373383Y229976D01*
X373407Y229948D01*
G02Y227974I-1131J-987D01*
G01X373383Y227946D01*
X373358Y227879D01*
Y227543D01*
X373383Y227476D01*
X373407Y227448D01*
G02X373777Y226461I-1131J-987D01*
G02X373292Y225355I-1502J-1D01*
G03X373227Y225208I135J-148D01*
G01Y224914D01*
G03X373292Y224767I200J1D01*
G02X373777Y223661I-1017J-1105D01*
G02X370773I-1502J0D01*
G02X371258Y224767I1502J1D01*
G03X371323Y224914I-135J148D01*
G01Y225208D01*
G03X371258Y225355I-200J-1D01*
G02X370773Y226461I1017J1105D01*
G02X371143Y227448I1501J0D01*
G01X371167Y227476D01*
X371192Y227543D01*
Y227879D01*
X371167Y227946D01*
X371143Y227974D01*
G02Y229948I1131J987D01*
G01X371167Y229976D01*
X371192Y230043D01*
G37*
G36*
G01X379161Y230368D02*
Y230704D01*
X379136Y230771D01*
X379112Y230799D01*
G02X378742Y231786I1131J987D01*
G02X381746I1502J0D01*
G02X381376Y230799I-1501J0D01*
G01X381352Y230771D01*
X381327Y230704D01*
Y230368D01*
X381352Y230301D01*
X381376Y230273D01*
G02X381746Y229286I-1131J-987D01*
G02X378742I-1502J0D01*
G02X379112Y230273I1501J0D01*
G01X379136Y230301D01*
X379161Y230368D01*
G37*
G36*
G01X377307Y237694D02*
X377643D01*
X377710Y237719D01*
X377738Y237743D01*
G02X379712I987J-1131D01*
G01X379740Y237719D01*
X379807Y237694D01*
X380143D01*
X380210Y237719D01*
X380238Y237743D01*
G02X381225Y238113I987J-1131D01*
G02Y235109I0J-1502D01*
G02X380238Y235479I0J1501D01*
G01X380210Y235503D01*
X380143Y235528D01*
X379807D01*
X379740Y235503D01*
X379712Y235479D01*
G02X377738I-987J1131D01*
G01X377710Y235503D01*
X377643Y235528D01*
X377307D01*
X377240Y235503D01*
X377212Y235479D01*
G02X376225Y235109I-987J1131D01*
G02Y238113I0J1502D01*
G02X377212Y237743I0J-1501D01*
G01X377240Y237719D01*
X377307Y237694D01*
G37*
G36*
G01X377009Y249974D02*
X377345D01*
X377412Y249999D01*
X377440Y250023D01*
G02X379414I987J-1131D01*
G01X379442Y249999D01*
X379509Y249974D01*
X379845D01*
X379912Y249999D01*
X379940Y250023D01*
G02X380927Y250393I987J-1131D01*
G02Y247389I0J-1502D01*
G02X379940Y247759I0J1501D01*
G01X379912Y247783D01*
X379845Y247808D01*
X379509D01*
X379442Y247783D01*
X379414Y247759D01*
G02X377440I-987J1131D01*
G01X377412Y247783D01*
X377345Y247808D01*
X377009D01*
X376942Y247783D01*
X376914Y247759D01*
G02X375927Y247389I-987J1131D01*
G02Y250393I0J1502D01*
G02X376914Y250023I0J-1501D01*
G01X376942Y249999D01*
X377009Y249974D01*
G37*
G36*
G01X381304Y190705D02*
G02X380656Y191941I855J1236D01*
G02X383660I1502J0D01*
G02X382907Y190639I-1502J0D01*
G03X382879Y189963I199J-347D01*
G02X383527Y188727I-855J-1236D01*
G02X380523I-1502J0D01*
G02X381276Y190029I1502J0D01*
G03X381304Y190705I-199J347D01*
G37*
G36*
G01X405347Y185330D02*
X405482Y185710D01*
X405472Y185800D01*
X405448Y185839D01*
G02X405223Y186629I1277J791D01*
G02X408227I1502J0D01*
G02X407224Y185212I-1502J0D01*
G01X407180Y185197D01*
X407117Y185133D01*
X406982Y184753D01*
X406992Y184663D01*
X407016Y184624D01*
G02X407241Y183834I-1277J-791D01*
G02X404237I-1502J0D01*
G02X405240Y185251I1502J0D01*
G01X405284Y185266D01*
X405347Y185330D01*
G37*
G36*
G01X451789Y1003333D02*
X451426Y1003469D01*
X451340Y1003463D01*
X451302Y1003443D01*
G02X450591Y1003264I-711J1323D01*
G02Y1006268I0J1502D01*
G02X451996Y1005297I0J-1502D01*
G01X452011Y1005256D01*
X452072Y1005196D01*
X452435Y1005060D01*
X452521Y1005066D01*
X452559Y1005086D01*
G02X453270Y1005265I711J-1323D01*
G02Y1002261I0J-1502D01*
G02X451865Y1003232I0J1502D01*
G01X451850Y1003273D01*
X451789Y1003333D01*
G37*
G36*
G01X411129Y1061780D02*
X411465D01*
X411532Y1061805D01*
X411560Y1061829D01*
G02X413534I987J-1131D01*
G01X413562Y1061805D01*
X413629Y1061780D01*
X413965D01*
X414032Y1061805D01*
X414060Y1061829D01*
G02X415047Y1062199I987J-1131D01*
G02X416549Y1060697I0J-1502D01*
G02X416143Y1059670I-1502J0D01*
G01X416117Y1059642D01*
X416089Y1059573D01*
Y1059221D01*
X416117Y1059152D01*
X416143Y1059124D01*
G02X416549Y1058097I-1096J-1027D01*
G02X415047Y1056595I-1502J0D01*
G02X414060Y1056965I0J1501D01*
G01X414032Y1056989D01*
X413965Y1057014D01*
X413629D01*
X413562Y1056989D01*
X413534Y1056965D01*
G02X411560I-987J1131D01*
G01X411532Y1056989D01*
X411465Y1057014D01*
X411129D01*
X411062Y1056989D01*
X411034Y1056965D01*
G02X409060I-987J1131D01*
G01X409032Y1056989D01*
X408965Y1057014D01*
X408629D01*
X408562Y1056989D01*
X408534Y1056965D01*
G02X406560I-987J1131D01*
G01X406532Y1056989D01*
X406465Y1057014D01*
X406129D01*
X406062Y1056989D01*
X406034Y1056965D01*
G02X405047Y1056595I-987J1131D01*
G02X403545Y1058097I0J1502D01*
G02X403951Y1059124I1502J0D01*
G01X403977Y1059152D01*
X404005Y1059221D01*
Y1059573D01*
X403977Y1059642D01*
X403951Y1059670D01*
G02X403545Y1060697I1096J1027D01*
G02X405047Y1062199I1502J0D01*
G02X406034Y1061829I0J-1501D01*
G01X406062Y1061805D01*
X406129Y1061780D01*
X406465D01*
X406532Y1061805D01*
X406560Y1061829D01*
G02X408534I987J-1131D01*
G01X408562Y1061805D01*
X408629Y1061780D01*
X408965D01*
X409032Y1061805D01*
X409060Y1061829D01*
G02X411034I987J-1131D01*
G01X411062Y1061805D01*
X411129Y1061780D01*
G37*
G36*
G01X499259D02*
X499595D01*
X499662Y1061805D01*
X499690Y1061829D01*
G02X501664I987J-1131D01*
G01X501692Y1061805D01*
X501759Y1061780D01*
X502095D01*
X502162Y1061805D01*
X502190Y1061829D01*
G02X503177Y1062199I987J-1131D01*
G02X504679Y1060697I0J-1502D01*
G02X504273Y1059670I-1502J0D01*
G01X504247Y1059642D01*
X504219Y1059573D01*
Y1059221D01*
X504247Y1059152D01*
X504273Y1059124D01*
G02X504679Y1058097I-1096J-1027D01*
G02X503177Y1056595I-1502J0D01*
G02X502190Y1056965I0J1501D01*
G01X502162Y1056989D01*
X502095Y1057014D01*
X501759D01*
X501692Y1056989D01*
X501664Y1056965D01*
G02X499690I-987J1131D01*
G01X499662Y1056989D01*
X499595Y1057014D01*
X499259D01*
X499192Y1056989D01*
X499164Y1056965D01*
G02X497190I-987J1131D01*
G01X497162Y1056989D01*
X497095Y1057014D01*
X496759D01*
X496692Y1056989D01*
X496664Y1056965D01*
G02X494690I-987J1131D01*
G01X494662Y1056989D01*
X494595Y1057014D01*
X494259D01*
X494192Y1056989D01*
X494164Y1056965D01*
G02X493177Y1056595I-987J1131D01*
G02X491675Y1058097I0J1502D01*
G02X492081Y1059124I1502J0D01*
G01X492107Y1059152D01*
X492135Y1059221D01*
Y1059573D01*
X492107Y1059642D01*
X492081Y1059670D01*
G02X491675Y1060697I1096J1027D01*
G02X493177Y1062199I1502J0D01*
G02X494164Y1061829I0J-1501D01*
G01X494192Y1061805D01*
X494259Y1061780D01*
X494595D01*
X494662Y1061805D01*
X494690Y1061829D01*
G02X496664I987J-1131D01*
G01X496692Y1061805D01*
X496759Y1061780D01*
X497095D01*
X497162Y1061805D01*
X497190Y1061829D01*
G02X499164I987J-1131D01*
G01X499192Y1061805D01*
X499259Y1061780D01*
G37*
G36*
G01X497585Y1087879D02*
X497921D01*
X497988Y1087904D01*
X498016Y1087928D01*
G02X499990I987J-1131D01*
G01X500018Y1087904D01*
X500085Y1087879D01*
X500421D01*
X500488Y1087904D01*
X500516Y1087928D01*
G02X501503Y1088298I987J-1131D01*
G02X503005Y1086796I0J-1502D01*
G02X502635Y1085809I-1501J0D01*
G01X502611Y1085781D01*
X502586Y1085714D01*
Y1085378D01*
X502611Y1085311D01*
X502635Y1085283D01*
G02X503005Y1084296I-1131J-987D01*
G02X501503Y1082794I-1502J0D01*
G02X500516Y1083164I0J1501D01*
G01X500488Y1083188D01*
X500421Y1083213D01*
X500085D01*
X500018Y1083188D01*
X499990Y1083164D01*
G02X498016I-987J1131D01*
G01X497988Y1083188D01*
X497921Y1083213D01*
X497585D01*
X497518Y1083188D01*
X497490Y1083164D01*
G02X495516I-987J1131D01*
G01X495488Y1083188D01*
X495421Y1083213D01*
X495085D01*
X495018Y1083188D01*
X494990Y1083164D01*
G02X493016I-987J1131D01*
G01X492988Y1083188D01*
X492921Y1083213D01*
X492585D01*
X492518Y1083188D01*
X492490Y1083164D01*
G02X491503Y1082794I-987J1131D01*
G02X490001Y1084296I0J1502D01*
G02X490371Y1085283I1501J0D01*
G01X490395Y1085311D01*
X490420Y1085378D01*
Y1085714D01*
X490395Y1085781D01*
X490371Y1085809D01*
G02X490001Y1086796I1131J987D01*
G02X491503Y1088298I1502J0D01*
G02X492490Y1087928I0J-1501D01*
G01X492518Y1087904D01*
X492585Y1087879D01*
X492921D01*
X492988Y1087904D01*
X493016Y1087928D01*
G02X494990I987J-1131D01*
G01X495018Y1087904D01*
X495085Y1087879D01*
X495421D01*
X495488Y1087904D01*
X495516Y1087928D01*
G02X497490I987J-1131D01*
G01X497518Y1087904D01*
X497585Y1087879D01*
G37*
G36*
G01X500879Y1091541D02*
Y1091835D01*
G03X500814Y1091982I-200J-1D01*
G02X500329Y1093088I1017J1105D01*
G02X503333I1502J0D01*
G02X502848Y1091982I-1502J-1D01*
G03X502783Y1091835I135J-148D01*
G01Y1091541D01*
G03X502848Y1091394I200J1D01*
G02X503333Y1090288I-1017J-1105D01*
G02X500329I-1502J0D01*
G02X500814Y1091394I1502J1D01*
G03X500879Y1091541I-135J148D01*
G37*
G36*
G01X413498Y1112565D02*
X413162D01*
X413095Y1112540D01*
X413067Y1112516D01*
G02X412080Y1112146I-987J1131D01*
G02Y1115150I0J1502D01*
G02X413067Y1114780I0J-1501D01*
G01X413095Y1114756D01*
X413162Y1114731D01*
X413498D01*
X413565Y1114756D01*
X413593Y1114780D01*
G02X414580Y1115150I987J-1131D01*
G02Y1112146I0J-1502D01*
G02X413593Y1112516I0J1501D01*
G01X413565Y1112540D01*
X413498Y1112565D01*
G37*
G36*
G01X445626D02*
X445290D01*
X445223Y1112540D01*
X445195Y1112516D01*
G02X444208Y1112146I-987J1131D01*
G02Y1115150I0J1502D01*
G02X445195Y1114780I0J-1501D01*
G01X445223Y1114756D01*
X445290Y1114731D01*
X445626D01*
X445693Y1114756D01*
X445721Y1114780D01*
G02X446708Y1115150I987J-1131D01*
G02Y1112146I0J-1502D01*
G02X445721Y1112516I0J1501D01*
G01X445693Y1112540D01*
X445626Y1112565D01*
G37*
G36*
G01X479085D02*
X478749D01*
X478682Y1112540D01*
X478654Y1112516D01*
G02X477667Y1112146I-987J1131D01*
G02Y1115150I0J1502D01*
G02X478654Y1114780I0J-1501D01*
G01X478682Y1114756D01*
X478749Y1114731D01*
X479085D01*
X479152Y1114756D01*
X479180Y1114780D01*
G02X480167Y1115150I987J-1131D01*
G02Y1112146I0J-1502D01*
G02X479180Y1112516I0J1501D01*
G01X479152Y1112540D01*
X479085Y1112565D01*
G37*
G36*
G01X511213D02*
X510877D01*
X510810Y1112540D01*
X510782Y1112516D01*
G02X509795Y1112146I-987J1131D01*
G02Y1115150I0J1502D01*
G02X510782Y1114780I0J-1501D01*
G01X510810Y1114756D01*
X510877Y1114731D01*
X511213D01*
X511280Y1114756D01*
X511308Y1114780D01*
G02X512295Y1115150I987J-1131D01*
G02Y1112146I0J-1502D01*
G02X511308Y1112516I0J1501D01*
G01X511280Y1112540D01*
X511213Y1112565D01*
G37*
G36*
G01X430393Y1116978D02*
Y1117314D01*
X430368Y1117381D01*
X430344Y1117409D01*
G02X429974Y1118396I1131J987D01*
G02X432978I1502J0D01*
G02X432608Y1117409I-1501J0D01*
G01X432584Y1117381D01*
X432559Y1117314D01*
Y1116978D01*
X432584Y1116911D01*
X432608Y1116883D01*
G02X432978Y1115896I-1131J-987D01*
G02X429974I-1502J0D01*
G02X430344Y1116883I1501J0D01*
G01X430368Y1116911D01*
X430393Y1116978D01*
G37*
G36*
G01X462521D02*
Y1117314D01*
X462496Y1117381D01*
X462472Y1117409D01*
G02X462102Y1118396I1131J987D01*
G02X465106I1502J0D01*
G02X464736Y1117409I-1501J0D01*
G01X464712Y1117381D01*
X464687Y1117314D01*
Y1116978D01*
X464712Y1116911D01*
X464736Y1116883D01*
G02X465106Y1115896I-1131J-987D01*
G02X462102I-1502J0D01*
G02X462472Y1116883I1501J0D01*
G01X462496Y1116911D01*
X462521Y1116978D01*
G37*
G36*
G01X495980D02*
Y1117314D01*
X495955Y1117381D01*
X495931Y1117409D01*
G02X495561Y1118396I1131J987D01*
G02X498565I1502J0D01*
G02X498195Y1117409I-1501J0D01*
G01X498171Y1117381D01*
X498146Y1117314D01*
Y1116978D01*
X498171Y1116911D01*
X498195Y1116883D01*
G02X498565Y1115896I-1131J-987D01*
G02X495561I-1502J0D01*
G02X495931Y1116883I1501J0D01*
G01X495955Y1116911D01*
X495980Y1116978D01*
G37*
G36*
G01X528108D02*
Y1117314D01*
X528083Y1117381D01*
X528059Y1117409D01*
G02X527689Y1118396I1131J987D01*
G02X530693I1502J0D01*
G02X530323Y1117409I-1501J0D01*
G01X530299Y1117381D01*
X530274Y1117314D01*
Y1116978D01*
X530299Y1116911D01*
X530323Y1116883D01*
G02X530693Y1115896I-1131J-987D01*
G02X527689I-1502J0D01*
G02X528059Y1116883I1501J0D01*
G01X528083Y1116911D01*
X528108Y1116978D01*
G37*
G36*
G01X378759Y1129676D02*
G03X378370Y1130072I-400J-4D01*
G02X376908Y1131573I40J1501D01*
G02X378410Y1133075I1502J0D01*
G02X379912Y1131589I0J-1502D01*
G03X380301Y1131193I400J4D01*
G02X381763Y1129692I-40J-1501D01*
G02X380261Y1128190I-1502J0D01*
G02X378759Y1129676I0J1502D01*
G37*
G36*
G01X407878Y1173466D02*
Y1173802D01*
X407853Y1173869D01*
X407829Y1173897D01*
G02X407459Y1174884I1131J987D01*
G02X408961Y1176386I1502J0D01*
G02X409948Y1176016I0J-1501D01*
G01X409976Y1175992D01*
X410043Y1175967D01*
X410379D01*
X410446Y1175992D01*
X410474Y1176016D01*
G02X411461Y1176386I987J-1131D01*
G02X412963Y1174884I0J-1502D01*
G02X412593Y1173897I-1501J0D01*
G01X412569Y1173869D01*
X412544Y1173802D01*
Y1173466D01*
X412569Y1173399D01*
X412593Y1173371D01*
G02Y1171397I-1131J-987D01*
G01X412569Y1171369D01*
X412544Y1171302D01*
Y1170966D01*
X412569Y1170899D01*
X412593Y1170871D01*
G02Y1168897I-1131J-987D01*
G01X412569Y1168869D01*
X412544Y1168802D01*
Y1168466D01*
X412569Y1168399D01*
X412593Y1168371D01*
G02Y1166397I-1131J-987D01*
G01X412569Y1166369D01*
X412544Y1166302D01*
Y1165966D01*
X412569Y1165899D01*
X412593Y1165871D01*
G02Y1163897I-1131J-987D01*
G01X412569Y1163869D01*
X412544Y1163802D01*
Y1163466D01*
X412569Y1163399D01*
X412593Y1163371D01*
G02X412963Y1162384I-1131J-987D01*
G02X411461Y1160882I-1502J0D01*
G02X410474Y1161252I0J1501D01*
G01X410446Y1161276D01*
X410379Y1161301D01*
X410043D01*
X409976Y1161276D01*
X409948Y1161252D01*
G02X408961Y1160882I-987J1131D01*
G02X407459Y1162384I0J1502D01*
G02X407829Y1163371I1501J0D01*
G01X407853Y1163399D01*
X407878Y1163466D01*
Y1163802D01*
X407853Y1163869D01*
X407829Y1163897D01*
G02Y1165871I1131J987D01*
G01X407853Y1165899D01*
X407878Y1165966D01*
Y1166302D01*
X407853Y1166369D01*
X407829Y1166397D01*
G02Y1168371I1131J987D01*
G01X407853Y1168399D01*
X407878Y1168466D01*
Y1168802D01*
X407853Y1168869D01*
X407829Y1168897D01*
G02Y1170871I1131J987D01*
G01X407853Y1170899D01*
X407878Y1170966D01*
Y1171302D01*
X407853Y1171369D01*
X407829Y1171397D01*
G02Y1173371I1131J987D01*
G01X407853Y1173399D01*
X407878Y1173466D01*
G37*
G36*
G01X426148D02*
Y1173802D01*
X426123Y1173869D01*
X426099Y1173897D01*
G02X425729Y1174884I1131J987D01*
G02X427231Y1176386I1502J0D01*
G02X428218Y1176016I0J-1501D01*
G01X428246Y1175992D01*
X428313Y1175967D01*
X428649D01*
X428716Y1175992D01*
X428744Y1176016D01*
G02X429731Y1176386I987J-1131D01*
G02X431233Y1174884I0J-1502D01*
G02X430863Y1173897I-1501J0D01*
G01X430839Y1173869D01*
X430814Y1173802D01*
Y1173466D01*
X430839Y1173399D01*
X430863Y1173371D01*
G02Y1171397I-1131J-987D01*
G01X430839Y1171369D01*
X430814Y1171302D01*
Y1170966D01*
X430839Y1170899D01*
X430863Y1170871D01*
G02Y1168897I-1131J-987D01*
G01X430839Y1168869D01*
X430814Y1168802D01*
Y1168466D01*
X430839Y1168399D01*
X430863Y1168371D01*
G02Y1166397I-1131J-987D01*
G01X430839Y1166369D01*
X430814Y1166302D01*
Y1165966D01*
X430839Y1165899D01*
X430863Y1165871D01*
G02Y1163897I-1131J-987D01*
G01X430839Y1163869D01*
X430814Y1163802D01*
Y1163466D01*
X430839Y1163399D01*
X430863Y1163371D01*
G02X431233Y1162384I-1131J-987D01*
G02X429731Y1160882I-1502J0D01*
G02X428744Y1161252I0J1501D01*
G01X428716Y1161276D01*
X428649Y1161301D01*
X428313D01*
X428246Y1161276D01*
X428218Y1161252D01*
G02X427231Y1160882I-987J1131D01*
G02X425729Y1162384I0J1502D01*
G02X426099Y1163371I1501J0D01*
G01X426123Y1163399D01*
X426148Y1163466D01*
Y1163802D01*
X426123Y1163869D01*
X426099Y1163897D01*
G02Y1165871I1131J987D01*
G01X426123Y1165899D01*
X426148Y1165966D01*
Y1166302D01*
X426123Y1166369D01*
X426099Y1166397D01*
G02Y1168371I1131J987D01*
G01X426123Y1168399D01*
X426148Y1168466D01*
Y1168802D01*
X426123Y1168869D01*
X426099Y1168897D01*
G02Y1170871I1131J987D01*
G01X426123Y1170899D01*
X426148Y1170966D01*
Y1171302D01*
X426123Y1171369D01*
X426099Y1171397D01*
G02Y1173371I1131J987D01*
G01X426123Y1173399D01*
X426148Y1173466D01*
G37*
G36*
G01X435706D02*
Y1173802D01*
X435681Y1173869D01*
X435657Y1173897D01*
G02X435287Y1174884I1131J987D01*
G02X436789Y1176386I1502J0D01*
G02X437776Y1176016I0J-1501D01*
G01X437804Y1175992D01*
X437871Y1175967D01*
X438207D01*
X438274Y1175992D01*
X438302Y1176016D01*
G02X439289Y1176386I987J-1131D01*
G02X440791Y1174884I0J-1502D01*
G02X440421Y1173897I-1501J0D01*
G01X440397Y1173869D01*
X440372Y1173802D01*
Y1173466D01*
X440397Y1173399D01*
X440421Y1173371D01*
G02Y1171397I-1131J-987D01*
G01X440397Y1171369D01*
X440372Y1171302D01*
Y1170966D01*
X440397Y1170899D01*
X440421Y1170871D01*
G02Y1168897I-1131J-987D01*
G01X440397Y1168869D01*
X440372Y1168802D01*
Y1168466D01*
X440397Y1168399D01*
X440421Y1168371D01*
G02Y1166397I-1131J-987D01*
G01X440397Y1166369D01*
X440372Y1166302D01*
Y1165966D01*
X440397Y1165899D01*
X440421Y1165871D01*
G02Y1163897I-1131J-987D01*
G01X440397Y1163869D01*
X440372Y1163802D01*
Y1163466D01*
X440397Y1163399D01*
X440421Y1163371D01*
G02X440791Y1162384I-1131J-987D01*
G02X439289Y1160882I-1502J0D01*
G02X438302Y1161252I0J1501D01*
G01X438274Y1161276D01*
X438207Y1161301D01*
X437871D01*
X437804Y1161276D01*
X437776Y1161252D01*
G02X436789Y1160882I-987J1131D01*
G02X435287Y1162384I0J1502D01*
G02X435657Y1163371I1501J0D01*
G01X435681Y1163399D01*
X435706Y1163466D01*
Y1163802D01*
X435681Y1163869D01*
X435657Y1163897D01*
G02Y1165871I1131J987D01*
G01X435681Y1165899D01*
X435706Y1165966D01*
Y1166302D01*
X435681Y1166369D01*
X435657Y1166397D01*
G02Y1168371I1131J987D01*
G01X435681Y1168399D01*
X435706Y1168466D01*
Y1168802D01*
X435681Y1168869D01*
X435657Y1168897D01*
G02Y1170871I1131J987D01*
G01X435681Y1170899D01*
X435706Y1170966D01*
Y1171302D01*
X435681Y1171369D01*
X435657Y1171397D01*
G02Y1173371I1131J987D01*
G01X435681Y1173399D01*
X435706Y1173466D01*
G37*
G36*
G01X453976D02*
Y1173802D01*
X453951Y1173869D01*
X453927Y1173897D01*
G02X453557Y1174884I1131J987D01*
G02X455059Y1176386I1502J0D01*
G02X456046Y1176016I0J-1501D01*
G01X456074Y1175992D01*
X456141Y1175967D01*
X456477D01*
X456544Y1175992D01*
X456572Y1176016D01*
G02X457559Y1176386I987J-1131D01*
G02X459061Y1174884I0J-1502D01*
G02X458691Y1173897I-1501J0D01*
G01X458667Y1173869D01*
X458642Y1173802D01*
Y1173466D01*
X458667Y1173399D01*
X458691Y1173371D01*
G02Y1171397I-1131J-987D01*
G01X458667Y1171369D01*
X458642Y1171302D01*
Y1170966D01*
X458667Y1170899D01*
X458691Y1170871D01*
G02Y1168897I-1131J-987D01*
G01X458667Y1168869D01*
X458642Y1168802D01*
Y1168466D01*
X458667Y1168399D01*
X458691Y1168371D01*
G02Y1166397I-1131J-987D01*
G01X458667Y1166369D01*
X458642Y1166302D01*
Y1165966D01*
X458667Y1165899D01*
X458691Y1165871D01*
G02Y1163897I-1131J-987D01*
G01X458667Y1163869D01*
X458642Y1163802D01*
Y1163466D01*
X458667Y1163399D01*
X458691Y1163371D01*
G02X459061Y1162384I-1131J-987D01*
G02X457559Y1160882I-1502J0D01*
G02X456572Y1161252I0J1501D01*
G01X456544Y1161276D01*
X456477Y1161301D01*
X456141D01*
X456074Y1161276D01*
X456046Y1161252D01*
G02X455059Y1160882I-987J1131D01*
G02X453557Y1162384I0J1502D01*
G02X453927Y1163371I1501J0D01*
G01X453951Y1163399D01*
X453976Y1163466D01*
Y1163802D01*
X453951Y1163869D01*
X453927Y1163897D01*
G02Y1165871I1131J987D01*
G01X453951Y1165899D01*
X453976Y1165966D01*
Y1166302D01*
X453951Y1166369D01*
X453927Y1166397D01*
G02Y1168371I1131J987D01*
G01X453951Y1168399D01*
X453976Y1168466D01*
Y1168802D01*
X453951Y1168869D01*
X453927Y1168897D01*
G02Y1170871I1131J987D01*
G01X453951Y1170899D01*
X453976Y1170966D01*
Y1171302D01*
X453951Y1171369D01*
X453927Y1171397D01*
G02Y1173371I1131J987D01*
G01X453951Y1173399D01*
X453976Y1173466D01*
G37*
G36*
G01X473465D02*
Y1173802D01*
X473440Y1173869D01*
X473416Y1173897D01*
G02X473046Y1174884I1131J987D01*
G02X474548Y1176386I1502J0D01*
G02X475535Y1176016I0J-1501D01*
G01X475563Y1175992D01*
X475630Y1175967D01*
X475966D01*
X476033Y1175992D01*
X476061Y1176016D01*
G02X477048Y1176386I987J-1131D01*
G02X478550Y1174884I0J-1502D01*
G02X478180Y1173897I-1501J0D01*
G01X478156Y1173869D01*
X478131Y1173802D01*
Y1173466D01*
X478156Y1173399D01*
X478180Y1173371D01*
G02Y1171397I-1131J-987D01*
G01X478156Y1171369D01*
X478131Y1171302D01*
Y1170966D01*
X478156Y1170899D01*
X478180Y1170871D01*
G02Y1168897I-1131J-987D01*
G01X478156Y1168869D01*
X478131Y1168802D01*
Y1168466D01*
X478156Y1168399D01*
X478180Y1168371D01*
G02Y1166397I-1131J-987D01*
G01X478156Y1166369D01*
X478131Y1166302D01*
Y1165966D01*
X478156Y1165899D01*
X478180Y1165871D01*
G02Y1163897I-1131J-987D01*
G01X478156Y1163869D01*
X478131Y1163802D01*
Y1163466D01*
X478156Y1163399D01*
X478180Y1163371D01*
G02X478550Y1162384I-1131J-987D01*
G02X477048Y1160882I-1502J0D01*
G02X476061Y1161252I0J1501D01*
G01X476033Y1161276D01*
X475966Y1161301D01*
X475630D01*
X475563Y1161276D01*
X475535Y1161252D01*
G02X474548Y1160882I-987J1131D01*
G02X473046Y1162384I0J1502D01*
G02X473416Y1163371I1501J0D01*
G01X473440Y1163399D01*
X473465Y1163466D01*
Y1163802D01*
X473440Y1163869D01*
X473416Y1163897D01*
G02Y1165871I1131J987D01*
G01X473440Y1165899D01*
X473465Y1165966D01*
Y1166302D01*
X473440Y1166369D01*
X473416Y1166397D01*
G02Y1168371I1131J987D01*
G01X473440Y1168399D01*
X473465Y1168466D01*
Y1168802D01*
X473440Y1168869D01*
X473416Y1168897D01*
G02Y1170871I1131J987D01*
G01X473440Y1170899D01*
X473465Y1170966D01*
Y1171302D01*
X473440Y1171369D01*
X473416Y1171397D01*
G02Y1173371I1131J987D01*
G01X473440Y1173399D01*
X473465Y1173466D01*
G37*
G36*
G01X491735D02*
Y1173802D01*
X491710Y1173869D01*
X491686Y1173897D01*
G02X491316Y1174884I1131J987D01*
G02X492818Y1176386I1502J0D01*
G02X493805Y1176016I0J-1501D01*
G01X493833Y1175992D01*
X493900Y1175967D01*
X494236D01*
X494303Y1175992D01*
X494331Y1176016D01*
G02X495318Y1176386I987J-1131D01*
G02X496820Y1174884I0J-1502D01*
G02X496450Y1173897I-1501J0D01*
G01X496426Y1173869D01*
X496401Y1173802D01*
Y1173466D01*
X496426Y1173399D01*
X496450Y1173371D01*
G02Y1171397I-1131J-987D01*
G01X496426Y1171369D01*
X496401Y1171302D01*
Y1170966D01*
X496426Y1170899D01*
X496450Y1170871D01*
G02Y1168897I-1131J-987D01*
G01X496426Y1168869D01*
X496401Y1168802D01*
Y1168466D01*
X496426Y1168399D01*
X496450Y1168371D01*
G02Y1166397I-1131J-987D01*
G01X496426Y1166369D01*
X496401Y1166302D01*
Y1165966D01*
X496426Y1165899D01*
X496450Y1165871D01*
G02Y1163897I-1131J-987D01*
G01X496426Y1163869D01*
X496401Y1163802D01*
Y1163466D01*
X496426Y1163399D01*
X496450Y1163371D01*
G02X496820Y1162384I-1131J-987D01*
G02X495318Y1160882I-1502J0D01*
G02X494331Y1161252I0J1501D01*
G01X494303Y1161276D01*
X494236Y1161301D01*
X493900D01*
X493833Y1161276D01*
X493805Y1161252D01*
G02X492818Y1160882I-987J1131D01*
G02X491316Y1162384I0J1502D01*
G02X491686Y1163371I1501J0D01*
G01X491710Y1163399D01*
X491735Y1163466D01*
Y1163802D01*
X491710Y1163869D01*
X491686Y1163897D01*
G02Y1165871I1131J987D01*
G01X491710Y1165899D01*
X491735Y1165966D01*
Y1166302D01*
X491710Y1166369D01*
X491686Y1166397D01*
G02Y1168371I1131J987D01*
G01X491710Y1168399D01*
X491735Y1168466D01*
Y1168802D01*
X491710Y1168869D01*
X491686Y1168897D01*
G02Y1170871I1131J987D01*
G01X491710Y1170899D01*
X491735Y1170966D01*
Y1171302D01*
X491710Y1171369D01*
X491686Y1171397D01*
G02Y1173371I1131J987D01*
G01X491710Y1173399D01*
X491735Y1173466D01*
G37*
G36*
G01X501293D02*
Y1173802D01*
X501268Y1173869D01*
X501244Y1173897D01*
G02X500874Y1174884I1131J987D01*
G02X502376Y1176386I1502J0D01*
G02X503363Y1176016I0J-1501D01*
G01X503391Y1175992D01*
X503458Y1175967D01*
X503794D01*
X503861Y1175992D01*
X503889Y1176016D01*
G02X504876Y1176386I987J-1131D01*
G02X506378Y1174884I0J-1502D01*
G02X506008Y1173897I-1501J0D01*
G01X505984Y1173869D01*
X505959Y1173802D01*
Y1173466D01*
X505984Y1173399D01*
X506008Y1173371D01*
G02Y1171397I-1131J-987D01*
G01X505984Y1171369D01*
X505959Y1171302D01*
Y1170966D01*
X505984Y1170899D01*
X506008Y1170871D01*
G02Y1168897I-1131J-987D01*
G01X505984Y1168869D01*
X505959Y1168802D01*
Y1168466D01*
X505984Y1168399D01*
X506008Y1168371D01*
G02Y1166397I-1131J-987D01*
G01X505984Y1166369D01*
X505959Y1166302D01*
Y1165966D01*
X505984Y1165899D01*
X506008Y1165871D01*
G02Y1163897I-1131J-987D01*
G01X505984Y1163869D01*
X505959Y1163802D01*
Y1163466D01*
X505984Y1163399D01*
X506008Y1163371D01*
G02X506378Y1162384I-1131J-987D01*
G02X504876Y1160882I-1502J0D01*
G02X503889Y1161252I0J1501D01*
G01X503861Y1161276D01*
X503794Y1161301D01*
X503458D01*
X503391Y1161276D01*
X503363Y1161252D01*
G02X502376Y1160882I-987J1131D01*
G02X500874Y1162384I0J1502D01*
G02X501244Y1163371I1501J0D01*
G01X501268Y1163399D01*
X501293Y1163466D01*
Y1163802D01*
X501268Y1163869D01*
X501244Y1163897D01*
G02Y1165871I1131J987D01*
G01X501268Y1165899D01*
X501293Y1165966D01*
Y1166302D01*
X501268Y1166369D01*
X501244Y1166397D01*
G02Y1168371I1131J987D01*
G01X501268Y1168399D01*
X501293Y1168466D01*
Y1168802D01*
X501268Y1168869D01*
X501244Y1168897D01*
G02Y1170871I1131J987D01*
G01X501268Y1170899D01*
X501293Y1170966D01*
Y1171302D01*
X501268Y1171369D01*
X501244Y1171397D01*
G02Y1173371I1131J987D01*
G01X501268Y1173399D01*
X501293Y1173466D01*
G37*
G36*
G01X519563D02*
Y1173802D01*
X519538Y1173869D01*
X519514Y1173897D01*
G02X519144Y1174884I1131J987D01*
G02X520646Y1176386I1502J0D01*
G02X521633Y1176016I0J-1501D01*
G01X521661Y1175992D01*
X521728Y1175967D01*
X522064D01*
X522131Y1175992D01*
X522159Y1176016D01*
G02X523146Y1176386I987J-1131D01*
G02X524648Y1174884I0J-1502D01*
G02X524278Y1173897I-1501J0D01*
G01X524254Y1173869D01*
X524229Y1173802D01*
Y1173466D01*
X524254Y1173399D01*
X524278Y1173371D01*
G02Y1171397I-1131J-987D01*
G01X524254Y1171369D01*
X524229Y1171302D01*
Y1170966D01*
X524254Y1170899D01*
X524278Y1170871D01*
G02Y1168897I-1131J-987D01*
G01X524254Y1168869D01*
X524229Y1168802D01*
Y1168466D01*
X524254Y1168399D01*
X524278Y1168371D01*
G02Y1166397I-1131J-987D01*
G01X524254Y1166369D01*
X524229Y1166302D01*
Y1165966D01*
X524254Y1165899D01*
X524278Y1165871D01*
G02Y1163897I-1131J-987D01*
G01X524254Y1163869D01*
X524229Y1163802D01*
Y1163466D01*
X524254Y1163399D01*
X524278Y1163371D01*
G02X524648Y1162384I-1131J-987D01*
G02X523146Y1160882I-1502J0D01*
G02X522159Y1161252I0J1501D01*
G01X522131Y1161276D01*
X522064Y1161301D01*
X521728D01*
X521661Y1161276D01*
X521633Y1161252D01*
G02X520646Y1160882I-987J1131D01*
G02X519144Y1162384I0J1502D01*
G02X519514Y1163371I1501J0D01*
G01X519538Y1163399D01*
X519563Y1163466D01*
Y1163802D01*
X519538Y1163869D01*
X519514Y1163897D01*
G02Y1165871I1131J987D01*
G01X519538Y1165899D01*
X519563Y1165966D01*
Y1166302D01*
X519538Y1166369D01*
X519514Y1166397D01*
G02Y1168371I1131J987D01*
G01X519538Y1168399D01*
X519563Y1168466D01*
Y1168802D01*
X519538Y1168869D01*
X519514Y1168897D01*
G02Y1170871I1131J987D01*
G01X519538Y1170899D01*
X519563Y1170966D01*
Y1171302D01*
X519538Y1171369D01*
X519514Y1171397D01*
G02Y1173371I1131J987D01*
G01X519538Y1173399D01*
X519563Y1173466D01*
G37*
G36*
G01X405236Y1185291D02*
Y1185627D01*
X405211Y1185694D01*
X405187Y1185722D01*
G02X404817Y1186709I1131J987D01*
G02X407821I1502J0D01*
G02X407451Y1185722I-1501J0D01*
G01X407427Y1185694D01*
X407402Y1185627D01*
Y1185291D01*
X407427Y1185224D01*
X407451Y1185196D01*
G02Y1183222I-1131J-987D01*
G01X407427Y1183194D01*
X407402Y1183127D01*
Y1182791D01*
X407427Y1182724D01*
X407451Y1182696D01*
G02Y1180722I-1131J-987D01*
G01X407427Y1180694D01*
X407402Y1180627D01*
Y1180291D01*
X407427Y1180224D01*
X407451Y1180196D01*
G02X407821Y1179209I-1131J-987D01*
G02X404817I-1502J0D01*
G02X405187Y1180196I1501J0D01*
G01X405211Y1180224D01*
X405236Y1180291D01*
Y1180627D01*
X405211Y1180694D01*
X405187Y1180722D01*
G02Y1182696I1131J987D01*
G01X405211Y1182724D01*
X405236Y1182791D01*
Y1183127D01*
X405211Y1183194D01*
X405187Y1183222D01*
G02Y1185196I1131J987D01*
G01X405211Y1185224D01*
X405236Y1185291D01*
G37*
G36*
G01X432166D02*
Y1185627D01*
X432141Y1185694D01*
X432117Y1185722D01*
G02X431747Y1186709I1131J987D01*
G02X434751I1502J0D01*
G02X434381Y1185722I-1501J0D01*
G01X434357Y1185694D01*
X434332Y1185627D01*
Y1185291D01*
X434357Y1185224D01*
X434381Y1185196D01*
G02Y1183222I-1131J-987D01*
G01X434357Y1183194D01*
X434332Y1183127D01*
Y1182791D01*
X434357Y1182724D01*
X434381Y1182696D01*
G02Y1180722I-1131J-987D01*
G01X434357Y1180694D01*
X434332Y1180627D01*
Y1180291D01*
X434357Y1180224D01*
X434381Y1180196D01*
G02X434751Y1179209I-1131J-987D01*
G02X431747I-1502J0D01*
G02X432117Y1180196I1501J0D01*
G01X432141Y1180224D01*
X432166Y1180291D01*
Y1180627D01*
X432141Y1180694D01*
X432117Y1180722D01*
G02Y1182696I1131J987D01*
G01X432141Y1182724D01*
X432166Y1182791D01*
Y1183127D01*
X432141Y1183194D01*
X432117Y1183222D01*
G02Y1185196I1131J987D01*
G01X432141Y1185224D01*
X432166Y1185291D01*
G37*
G36*
G01X478438D02*
Y1185627D01*
X478413Y1185694D01*
X478389Y1185722D01*
G02X478019Y1186709I1131J987D01*
G02X481023I1502J0D01*
G02X480653Y1185722I-1501J0D01*
G01X480629Y1185694D01*
X480604Y1185627D01*
Y1185291D01*
X480629Y1185224D01*
X480653Y1185196D01*
G02Y1183222I-1131J-987D01*
G01X480629Y1183194D01*
X480604Y1183127D01*
Y1182791D01*
X480629Y1182724D01*
X480653Y1182696D01*
G02Y1180722I-1131J-987D01*
G01X480629Y1180694D01*
X480604Y1180627D01*
Y1180291D01*
X480629Y1180224D01*
X480653Y1180196D01*
G02X481023Y1179209I-1131J-987D01*
G02X478019I-1502J0D01*
G02X478389Y1180196I1501J0D01*
G01X478413Y1180224D01*
X478438Y1180291D01*
Y1180627D01*
X478413Y1180694D01*
X478389Y1180722D01*
G02Y1182696I1131J987D01*
G01X478413Y1182724D01*
X478438Y1182791D01*
Y1183127D01*
X478413Y1183194D01*
X478389Y1183222D01*
G02Y1185196I1131J987D01*
G01X478413Y1185224D01*
X478438Y1185291D01*
G37*
G36*
G01X505368D02*
Y1185627D01*
X505343Y1185694D01*
X505319Y1185722D01*
G02X504949Y1186709I1131J987D01*
G02X507953I1502J0D01*
G02X507583Y1185722I-1501J0D01*
G01X507559Y1185694D01*
X507534Y1185627D01*
Y1185291D01*
X507559Y1185224D01*
X507583Y1185196D01*
G02Y1183222I-1131J-987D01*
G01X507559Y1183194D01*
X507534Y1183127D01*
Y1182791D01*
X507559Y1182724D01*
X507583Y1182696D01*
G02Y1180722I-1131J-987D01*
G01X507559Y1180694D01*
X507534Y1180627D01*
Y1180291D01*
X507559Y1180224D01*
X507583Y1180196D01*
G02X507953Y1179209I-1131J-987D01*
G02X504949I-1502J0D01*
G02X505319Y1180196I1501J0D01*
G01X505343Y1180224D01*
X505368Y1180291D01*
Y1180627D01*
X505343Y1180694D01*
X505319Y1180722D01*
G02Y1182696I1131J987D01*
G01X505343Y1182724D01*
X505368Y1182791D01*
Y1183127D01*
X505343Y1183194D01*
X505319Y1183222D01*
G02Y1185196I1131J987D01*
G01X505343Y1185224D01*
X505368Y1185291D01*
G37*
G36*
G01X419536Y1185503D02*
Y1185839D01*
X419511Y1185906D01*
X419487Y1185934D01*
G02X419117Y1186921I1131J987D01*
G02X422121I1502J0D01*
G02X421751Y1185934I-1501J0D01*
G01X421727Y1185906D01*
X421702Y1185839D01*
Y1185503D01*
X421727Y1185436D01*
X421751Y1185408D01*
G02Y1183434I-1131J-987D01*
G01X421727Y1183406D01*
X421702Y1183339D01*
Y1183003D01*
X421727Y1182936D01*
X421751Y1182908D01*
G02Y1180934I-1131J-987D01*
G01X421727Y1180906D01*
X421702Y1180839D01*
Y1180503D01*
X421727Y1180436D01*
X421751Y1180408D01*
G02X422121Y1179421I-1131J-987D01*
G02X419117I-1502J0D01*
G02X419487Y1180408I1501J0D01*
G01X419511Y1180436D01*
X419536Y1180503D01*
Y1180839D01*
X419511Y1180906D01*
X419487Y1180934D01*
G02Y1182908I1131J987D01*
G01X419511Y1182936D01*
X419536Y1183003D01*
Y1183339D01*
X419511Y1183406D01*
X419487Y1183434D01*
G02Y1185408I1131J987D01*
G01X419511Y1185436D01*
X419536Y1185503D01*
G37*
G36*
G01X446466D02*
Y1185839D01*
X446441Y1185906D01*
X446417Y1185934D01*
G02X446047Y1186921I1131J987D01*
G02X449051I1502J0D01*
G02X448681Y1185934I-1501J0D01*
G01X448657Y1185906D01*
X448632Y1185839D01*
Y1185503D01*
X448657Y1185436D01*
X448681Y1185408D01*
G02Y1183434I-1131J-987D01*
G01X448657Y1183406D01*
X448632Y1183339D01*
Y1183003D01*
X448657Y1182936D01*
X448681Y1182908D01*
G02Y1180934I-1131J-987D01*
G01X448657Y1180906D01*
X448632Y1180839D01*
Y1180503D01*
X448657Y1180436D01*
X448681Y1180408D01*
G02X449051Y1179421I-1131J-987D01*
G02X446047I-1502J0D01*
G02X446417Y1180408I1501J0D01*
G01X446441Y1180436D01*
X446466Y1180503D01*
Y1180839D01*
X446441Y1180906D01*
X446417Y1180934D01*
G02Y1182908I1131J987D01*
G01X446441Y1182936D01*
X446466Y1183003D01*
Y1183339D01*
X446441Y1183406D01*
X446417Y1183434D01*
G02Y1185408I1131J987D01*
G01X446441Y1185436D01*
X446466Y1185503D01*
G37*
G36*
G01X492738D02*
Y1185839D01*
X492713Y1185906D01*
X492689Y1185934D01*
G02X492319Y1186921I1131J987D01*
G02X495323I1502J0D01*
G02X494953Y1185934I-1501J0D01*
G01X494929Y1185906D01*
X494904Y1185839D01*
Y1185503D01*
X494929Y1185436D01*
X494953Y1185408D01*
G02Y1183434I-1131J-987D01*
G01X494929Y1183406D01*
X494904Y1183339D01*
Y1183003D01*
X494929Y1182936D01*
X494953Y1182908D01*
G02Y1180934I-1131J-987D01*
G01X494929Y1180906D01*
X494904Y1180839D01*
Y1180503D01*
X494929Y1180436D01*
X494953Y1180408D01*
G02X495323Y1179421I-1131J-987D01*
G02X492319I-1502J0D01*
G02X492689Y1180408I1501J0D01*
G01X492713Y1180436D01*
X492738Y1180503D01*
Y1180839D01*
X492713Y1180906D01*
X492689Y1180934D01*
G02Y1182908I1131J987D01*
G01X492713Y1182936D01*
X492738Y1183003D01*
Y1183339D01*
X492713Y1183406D01*
X492689Y1183434D01*
G02Y1185408I1131J987D01*
G01X492713Y1185436D01*
X492738Y1185503D01*
G37*
G36*
G01X519668D02*
Y1185839D01*
X519643Y1185906D01*
X519619Y1185934D01*
G02X519249Y1186921I1131J987D01*
G02X522253I1502J0D01*
G02X521883Y1185934I-1501J0D01*
G01X521859Y1185906D01*
X521834Y1185839D01*
Y1185503D01*
X521859Y1185436D01*
X521883Y1185408D01*
G02Y1183434I-1131J-987D01*
G01X521859Y1183406D01*
X521834Y1183339D01*
Y1183003D01*
X521859Y1182936D01*
X521883Y1182908D01*
G02Y1180934I-1131J-987D01*
G01X521859Y1180906D01*
X521834Y1180839D01*
Y1180503D01*
X521859Y1180436D01*
X521883Y1180408D01*
G02X522253Y1179421I-1131J-987D01*
G02X519249I-1502J0D01*
G02X519619Y1180408I1501J0D01*
G01X519643Y1180436D01*
X519668Y1180503D01*
Y1180839D01*
X519643Y1180906D01*
X519619Y1180934D01*
G02Y1182908I1131J987D01*
G01X519643Y1182936D01*
X519668Y1183003D01*
Y1183339D01*
X519643Y1183406D01*
X519619Y1183434D01*
G02Y1185408I1131J987D01*
G01X519643Y1185436D01*
X519668Y1185503D01*
G37*
G36*
G01X459007Y1017640D02*
X458970Y1017669D01*
G02X458383Y1018860I915J1191D01*
G02X461387I1502J0D01*
G02X461380Y1018720I-1502J5D01*
G01X461376Y1018672D01*
X461411Y1018584D01*
X461725Y1018306D01*
X461817Y1018282D01*
X461864Y1018292D01*
G02X462185Y1018327I322J-1467D01*
G02Y1015323I0J-1502D01*
G02X461710Y1015400I0J1502D01*
G01X461675Y1015412D01*
X461602Y1015409D01*
X461289Y1015274D01*
X461237Y1015223D01*
X461221Y1015190D01*
G02X459860Y1014323I-1361J635D01*
G02X458358Y1015825I0J1502D01*
G02X458964Y1017031I1503J0D01*
G01X459003Y1017059D01*
X459045Y1017142D01*
X459048Y1017556D01*
X459007Y1017640D01*
G37*
G36*
G01X431105Y1020336D02*
X431399D01*
G03X431546Y1020401I-1J200D01*
G02X432652Y1020886I1105J-1017D01*
G02X434154Y1019384I0J-1502D01*
G02X433475Y1018128I-1501J0D01*
G01X433433Y1018100D01*
X433385Y1018010D01*
X433388Y1017572D01*
X433438Y1017483D01*
X433481Y1017455D01*
G02X434180Y1016186I-802J-1269D01*
G02X432678Y1014684I-1502J0D01*
G02X431572Y1015169I-1J1502D01*
G03X431425Y1015234I-148J-135D01*
G01X431131D01*
G03X430984Y1015169I1J-200D01*
G02X429878Y1014684I-1105J1017D01*
G02X428772Y1015169I-1J1502D01*
G03X428625Y1015234I-148J-135D01*
G01X428331D01*
G03X428184Y1015169I1J-200D01*
G02X427078Y1014684I-1105J1017D01*
G02X425576Y1016186I0J1502D01*
G02X426255Y1017442I1501J0D01*
G01X426297Y1017470D01*
X426345Y1017560D01*
X426342Y1017998D01*
X426292Y1018087D01*
X426249Y1018115D01*
G02X425550Y1019384I802J1269D01*
G02X427052Y1020886I1502J0D01*
G02X428158Y1020401I1J-1502D01*
G03X428305Y1020336I148J135D01*
G01X428599D01*
G03X428746Y1020401I-1J200D01*
G02X429852Y1020886I1105J-1017D01*
G02X430958Y1020401I1J-1502D01*
G03X431105Y1020336I148J135D01*
G37*
G36*
G01X473357Y1091860D02*
X473323Y1091888D01*
G02X472775Y1093048I954J1160D01*
G02X475779I1502J0D01*
G02X475287Y1091936I-1503J0D01*
G01X475254Y1091906D01*
X475220Y1091828D01*
X475230Y1091436D01*
X475268Y1091359D01*
X475302Y1091331D01*
G02X475689Y1090848I-954J-1161D01*
G01X475713Y1090800D01*
X475800Y1090742D01*
X476249Y1090711D01*
X476343Y1090756D01*
X476374Y1090800D01*
G02X477607Y1091444I1233J-858D01*
G02X479109Y1089942I0J-1502D01*
G02X478655Y1088866I-1502J0D01*
G01X478616Y1088828D01*
X478587Y1088721D01*
X478713Y1088277D01*
X478793Y1088201D01*
X478846Y1088189D01*
G02X480019Y1086724I-328J-1465D01*
G02X479649Y1085737I-1501J0D01*
G01X479625Y1085709D01*
X479600Y1085642D01*
Y1085306D01*
X479625Y1085239D01*
X479649Y1085211D01*
G02Y1083237I-1131J-987D01*
G01X479625Y1083209D01*
X479600Y1083142D01*
Y1082806D01*
X479625Y1082739D01*
X479649Y1082711D01*
G02X480019Y1081724I-1131J-987D01*
G02X478517Y1080222I-1502J0D01*
G02X477530Y1080592I0J1501D01*
G01X477502Y1080616D01*
X477435Y1080641D01*
X477099D01*
X477032Y1080616D01*
X477004Y1080592D01*
G02X476017Y1080222I-987J1131D01*
G02X474515Y1081724I0J1502D01*
G02X474885Y1082711I1501J0D01*
G01X474909Y1082739D01*
X474934Y1082806D01*
Y1083142D01*
X474909Y1083209D01*
X474885Y1083237D01*
G02Y1085211I1131J987D01*
G01X474909Y1085239D01*
X474934Y1085306D01*
Y1085642D01*
X474909Y1085709D01*
X474885Y1085737D01*
G02X474515Y1086724I1131J987D01*
G02X476017Y1088226I1502J0D01*
G02X477004Y1087856I0J-1501D01*
G01X477032Y1087832D01*
X477099Y1087807D01*
X477435D01*
X477502Y1087832D01*
X477530Y1087856D01*
G02X477846Y1088068I988J-1131D01*
G03X477739Y1088446I-90J179D01*
G02X477607Y1088440I-134J1496D01*
G02X476266Y1089265I0J1502D01*
G01X476242Y1089313D01*
X476155Y1089371D01*
X475706Y1089402D01*
X475612Y1089357D01*
X475581Y1089313D01*
G02X474348Y1088669I-1233J858D01*
G02X472846Y1090171I0J1502D01*
G02X473338Y1091283I1503J0D01*
G01X473371Y1091313D01*
X473405Y1091391D01*
X473395Y1091783D01*
X473357Y1091860D01*
G37*
G36*
G01X434758Y1093314D02*
X434767Y1093363D01*
G02X436244Y1094590I1477J-275D01*
G02X437746Y1093088I0J-1502D01*
G02X437261Y1091982I-1502J-1D01*
G03X437196Y1091835I135J-148D01*
G01Y1091541D01*
G03X437261Y1091394I200J1D01*
G02X437746Y1090288I-1017J-1105D01*
G02X436244Y1088786I-1502J0D01*
G02X435405Y1089042I0J1503D01*
G01X435366Y1089069D01*
X435273Y1089081D01*
X434883Y1088949D01*
X434817Y1088883D01*
X434802Y1088838D01*
G02X434510Y1088329I-1424J478D01*
G01X434486Y1088301D01*
X434461Y1088234D01*
Y1087898D01*
X434486Y1087831D01*
X434510Y1087803D01*
G02Y1085829I-1131J-987D01*
G01X434486Y1085801D01*
X434461Y1085734D01*
Y1085398D01*
X434486Y1085331D01*
X434510Y1085303D01*
G02Y1083329I-1131J-987D01*
G01X434486Y1083301D01*
X434461Y1083234D01*
Y1082898D01*
X434486Y1082831D01*
X434510Y1082803D01*
G02X434880Y1081816I-1131J-987D01*
G02X433378Y1080314I-1502J0D01*
G02X432391Y1080684I0J1501D01*
G01X432363Y1080708D01*
X432296Y1080733D01*
X431960D01*
X431893Y1080708D01*
X431865Y1080684D01*
G02X430878Y1080314I-987J1131D01*
G02X429376Y1081816I0J1502D01*
G02X429746Y1082803I1501J0D01*
G01X429770Y1082831D01*
X429795Y1082898D01*
Y1083234D01*
X429770Y1083301D01*
X429746Y1083329D01*
G02Y1085303I1131J987D01*
G01X429770Y1085331D01*
X429795Y1085398D01*
Y1085734D01*
X429770Y1085801D01*
X429746Y1085829D01*
G02X429376Y1086816I1131J987D01*
G02X430878Y1088318I1502J0D01*
G02X431926Y1087892I0J-1502D01*
G03X432065Y1087835I140J143D01*
G01X432191D01*
G03X432330Y1087892I-1J200D01*
G02X432359Y1087919I1038J-1086D01*
G01Y1088129D01*
G03X432302Y1088268I-200J-1D01*
G02X431876Y1089316I1076J1048D01*
G02X432246Y1090303I1501J0D01*
G01X432270Y1090331D01*
X432295Y1090398D01*
Y1090734D01*
X432270Y1090801D01*
X432246Y1090829D01*
G02X431876Y1091816I1131J987D01*
G02X433378Y1093318I1502J0D01*
G02X434165Y1093096I1J-1502D01*
G01X434208Y1093069D01*
X434305Y1093063D01*
X434698Y1093237D01*
X434758Y1093314D01*
G37*
G36*
G01X407924Y1092771D02*
G02X407345Y1093956I923J1185D01*
G02X410349I1502J0D01*
G02X409770Y1092771I-1502J0D01*
G03X409693Y1092614I123J-158D01*
G01Y1092298D01*
G03X409770Y1092141I200J1D01*
G02X410349Y1090956I-923J-1185D01*
G02X409689Y1089712I-1502J0D01*
G01X409646Y1089683D01*
X409599Y1089589D01*
X409622Y1089142D01*
X409678Y1089054D01*
X409725Y1089029D01*
G02X410051Y1088792I-712J-1322D01*
G01X410086Y1088759D01*
X410175Y1088732D01*
X410585Y1088800D01*
X410660Y1088855D01*
X410682Y1088897D01*
G02X411225Y1089482I1333J-692D01*
G01X411265Y1089507D01*
X411314Y1089587D01*
X411353Y1089999D01*
X411319Y1090086D01*
X411284Y1090118D01*
G02X410795Y1091227I1013J1109D01*
G02X413799I1502J0D01*
G02X413087Y1089950I-1501J0D01*
G01X413047Y1089925D01*
X412998Y1089845D01*
X412959Y1089433D01*
X412993Y1089346D01*
X413028Y1089314D01*
G02X413200Y1089128I-1013J-1109D01*
G03X413357Y1089051I158J123D01*
G01X413673D01*
G03X413830Y1089128I-1J200D01*
G02X415015Y1089707I1185J-923D01*
G02X416517Y1088205I0J-1502D01*
G02X415938Y1087020I-1502J0D01*
G03X415861Y1086863I123J-158D01*
G01Y1086547D01*
G03X415938Y1086390I200J1D01*
G02X416517Y1085205I-923J-1185D01*
G02X416061Y1084127I-1502J0D01*
G01X416032Y1084099D01*
X416001Y1084026D01*
X415997Y1083661D01*
X416027Y1083587D01*
X416056Y1083559D01*
G02X416491Y1082501I-1067J-1057D01*
G02X414989Y1080999I-1502J0D01*
G02X413804Y1081578I0J1502D01*
G03X413647Y1081655I-158J-123D01*
G01X413331D01*
G03X413174Y1081578I1J-200D01*
G02X410804I-1185J923D01*
G03X410647Y1081655I-158J-123D01*
G01X410331D01*
G03X410174Y1081578I1J-200D01*
G02X408989Y1080999I-1185J923D01*
G02X407487Y1082501I0J1502D01*
G02X407943Y1083579I1502J0D01*
G01X407972Y1083607D01*
X408003Y1083680D01*
X408007Y1084045D01*
X407977Y1084119D01*
X407948Y1084147D01*
G02X407513Y1085205I1067J1057D01*
G02X407883Y1086192I1501J0D01*
G01X407907Y1086220D01*
X407932Y1086287D01*
Y1086623D01*
X407907Y1086690D01*
X407883Y1086718D01*
G02X407513Y1087705I1131J987D01*
G02X408173Y1088949I1502J0D01*
G01X408216Y1088978D01*
X408263Y1089072D01*
X408240Y1089519D01*
X408184Y1089607D01*
X408137Y1089632D01*
G02X407345Y1090956I711J1324D01*
G02X407924Y1092141I1502J0D01*
G03X408001Y1092298I-123J158D01*
G01Y1092614D01*
G03X407924Y1092771I-200J-1D01*
G37*
G36*
G01X423604Y1106328D02*
X423588Y1106372D01*
G02X423493Y1106897I1407J526D01*
G02X426497I1502J0D01*
G02X425095Y1105398I-1502J0D01*
G01X425048Y1105395D01*
X424967Y1105347D01*
X424741Y1104998D01*
X424731Y1104904D01*
X424747Y1104860D01*
G02X424842Y1104335I-1407J-526D01*
G02X424785Y1103925I-1503J0D01*
G01X424772Y1103881D01*
X424788Y1103792D01*
X425022Y1103463D01*
X425101Y1103419D01*
X425147Y1103416D01*
G02X426562Y1101917I-86J-1499D01*
G02X423558I-1502J0D01*
G02X423615Y1102327I1503J0D01*
G01X423628Y1102371D01*
X423612Y1102460D01*
X423378Y1102789D01*
X423299Y1102833D01*
X423253Y1102836D01*
G02X421899Y1103910I86J1499D01*
G01X421887Y1103952D01*
X421832Y1104016D01*
X421485Y1104181D01*
X421401Y1104183D01*
X421361Y1104166D01*
G02X420782Y1104050I-579J1387D01*
G02X419340Y1105133I0J1502D01*
G01X419329Y1105171D01*
X419282Y1105231D01*
X418972Y1105409D01*
X418897Y1105419D01*
X418859Y1105410D01*
G02X418798Y1105396I-366J1457D01*
G01X418761Y1105388D01*
X418698Y1105348D01*
X418495Y1105069D01*
X418476Y1104997D01*
X418481Y1104959D01*
G02X418490Y1104792I-1493J-164D01*
G02X415486I-1502J0D01*
G02X416685Y1106263I1502J0D01*
G01X416722Y1106271D01*
X416785Y1106311D01*
X416988Y1106590D01*
X417007Y1106662D01*
X417002Y1106700D01*
G02X416993Y1106867I1493J164D01*
G02X418495Y1108369I1502J0D01*
G02X419937Y1107286I0J-1502D01*
G01X419948Y1107248D01*
X419995Y1107188D01*
X420305Y1107010D01*
X420380Y1107000D01*
X420418Y1107009D01*
G02X420782Y1107054I365J-1457D01*
G02X422223Y1105977I0J-1503D01*
G01X422235Y1105935D01*
X422290Y1105871D01*
X422637Y1105706D01*
X422721Y1105704D01*
X422761Y1105721D01*
G02X423240Y1105834I580J-1386D01*
G01X423287Y1105837D01*
X423368Y1105885D01*
X423594Y1106234D01*
X423604Y1106328D01*
G37*
G36*
G01X455732D02*
X455716Y1106372D01*
G02X455621Y1106897I1407J526D01*
G02X458625I1502J0D01*
G02X457223Y1105398I-1502J0D01*
G01X457176Y1105395D01*
X457095Y1105347D01*
X456869Y1104998D01*
X456859Y1104904D01*
X456875Y1104860D01*
G02X456970Y1104335I-1407J-526D01*
G02X456913Y1103925I-1503J0D01*
G01X456900Y1103881D01*
X456916Y1103792D01*
X457150Y1103463D01*
X457229Y1103419D01*
X457275Y1103416D01*
G02X458690Y1101917I-86J-1499D01*
G02X455686I-1502J0D01*
G02X455743Y1102327I1503J0D01*
G01X455756Y1102371D01*
X455740Y1102460D01*
X455506Y1102789D01*
X455427Y1102833D01*
X455381Y1102836D01*
G02X454027Y1103910I86J1499D01*
G01X454015Y1103952D01*
X453960Y1104016D01*
X453613Y1104181D01*
X453529Y1104183D01*
X453489Y1104166D01*
G02X452910Y1104050I-579J1387D01*
G02X451468Y1105133I0J1502D01*
G01X451457Y1105171D01*
X451410Y1105231D01*
X451100Y1105409D01*
X451025Y1105419D01*
X450987Y1105410D01*
G02X450926Y1105396I-366J1457D01*
G01X450889Y1105388D01*
X450826Y1105348D01*
X450623Y1105069D01*
X450604Y1104997D01*
X450609Y1104959D01*
G02X450618Y1104792I-1493J-164D01*
G02X447614I-1502J0D01*
G02X448813Y1106263I1502J0D01*
G01X448850Y1106271D01*
X448913Y1106311D01*
X449116Y1106590D01*
X449135Y1106662D01*
X449130Y1106700D01*
G02X449121Y1106867I1493J164D01*
G02X450623Y1108369I1502J0D01*
G02X452065Y1107286I0J-1502D01*
G01X452076Y1107248D01*
X452123Y1107188D01*
X452433Y1107010D01*
X452508Y1107000D01*
X452546Y1107009D01*
G02X452910Y1107054I365J-1457D01*
G02X454351Y1105977I0J-1503D01*
G01X454363Y1105935D01*
X454418Y1105871D01*
X454765Y1105706D01*
X454849Y1105704D01*
X454889Y1105721D01*
G02X455368Y1105834I580J-1386D01*
G01X455415Y1105837D01*
X455496Y1105885D01*
X455722Y1106234D01*
X455732Y1106328D01*
G37*
G36*
G01X489191D02*
X489175Y1106372D01*
G02X489080Y1106897I1407J526D01*
G02X492084I1502J0D01*
G02X490682Y1105398I-1502J0D01*
G01X490635Y1105395D01*
X490554Y1105347D01*
X490328Y1104998D01*
X490318Y1104904D01*
X490334Y1104860D01*
G02X490429Y1104335I-1407J-526D01*
G02X490372Y1103925I-1503J0D01*
G01X490359Y1103881D01*
X490375Y1103792D01*
X490609Y1103463D01*
X490688Y1103419D01*
X490734Y1103416D01*
G02X492149Y1101917I-86J-1499D01*
G02X489145I-1502J0D01*
G02X489202Y1102327I1503J0D01*
G01X489215Y1102371D01*
X489199Y1102460D01*
X488965Y1102789D01*
X488886Y1102833D01*
X488840Y1102836D01*
G02X487486Y1103910I86J1499D01*
G01X487474Y1103952D01*
X487419Y1104016D01*
X487072Y1104181D01*
X486988Y1104183D01*
X486948Y1104166D01*
G02X486369Y1104050I-579J1387D01*
G02X484927Y1105133I0J1502D01*
G01X484916Y1105171D01*
X484869Y1105231D01*
X484559Y1105409D01*
X484484Y1105419D01*
X484446Y1105410D01*
G02X484385Y1105396I-366J1457D01*
G01X484348Y1105388D01*
X484285Y1105348D01*
X484082Y1105069D01*
X484063Y1104997D01*
X484068Y1104959D01*
G02X484077Y1104792I-1493J-164D01*
G02X481073I-1502J0D01*
G02X482272Y1106263I1502J0D01*
G01X482309Y1106271D01*
X482372Y1106311D01*
X482575Y1106590D01*
X482594Y1106662D01*
X482589Y1106700D01*
G02X482580Y1106867I1493J164D01*
G02X484082Y1108369I1502J0D01*
G02X485524Y1107286I0J-1502D01*
G01X485535Y1107248D01*
X485582Y1107188D01*
X485892Y1107010D01*
X485967Y1107000D01*
X486005Y1107009D01*
G02X486369Y1107054I365J-1457D01*
G02X487810Y1105977I0J-1503D01*
G01X487822Y1105935D01*
X487877Y1105871D01*
X488224Y1105706D01*
X488308Y1105704D01*
X488348Y1105721D01*
G02X488827Y1105834I580J-1386D01*
G01X488874Y1105837D01*
X488955Y1105885D01*
X489181Y1106234D01*
X489191Y1106328D01*
G37*
G36*
G01X521319D02*
X521303Y1106372D01*
G02X521208Y1106897I1407J526D01*
G02X524212I1502J0D01*
G02X522810Y1105398I-1502J0D01*
G01X522763Y1105395D01*
X522682Y1105347D01*
X522456Y1104998D01*
X522446Y1104904D01*
X522462Y1104860D01*
G02X522557Y1104335I-1407J-526D01*
G02X522500Y1103925I-1503J0D01*
G01X522487Y1103881D01*
X522503Y1103792D01*
X522737Y1103463D01*
X522816Y1103419D01*
X522862Y1103416D01*
G02X524277Y1101917I-86J-1499D01*
G02X521273I-1502J0D01*
G02X521330Y1102327I1503J0D01*
G01X521343Y1102371D01*
X521327Y1102460D01*
X521093Y1102789D01*
X521014Y1102833D01*
X520968Y1102836D01*
G02X519614Y1103910I86J1499D01*
G01X519602Y1103952D01*
X519547Y1104016D01*
X519200Y1104181D01*
X519116Y1104183D01*
X519076Y1104166D01*
G02X518497Y1104050I-579J1387D01*
G02X517055Y1105133I0J1502D01*
G01X517044Y1105171D01*
X516997Y1105231D01*
X516687Y1105409D01*
X516612Y1105419D01*
X516574Y1105410D01*
G02X516513Y1105396I-366J1457D01*
G01X516476Y1105388D01*
X516413Y1105348D01*
X516210Y1105069D01*
X516191Y1104997D01*
X516196Y1104959D01*
G02X516205Y1104792I-1493J-164D01*
G02X513201I-1502J0D01*
G02X514400Y1106263I1502J0D01*
G01X514437Y1106271D01*
X514500Y1106311D01*
X514703Y1106590D01*
X514722Y1106662D01*
X514717Y1106700D01*
G02X514708Y1106867I1493J164D01*
G02X516210Y1108369I1502J0D01*
G02X517652Y1107286I0J-1502D01*
G01X517663Y1107248D01*
X517710Y1107188D01*
X518020Y1107010D01*
X518095Y1107000D01*
X518133Y1107009D01*
G02X518497Y1107054I365J-1457D01*
G02X519938Y1105977I0J-1503D01*
G01X519950Y1105935D01*
X520005Y1105871D01*
X520352Y1105706D01*
X520436Y1105704D01*
X520476Y1105721D01*
G02X520955Y1105834I580J-1386D01*
G01X521002Y1105837D01*
X521083Y1105885D01*
X521309Y1106234D01*
X521319Y1106328D01*
G37*
G36*
G01X401723Y1112652D02*
G02X401193Y1113797I972J1145D01*
G02X402695Y1115299I1502J0D01*
G02X404151Y1114167I0J-1502D01*
G01X404160Y1114130D01*
X404205Y1114068D01*
X404501Y1113880D01*
X404576Y1113865D01*
X404613Y1113872D01*
G02X404895Y1113899I284J-1475D01*
G02X405698Y1113666I0J-1502D01*
G01X405740Y1113640D01*
X405839Y1113632D01*
X406233Y1113803D01*
X406295Y1113881D01*
X406305Y1113929D01*
G02X407780Y1115150I1475J-280D01*
G02X409282Y1113648I0J-1502D01*
G02X408285Y1112234I-1501J0D01*
G01X408238Y1112217D01*
X408171Y1112144D01*
X408064Y1111726D01*
X408087Y1111630D01*
X408120Y1111592D01*
G02X408497Y1110597I-1125J-995D01*
G02X408050Y1109528I-1502J0D01*
G01X408023Y1109501D01*
X407993Y1109433D01*
X407979Y1109081D01*
X408004Y1109011D01*
X408029Y1108982D01*
G02X408397Y1107997I-1134J-985D01*
G02X406895Y1106495I-1502J0D01*
G02X405442Y1107615I0J1503D01*
G01X405433Y1107650D01*
X405391Y1107710D01*
X405108Y1107898D01*
X405037Y1107914D01*
X405001Y1107909D01*
G02X404795Y1107895I-205J1488D01*
G02X404589Y1107909I-1J1502D01*
G01X404553Y1107914D01*
X404482Y1107898D01*
X404199Y1107710D01*
X404157Y1107650D01*
X404148Y1107615D01*
G02X402695Y1106495I-1453J383D01*
G02X401193Y1107997I0J1502D01*
G02X401723Y1109142I1502J0D01*
G03X401794Y1109295I-129J153D01*
G01Y1109599D01*
G03X401723Y1109752I-200J0D01*
G02Y1112042I972J1145D01*
G03X401794Y1112195I-129J153D01*
G01Y1112499D01*
G03X401723Y1112652I-200J0D01*
G37*
G36*
G01X440330Y1117707D02*
X440301Y1117735D01*
G02X439857Y1118801I1058J1066D01*
G02X442861I1502J0D01*
G02X442417Y1117735I-1502J0D01*
G01X442388Y1117707D01*
X442358Y1117633D01*
Y1117269D01*
X442388Y1117195D01*
X442417Y1117167D01*
G02X442861Y1116101I-1058J-1066D01*
G02X441642Y1114626I-1502J0D01*
G01X441600Y1114618D01*
X441530Y1114569D01*
X441333Y1114236D01*
X441324Y1114151D01*
X441337Y1114110D01*
G02X441410Y1113648I-1429J-463D01*
G02X440413Y1112234I-1501J0D01*
G01X440366Y1112217D01*
X440299Y1112144D01*
X440192Y1111726D01*
X440215Y1111630D01*
X440248Y1111592D01*
G02X440625Y1110597I-1125J-995D01*
G02X440178Y1109528I-1502J0D01*
G01X440151Y1109501D01*
X440121Y1109433D01*
X440107Y1109081D01*
X440132Y1109011D01*
X440157Y1108982D01*
G02X440525Y1107997I-1134J-985D01*
G02X439023Y1106495I-1502J0D01*
G02X437570Y1107615I0J1503D01*
G01X437561Y1107650D01*
X437519Y1107710D01*
X437236Y1107898D01*
X437165Y1107914D01*
X437129Y1107909D01*
G02X436923Y1107895I-205J1488D01*
G02X436717Y1107909I-1J1502D01*
G01X436681Y1107914D01*
X436610Y1107898D01*
X436327Y1107710D01*
X436285Y1107650D01*
X436276Y1107615D01*
G02X434823Y1106495I-1453J383D01*
G02X433321Y1107997I0J1502D01*
G02X433851Y1109142I1502J0D01*
G03X433922Y1109295I-129J153D01*
G01Y1109599D01*
G03X433851Y1109752I-200J0D01*
G02Y1112042I972J1145D01*
G03X433922Y1112195I-129J153D01*
G01Y1112499D01*
G03X433851Y1112652I-200J0D01*
G02X433321Y1113797I972J1145D01*
G02X434823Y1115299I1502J0D01*
G02X436279Y1114167I0J-1502D01*
G01X436288Y1114130D01*
X436333Y1114068D01*
X436629Y1113880D01*
X436704Y1113865D01*
X436741Y1113872D01*
G02X437023Y1113899I284J-1475D01*
G02X437826Y1113666I0J-1502D01*
G01X437868Y1113640D01*
X437967Y1113632D01*
X438361Y1113803D01*
X438423Y1113881D01*
X438433Y1113929D01*
G02X439625Y1115123I1475J-281D01*
G01X439667Y1115131D01*
X439737Y1115180D01*
X439934Y1115513D01*
X439943Y1115598D01*
X439930Y1115639D01*
G02X439857Y1116101I1429J463D01*
G02X440301Y1117167I1502J0D01*
G01X440330Y1117195D01*
X440360Y1117269D01*
Y1117633D01*
X440330Y1117707D01*
G37*
G36*
G01X473789D02*
X473760Y1117735D01*
G02X473316Y1118801I1058J1066D01*
G02X476320I1502J0D01*
G02X475876Y1117735I-1502J0D01*
G01X475847Y1117707D01*
X475817Y1117633D01*
Y1117269D01*
X475847Y1117195D01*
X475876Y1117167D01*
G02X476320Y1116101I-1058J-1066D01*
G02X475101Y1114626I-1502J0D01*
G01X475059Y1114618D01*
X474989Y1114569D01*
X474792Y1114236D01*
X474783Y1114151D01*
X474796Y1114110D01*
G02X474869Y1113648I-1429J-463D01*
G02X473872Y1112234I-1501J0D01*
G01X473825Y1112217D01*
X473758Y1112144D01*
X473651Y1111726D01*
X473674Y1111630D01*
X473707Y1111592D01*
G02X474084Y1110597I-1125J-995D01*
G02X473637Y1109528I-1502J0D01*
G01X473610Y1109501D01*
X473580Y1109433D01*
X473566Y1109081D01*
X473591Y1109011D01*
X473616Y1108982D01*
G02X473984Y1107997I-1134J-985D01*
G02X472482Y1106495I-1502J0D01*
G02X471029Y1107615I0J1503D01*
G01X471020Y1107650D01*
X470978Y1107710D01*
X470695Y1107898D01*
X470624Y1107914D01*
X470588Y1107909D01*
G02X470382Y1107895I-205J1488D01*
G02X470176Y1107909I-1J1502D01*
G01X470140Y1107914D01*
X470069Y1107898D01*
X469786Y1107710D01*
X469744Y1107650D01*
X469735Y1107615D01*
G02X468282Y1106495I-1453J383D01*
G02X466780Y1107997I0J1502D01*
G02X467310Y1109142I1502J0D01*
G03X467381Y1109295I-129J153D01*
G01Y1109599D01*
G03X467310Y1109752I-200J0D01*
G02Y1112042I972J1145D01*
G03X467381Y1112195I-129J153D01*
G01Y1112499D01*
G03X467310Y1112652I-200J0D01*
G02X466780Y1113797I972J1145D01*
G02X468282Y1115299I1502J0D01*
G02X469738Y1114167I0J-1502D01*
G01X469747Y1114130D01*
X469792Y1114068D01*
X470088Y1113880D01*
X470163Y1113865D01*
X470200Y1113872D01*
G02X470482Y1113899I284J-1475D01*
G02X471285Y1113666I0J-1502D01*
G01X471327Y1113640D01*
X471426Y1113632D01*
X471820Y1113803D01*
X471882Y1113881D01*
X471892Y1113929D01*
G02X473084Y1115123I1475J-281D01*
G01X473126Y1115131D01*
X473196Y1115180D01*
X473393Y1115513D01*
X473402Y1115598D01*
X473389Y1115639D01*
G02X473316Y1116101I1429J463D01*
G02X473760Y1117167I1502J0D01*
G01X473789Y1117195D01*
X473819Y1117269D01*
Y1117633D01*
X473789Y1117707D01*
G37*
G36*
G01X505917D02*
X505888Y1117735D01*
G02X505444Y1118801I1058J1066D01*
G02X508448I1502J0D01*
G02X508004Y1117735I-1502J0D01*
G01X507975Y1117707D01*
X507945Y1117633D01*
Y1117269D01*
X507975Y1117195D01*
X508004Y1117167D01*
G02X508448Y1116101I-1058J-1066D01*
G02X507229Y1114626I-1502J0D01*
G01X507187Y1114618D01*
X507117Y1114569D01*
X506920Y1114236D01*
X506911Y1114151D01*
X506924Y1114110D01*
G02X506997Y1113648I-1429J-463D01*
G02X506000Y1112234I-1501J0D01*
G01X505953Y1112217D01*
X505886Y1112144D01*
X505779Y1111726D01*
X505802Y1111630D01*
X505835Y1111592D01*
G02X506212Y1110597I-1125J-995D01*
G02X505765Y1109528I-1502J0D01*
G01X505738Y1109501D01*
X505708Y1109433D01*
X505694Y1109081D01*
X505719Y1109011D01*
X505744Y1108982D01*
G02X506112Y1107997I-1134J-985D01*
G02X504610Y1106495I-1502J0D01*
G02X503157Y1107615I0J1503D01*
G01X503148Y1107650D01*
X503106Y1107710D01*
X502823Y1107898D01*
X502752Y1107914D01*
X502716Y1107909D01*
G02X502510Y1107895I-205J1488D01*
G02X502304Y1107909I-1J1502D01*
G01X502268Y1107914D01*
X502197Y1107898D01*
X501914Y1107710D01*
X501872Y1107650D01*
X501863Y1107615D01*
G02X500410Y1106495I-1453J383D01*
G02X498908Y1107997I0J1502D01*
G02X499438Y1109142I1502J0D01*
G03X499509Y1109295I-129J153D01*
G01Y1109599D01*
G03X499438Y1109752I-200J0D01*
G02Y1112042I972J1145D01*
G03X499509Y1112195I-129J153D01*
G01Y1112499D01*
G03X499438Y1112652I-200J0D01*
G02X498908Y1113797I972J1145D01*
G02X500410Y1115299I1502J0D01*
G02X501866Y1114167I0J-1502D01*
G01X501875Y1114130D01*
X501920Y1114068D01*
X502216Y1113880D01*
X502291Y1113865D01*
X502328Y1113872D01*
G02X502610Y1113899I284J-1475D01*
G02X503413Y1113666I0J-1502D01*
G01X503455Y1113640D01*
X503554Y1113632D01*
X503948Y1113803D01*
X504010Y1113881D01*
X504020Y1113929D01*
G02X505212Y1115123I1475J-281D01*
G01X505254Y1115131D01*
X505324Y1115180D01*
X505521Y1115513D01*
X505530Y1115598D01*
X505517Y1115639D01*
G02X505444Y1116101I1429J463D01*
G02X505888Y1117167I1502J0D01*
G01X505917Y1117195D01*
X505947Y1117269D01*
Y1117633D01*
X505917Y1117707D01*
G37*
G36*
G01X459472Y1197781D02*
X460223Y1198533D01*
G02X461285Y1198972I1061J-1062D01*
G02X462786Y1197471I0J-1501D01*
G02X462347Y1196409I-1501J-1D01*
G01X461550Y1195612D01*
G03Y1195330I141J-141D01*
G01X462347Y1194533D01*
G02X462786Y1193471I-1062J-1061D01*
G02X461285Y1191970I-1501J0D01*
G02X460223Y1192409I-1J1501D01*
G01X459472Y1193161D01*
G03X459330Y1193220I-142J-141D01*
G01X451756D01*
G03X451607Y1193153I0J-200D01*
G01X451379Y1192901D01*
X451353Y1192821D01*
X451358Y1192778D01*
G02X451366Y1192621I-1494J-155D01*
G02X450996Y1191634I-1501J0D01*
G01X450972Y1191606D01*
X450947Y1191539D01*
Y1191203D01*
X450972Y1191136D01*
X450996Y1191108D01*
G02X451366Y1190121I-1131J-987D01*
G02X448362I-1502J0D01*
G02X448732Y1191108I1501J0D01*
G01X448756Y1191136D01*
X448781Y1191203D01*
Y1191539D01*
X448756Y1191606D01*
X448732Y1191634D01*
G02X448362Y1192621I1131J987D01*
G02X448370Y1192778I1502J2D01*
G01X448375Y1192821D01*
X448349Y1192901D01*
X448121Y1193153D01*
G03X447972Y1193220I-149J-133D01*
G01X432826D01*
G03X432677Y1193153I0J-200D01*
G01X432449Y1192901D01*
X432423Y1192821D01*
X432428Y1192778D01*
G02X432436Y1192621I-1494J-155D01*
G02X432066Y1191634I-1501J0D01*
G01X432042Y1191606D01*
X432017Y1191539D01*
Y1191203D01*
X432042Y1191136D01*
X432066Y1191108D01*
G02X432436Y1190121I-1131J-987D01*
G02X429432I-1502J0D01*
G02X429802Y1191108I1501J0D01*
G01X429826Y1191136D01*
X429851Y1191203D01*
Y1191539D01*
X429826Y1191606D01*
X429802Y1191634D01*
G02X429432Y1192621I1131J987D01*
G02X429440Y1192778I1502J2D01*
G01X429445Y1192821D01*
X429419Y1192901D01*
X429191Y1193153D01*
G03X429042Y1193220I-149J-133D01*
G01X424826D01*
G03X424677Y1193153I0J-200D01*
G01X424449Y1192901D01*
X424423Y1192821D01*
X424428Y1192778D01*
G02X424436Y1192621I-1494J-155D01*
G02X424066Y1191634I-1501J0D01*
G01X424042Y1191606D01*
X424017Y1191539D01*
Y1191203D01*
X424042Y1191136D01*
X424066Y1191108D01*
G02X424436Y1190121I-1131J-987D01*
G02X421432I-1502J0D01*
G02X421802Y1191108I1501J0D01*
G01X421826Y1191136D01*
X421851Y1191203D01*
Y1191539D01*
X421826Y1191606D01*
X421802Y1191634D01*
G02X421432Y1192621I1131J987D01*
G02X421440Y1192778I1502J2D01*
G01X421445Y1192821D01*
X421419Y1192901D01*
X421191Y1193153D01*
G03X421042Y1193220I-149J-133D01*
G01X419361D01*
G03X419212Y1193153I0J-200D01*
G01X418984Y1192901D01*
X418958Y1192821D01*
X418963Y1192778D01*
G02X418971Y1192621I-1494J-155D01*
G02X418601Y1191634I-1501J0D01*
G01X418577Y1191606D01*
X418552Y1191539D01*
Y1191203D01*
X418577Y1191136D01*
X418601Y1191108D01*
G02X418971Y1190121I-1131J-987D01*
G02X415967I-1502J0D01*
G02X416337Y1191108I1501J0D01*
G01X416361Y1191136D01*
X416386Y1191203D01*
Y1191539D01*
X416361Y1191606D01*
X416337Y1191634D01*
G02X415967Y1192621I1131J987D01*
G02X415975Y1192778I1502J2D01*
G01X415980Y1192821D01*
X415954Y1192901D01*
X415726Y1193153D01*
G03X415577Y1193220I-149J-133D01*
G01X405896D01*
G03X405747Y1193153I0J-200D01*
G01X405519Y1192901D01*
X405493Y1192821D01*
X405498Y1192778D01*
G02X405506Y1192621I-1494J-155D01*
G02X405136Y1191634I-1501J0D01*
G01X405112Y1191606D01*
X405087Y1191539D01*
Y1191203D01*
X405112Y1191136D01*
X405136Y1191108D01*
G02X405506Y1190121I-1131J-987D01*
G02X402502I-1502J0D01*
G02X402872Y1191108I1501J0D01*
G01X402896Y1191136D01*
X402921Y1191203D01*
Y1191539D01*
X402896Y1191606D01*
X402872Y1191634D01*
G02X402502Y1192621I1131J987D01*
G02X402510Y1192778I1502J2D01*
G01X402515Y1192821D01*
X402489Y1192901D01*
X402261Y1193153D01*
G03X402112Y1193220I-149J-133D01*
G01X398891D01*
G03X398749Y1193161I0J-200D01*
G01X397916Y1192328D01*
G03X397858Y1192186I142J-141D01*
G01Y1168886D01*
G02X397418Y1167824I-1502J0D01*
G01X375718Y1146125D01*
G03X375660Y1145983I142J-141D01*
G01Y1130289D01*
G03X375675Y1130213I200J0D01*
G01X378617Y1123111D01*
G03X378660Y1123046I185J76D01*
G01X397470Y1104236D01*
G03X397612Y1104178I141J142D01*
G01X409400D01*
G02X410462Y1103738I0J-1502D01*
G01X424174Y1090026D01*
G02X424614Y1088964I-1062J-1062D01*
G01Y1057508D01*
G03X424672Y1057366I200J-1D01*
G01X429015Y1053023D01*
G03X429157Y1052964I142J141D01*
G01X477683D01*
G02X478745Y1052525I1J-1501D01*
G01X482947Y1048323D01*
G02X483386Y1047261I-1062J-1061D01*
G01Y1040526D01*
G03X483584Y1040326I200J0D01*
G01X483897Y1040323D01*
G03X484039Y1040379I3J200D01*
G01X484630Y1040955D01*
G02X485678Y1041382I1049J-1075D01*
G02X487180Y1039880I0J-1502D01*
G02X486726Y1038805I-1502J1D01*
G01X486059Y1038155D01*
G03X486055Y1037872I139J-143D01*
G01X486707Y1037204D01*
G02X487134Y1036155I-1075J-1049D01*
G02X485633Y1034654I-1501J0D01*
G02X484559Y1035106I0J1502D01*
G01X483920Y1035760D01*
G03X483779Y1035820I-143J-140D01*
G01X483121Y1035828D01*
X482131D01*
G02X481069Y1036268I0J1502D01*
G01X479323Y1038014D01*
G02X478884Y1039076I1062J1061D01*
G01Y1045934D01*
G03X478825Y1046076I-200J0D01*
G01X476498Y1048403D01*
G03X476356Y1048462I-142J-141D01*
G01X472184D01*
G03X471996Y1048329I1J-200D01*
G01X471848Y1047914D01*
X471881Y1047793D01*
X471931Y1047752D01*
G02X472480Y1046591I-953J-1161D01*
G02X469476I-1502J0D01*
G02X470025Y1047752I1502J0D01*
G01X470075Y1047793D01*
X470108Y1047914D01*
X469960Y1048329D01*
G03X469772Y1048462I-189J-67D01*
G01X427830D01*
G02X426768Y1048901I-1J1501D01*
G01X420550Y1055119D01*
G02X420110Y1056181I1062J1062D01*
G01Y1087637D01*
G03X420052Y1087779I-200J1D01*
G01X408215Y1099616D01*
G03X408073Y1099674I-141J-142D01*
G01X396285D01*
G02X395223Y1100114I0J1502D01*
G01X375025Y1120312D01*
G02X374700Y1120799I1063J1061D01*
G01X374054Y1122359D01*
G03X373919Y1122476I-185J-77D01*
G01X373564Y1122568D01*
X373473Y1122549D01*
X373435Y1122519D01*
G02X372501Y1122193I-934J1175D01*
G02X370999Y1123695I0J1502D01*
G02X372330Y1125187I1502J0D01*
G01X372378Y1125193D01*
X372456Y1125243D01*
X372642Y1125560D01*
G03X372654Y1125738I-173J101D01*
G01X371271Y1129077D01*
G02X371156Y1129652I1387J576D01*
G01Y1147310D01*
G02X371596Y1148372I1502J0D01*
G01X393296Y1170071D01*
G03X393354Y1170213I-142J141D01*
G01Y1193513D01*
G02X393794Y1194575I1502J0D01*
G01X396502Y1197283D01*
G02X397564Y1197722I1061J-1062D01*
G01X459330D01*
G03X459472Y1197781I0J200D01*
G37*
G36*
G01X464723Y1196409D02*
G02X464284Y1197471I1062J1061D01*
G02X465785Y1198972I1501J0D01*
G02X466847Y1198533I1J-1501D01*
G01X467598Y1197781D01*
G03X467740Y1197722I142J141D01*
G01X532381D01*
G02X533443Y1197283I1J-1501D01*
G01X539026Y1191700D01*
G02X539466Y1190638I-1062J-1062D01*
G01Y1112059D01*
G03X539524Y1111917I200J-1D01*
G01X555880Y1095562D01*
G02X556320Y1094500I-1062J-1062D01*
G01Y1077737D01*
G02X555880Y1076675I-1502J0D01*
G01X517773Y1038568D01*
G02X516711Y1038128I-1062J1062D01*
G01X499942D01*
G03X499800Y1038070I-1J-200D01*
G01X486315Y1024584D01*
G02X485253Y1024144I-1062J1062D01*
G01X468636D01*
G02X467574Y1024584I0J1502D01*
G01X465125Y1027033D01*
G02X464686Y1028095I1062J1061D01*
G01Y1030895D01*
G03X464627Y1031037I-200J0D01*
G01X463983Y1031681D01*
G03X463841Y1031740I-142J-141D01*
G01X461380D01*
G03X461238Y1031681I0J-200D01*
G01X460762Y1031204D01*
G02X459700Y1030764I-1062J1062D01*
G02X458198Y1032266I0J1502D01*
G02X458638Y1033328I1502J0D01*
G01X459160Y1033850D01*
G03Y1034132I-141J141D01*
G01X458638Y1034654D01*
G02X458198Y1035716I1062J1062D01*
G02X459700Y1037218I1502J0D01*
G02X460762Y1036778I0J-1502D01*
G01X461238Y1036301D01*
G03X461380Y1036242I142J141D01*
G01X465168D01*
G02X466230Y1035803I1J-1501D01*
G01X468749Y1033284D01*
G02X468815Y1033213I-1066J-1057D01*
G03X469159Y1033396I151J132D01*
G02X469108Y1033783I1451J388D01*
G02X470610Y1032281I1502J0D01*
G02X469481Y1032792I0J1503D01*
G03X469138Y1032608I-150J-132D01*
G02X469188Y1032222I-1451J-384D01*
G01Y1029422D01*
G03X469247Y1029280I200J0D01*
G01X469821Y1028706D01*
G03X469963Y1028648I141J142D01*
G01X469979D01*
G03X470179Y1028848I0J200D01*
G01Y1028886D01*
X470164Y1028922D01*
G02X470056Y1029482I1394J559D01*
G02X471558Y1030984I1502J0D01*
G02X471736Y1030973I-3J-1502D01*
G01X471774Y1030969D01*
X471844Y1030987D01*
X472125Y1031185D01*
X472165Y1031246D01*
X472174Y1031283D01*
G02X473639Y1032454I1465J-331D01*
G02Y1029450I0J-1502D01*
G02X473461Y1029461I3J1502D01*
G01X473423Y1029465D01*
X473353Y1029447D01*
X473072Y1029249D01*
X473032Y1029188D01*
X473023Y1029151D01*
G02X473020Y1029139I-1458J358D01*
G01X473010Y1029093D01*
X473029Y1029006D01*
X473253Y1028723D01*
G03X473410Y1028648I156J125D01*
G01X483926D01*
G03X484068Y1028706I1J200D01*
G01X497553Y1042192D01*
G02X498615Y1042632I1062J-1062D01*
G01X515384D01*
G03X515526Y1042690I1J200D01*
G01X551758Y1078922D01*
G03X551816Y1079064I-142J141D01*
G01Y1093173D01*
G03X551758Y1093315I-200J1D01*
G01X535402Y1109670D01*
G02X534962Y1110732I1062J1062D01*
G01Y1189311D01*
G03X534904Y1189453I-200J1D01*
G01X531196Y1193161D01*
G03X531054Y1193220I-142J-141D01*
G01X524958D01*
G03X524809Y1193153I0J-200D01*
G01X524581Y1192901D01*
X524555Y1192821D01*
X524560Y1192778D01*
G02X524568Y1192621I-1494J-155D01*
G02X524198Y1191634I-1501J0D01*
G01X524174Y1191606D01*
X524149Y1191539D01*
Y1191203D01*
X524174Y1191136D01*
X524198Y1191108D01*
G02X524568Y1190121I-1131J-987D01*
G02X521564I-1502J0D01*
G02X521934Y1191108I1501J0D01*
G01X521958Y1191136D01*
X521983Y1191203D01*
Y1191539D01*
X521958Y1191606D01*
X521934Y1191634D01*
G02X521564Y1192621I1131J987D01*
G02X521572Y1192778I1502J2D01*
G01X521577Y1192821D01*
X521551Y1192901D01*
X521323Y1193153D01*
G03X521174Y1193220I-149J-133D01*
G01X506028D01*
G03X505879Y1193153I0J-200D01*
G01X505651Y1192901D01*
X505625Y1192821D01*
X505630Y1192778D01*
G02X505638Y1192621I-1494J-155D01*
G02X505268Y1191634I-1501J0D01*
G01X505244Y1191606D01*
X505219Y1191539D01*
Y1191203D01*
X505244Y1191136D01*
X505268Y1191108D01*
G02X505638Y1190121I-1131J-987D01*
G02X502634I-1502J0D01*
G02X503004Y1191108I1501J0D01*
G01X503028Y1191136D01*
X503053Y1191203D01*
Y1191539D01*
X503028Y1191606D01*
X503004Y1191634D01*
G02X502634Y1192621I1131J987D01*
G02X502642Y1192778I1502J2D01*
G01X502647Y1192821D01*
X502621Y1192901D01*
X502393Y1193153D01*
G03X502244Y1193220I-149J-133D01*
G01X498028D01*
G03X497879Y1193153I0J-200D01*
G01X497651Y1192901D01*
X497625Y1192821D01*
X497630Y1192778D01*
G02X497638Y1192621I-1494J-155D01*
G02X497268Y1191634I-1501J0D01*
G01X497244Y1191606D01*
X497219Y1191539D01*
Y1191203D01*
X497244Y1191136D01*
X497268Y1191108D01*
G02X497638Y1190121I-1131J-987D01*
G02X494634I-1502J0D01*
G02X495004Y1191108I1501J0D01*
G01X495028Y1191136D01*
X495053Y1191203D01*
Y1191539D01*
X495028Y1191606D01*
X495004Y1191634D01*
G02X494634Y1192621I1131J987D01*
G02X494642Y1192778I1502J2D01*
G01X494647Y1192821D01*
X494621Y1192901D01*
X494393Y1193153D01*
G03X494244Y1193220I-149J-133D01*
G01X492563D01*
G03X492414Y1193153I0J-200D01*
G01X492186Y1192901D01*
X492160Y1192821D01*
X492165Y1192778D01*
G02X492173Y1192621I-1494J-155D01*
G02X491803Y1191634I-1501J0D01*
G01X491779Y1191606D01*
X491754Y1191539D01*
Y1191203D01*
X491779Y1191136D01*
X491803Y1191108D01*
G02X492173Y1190121I-1131J-987D01*
G02X489169I-1502J0D01*
G02X489539Y1191108I1501J0D01*
G01X489563Y1191136D01*
X489588Y1191203D01*
Y1191539D01*
X489563Y1191606D01*
X489539Y1191634D01*
G02X489169Y1192621I1131J987D01*
G02X489177Y1192778I1502J2D01*
G01X489182Y1192821D01*
X489156Y1192901D01*
X488928Y1193153D01*
G03X488779Y1193220I-149J-133D01*
G01X479098D01*
G03X478949Y1193153I0J-200D01*
G01X478721Y1192901D01*
X478695Y1192821D01*
X478700Y1192778D01*
G02X478708Y1192621I-1494J-155D01*
G02X478338Y1191634I-1501J0D01*
G01X478314Y1191606D01*
X478289Y1191539D01*
Y1191203D01*
X478314Y1191136D01*
X478338Y1191108D01*
G02X478708Y1190121I-1131J-987D01*
G02X475704I-1502J0D01*
G02X476074Y1191108I1501J0D01*
G01X476098Y1191136D01*
X476123Y1191203D01*
Y1191539D01*
X476098Y1191606D01*
X476074Y1191634D01*
G02X475704Y1192621I1131J987D01*
G02X475712Y1192778I1502J2D01*
G01X475717Y1192821D01*
X475691Y1192901D01*
X475463Y1193153D01*
G03X475314Y1193220I-149J-133D01*
G01X467740D01*
G03X467598Y1193161I0J-200D01*
G01X466847Y1192409D01*
G02X465785Y1191970I-1061J1062D01*
G02X464284Y1193471I0J1501D01*
G02X464723Y1194533I1501J1D01*
G01X465520Y1195330D01*
G03Y1195612I-141J141D01*
G01X464723Y1196409D01*
G37*
G36*
G01X404759Y1347270D02*
G02Y1350874I0J1802D01*
G01X408159D01*
G02Y1347270I0J-1802D01*
G01X404759D01*
G37*
G36*
G01X402489Y1415472D02*
G02Y1419078I0J1803D01*
G01X405889D01*
G02Y1415472I0J-1803D01*
G01X402489D01*
G37*
G36*
G01X538322Y1358596D02*
G02Y1361602I0J1503D01*
G01X541722D01*
G02Y1358596I0J-1503D01*
G01X538322D01*
G37*
G36*
G01Y1346684D02*
G02Y1349690I0J1503D01*
G01X541722D01*
G02Y1346684I0J-1503D01*
G01X538322D01*
G37*
G36*
G01X526082D02*
G02Y1349690I0J1503D01*
G01X529482D01*
G02Y1346684I0J-1503D01*
G01X526082D01*
G37*
G36*
G01Y1358596D02*
G02Y1361602I0J1503D01*
G01X529482D01*
G02Y1358596I0J-1503D01*
G01X526082D01*
G37*
G36*
G01X513842Y1346684D02*
G02Y1349690I0J1503D01*
G01X517242D01*
G02Y1346684I0J-1503D01*
G01X513842D01*
G37*
G36*
G01Y1358596D02*
G02Y1361602I0J1503D01*
G01X517242D01*
G02Y1358596I0J-1503D01*
G01X513842D01*
G37*
G36*
G01X501602D02*
G02Y1361602I0J1503D01*
G01X505002D01*
G02Y1358596I0J-1503D01*
G01X501602D01*
G37*
G36*
G01Y1346684D02*
G02Y1349690I0J1503D01*
G01X505002D01*
G02Y1346684I0J-1503D01*
G01X501602D01*
G37*
G36*
G01X489362D02*
G02Y1349690I0J1503D01*
G01X492762D01*
G02Y1346684I0J-1503D01*
G01X489362D01*
G37*
G36*
G01Y1358596D02*
G02Y1361602I0J1503D01*
G01X492762D01*
G02Y1358596I0J-1503D01*
G01X489362D01*
G37*
G36*
G01X477122D02*
G02Y1361602I0J1503D01*
G01X480522D01*
G02Y1358596I0J-1503D01*
G01X477122D01*
G37*
G36*
G01Y1346684D02*
G02Y1349690I0J1503D01*
G01X480522D01*
G02Y1346684I0J-1503D01*
G01X477122D01*
G37*
G36*
G01X464882D02*
G02Y1349690I0J1503D01*
G01X468282D01*
G02Y1346684I0J-1503D01*
G01X464882D01*
G37*
G36*
G01Y1358596D02*
G02Y1361602I0J1503D01*
G01X468282D01*
G02Y1358596I0J-1503D01*
G01X464882D01*
G37*
G36*
G01X452642D02*
G02Y1361602I0J1503D01*
G01X456042D01*
G02Y1358596I0J-1503D01*
G01X452642D01*
G37*
G36*
G01Y1346684D02*
G02Y1349690I0J1503D01*
G01X456042D01*
G02Y1346684I0J-1503D01*
G01X452642D01*
G37*
G36*
G01X440402D02*
G02Y1349690I0J1503D01*
G01X443802D01*
G02Y1346684I0J-1503D01*
G01X440402D01*
G37*
G36*
G01Y1358596D02*
G02Y1361602I0J1503D01*
G01X443802D01*
G02Y1358596I0J-1503D01*
G01X440402D01*
G37*
G36*
G01Y1382794D02*
G02Y1385800I0J1503D01*
G01X443802D01*
G02Y1382794I0J-1503D01*
G01X440402D01*
G37*
G36*
G01Y1370882D02*
G02Y1373888I0J1503D01*
G01X443802D01*
G02Y1370882I0J-1503D01*
G01X440402D01*
G37*
G36*
G01X452642D02*
G02Y1373888I0J1503D01*
G01X456042D01*
G02Y1370882I0J-1503D01*
G01X452642D01*
G37*
G36*
G01Y1382794D02*
G02Y1385800I0J1503D01*
G01X456042D01*
G02Y1382794I0J-1503D01*
G01X452642D01*
G37*
G36*
G01X464882Y1370882D02*
G02Y1373888I0J1503D01*
G01X468282D01*
G02Y1370882I0J-1503D01*
G01X464882D01*
G37*
G36*
G01Y1382794D02*
G02Y1385800I0J1503D01*
G01X468282D01*
G02Y1382794I0J-1503D01*
G01X464882D01*
G37*
G36*
G01X477122Y1370882D02*
G02Y1373888I0J1503D01*
G01X480522D01*
G02Y1370882I0J-1503D01*
G01X477122D01*
G37*
G36*
G01Y1382794D02*
G02Y1385800I0J1503D01*
G01X480522D01*
G02Y1382794I0J-1503D01*
G01X477122D01*
G37*
G36*
G01X489362D02*
G02Y1385800I0J1503D01*
G01X492762D01*
G02Y1382794I0J-1503D01*
G01X489362D01*
G37*
G36*
G01Y1370882D02*
G02Y1373888I0J1503D01*
G01X492762D01*
G02Y1370882I0J-1503D01*
G01X489362D01*
G37*
G36*
G01X501602D02*
G02Y1373888I0J1503D01*
G01X505002D01*
G02Y1370882I0J-1503D01*
G01X501602D01*
G37*
G36*
G01Y1382794D02*
G02Y1385800I0J1503D01*
G01X505002D01*
G02Y1382794I0J-1503D01*
G01X501602D01*
G37*
G36*
G01X513842Y1370882D02*
G02Y1373888I0J1503D01*
G01X517242D01*
G02Y1370882I0J-1503D01*
G01X513842D01*
G37*
G36*
G01Y1382794D02*
G02Y1385800I0J1503D01*
G01X517242D01*
G02Y1382794I0J-1503D01*
G01X513842D01*
G37*
G36*
G01X526082D02*
G02Y1385800I0J1503D01*
G01X529482D01*
G02Y1382794I0J-1503D01*
G01X526082D01*
G37*
G36*
G01Y1370882D02*
G02Y1373888I0J1503D01*
G01X529482D01*
G02Y1370882I0J-1503D01*
G01X526082D01*
G37*
G36*
G01X538322D02*
G02Y1373888I0J1503D01*
G01X541722D01*
G02Y1370882I0J-1503D01*
G01X538322D01*
G37*
G36*
G01Y1382794D02*
G02Y1385800I0J1503D01*
G01X541722D01*
G02Y1382794I0J-1503D01*
G01X538322D01*
G37*
G36*
G01X550562Y1395080D02*
G02Y1398086I0J1503D01*
G01X553962D01*
G02Y1395080I0J-1503D01*
G01X550562D01*
G37*
G36*
G01Y1406992D02*
G02Y1409998I0J1503D01*
G01X553962D01*
G02Y1406992I0J-1503D01*
G01X550562D01*
G37*
G36*
G01X538322D02*
G02Y1409998I0J1503D01*
G01X541722D01*
G02Y1406992I0J-1503D01*
G01X538322D01*
G37*
G36*
G01Y1395080D02*
G02Y1398086I0J1503D01*
G01X541722D01*
G02Y1395080I0J-1503D01*
G01X538322D01*
G37*
G36*
G01X526082D02*
G02Y1398086I0J1503D01*
G01X529482D01*
G02Y1395080I0J-1503D01*
G01X526082D01*
G37*
G36*
G01Y1406992D02*
G02Y1409998I0J1503D01*
G01X529482D01*
G02Y1406992I0J-1503D01*
G01X526082D01*
G37*
G36*
G01X513842Y1395080D02*
G02Y1398086I0J1503D01*
G01X517242D01*
G02Y1395080I0J-1503D01*
G01X513842D01*
G37*
G36*
G01Y1406992D02*
G02Y1409998I0J1503D01*
G01X517242D01*
G02Y1406992I0J-1503D01*
G01X513842D01*
G37*
G36*
G01X501602D02*
G02Y1409998I0J1503D01*
G01X505002D01*
G02Y1406992I0J-1503D01*
G01X501602D01*
G37*
G36*
G01Y1395080D02*
G02Y1398086I0J1503D01*
G01X505002D01*
G02Y1395080I0J-1503D01*
G01X501602D01*
G37*
G36*
G01X489362D02*
G02Y1398086I0J1503D01*
G01X492762D01*
G02Y1395080I0J-1503D01*
G01X489362D01*
G37*
G36*
G01X477122D02*
G02Y1398086I0J1503D01*
G01X480522D01*
G02Y1395080I0J-1503D01*
G01X477122D01*
G37*
G36*
G01X464882D02*
G02Y1398086I0J1503D01*
G01X468282D01*
G02Y1395080I0J-1503D01*
G01X464882D01*
G37*
G36*
G01X452642D02*
G02Y1398086I0J1503D01*
G01X456042D01*
G02Y1395080I0J-1503D01*
G01X452642D01*
G37*
G36*
G01X489362Y1406992D02*
G02Y1409998I0J1503D01*
G01X492762D01*
G02Y1406992I0J-1503D01*
G01X489362D01*
G37*
G36*
G01X477122D02*
G02Y1409998I0J1503D01*
G01X480522D01*
G02Y1406992I0J-1503D01*
G01X477122D01*
G37*
G36*
G01X464882D02*
G02Y1409998I0J1503D01*
G01X468282D01*
G02Y1406992I0J-1503D01*
G01X464882D01*
G37*
G36*
G01X452642D02*
G02Y1409998I0J1503D01*
G01X456042D01*
G02Y1406992I0J-1503D01*
G01X452642D01*
G37*
G36*
G01X413753Y1515084D02*
G02Y1518690I0J1803D01*
G01X417153D01*
G02Y1515084I0J-1803D01*
G01X413753D01*
G37*
G36*
G01X417334Y1478902D02*
G02Y1475298I0J-1802D01*
G01X413934D01*
G02Y1478902I0J1802D01*
G01X417334D01*
G37*
G36*
G01X489018Y1301017D02*
X488682D01*
X488615Y1300992D01*
X488587Y1300968D01*
G02X487600Y1300598I-987J1131D01*
G02Y1303602I0J1502D01*
G02X488587Y1303232I0J-1501D01*
G01X488615Y1303208D01*
X488682Y1303183D01*
X489018D01*
X489085Y1303208D01*
X489113Y1303232D01*
G02X490100Y1303602I987J-1131D01*
G02Y1300598I0J-1502D01*
G02X489113Y1300968I0J1501D01*
G01X489085Y1300992D01*
X489018Y1301017D01*
G37*
G36*
G01X430827Y1314224D02*
X430825Y1314572D01*
X430797Y1314641D01*
X430771Y1314669D01*
G02X430365Y1315696I1096J1027D01*
G02X433369I1502J0D01*
G02X432977Y1314685I-1502J1D01*
G01X432952Y1314656D01*
X432925Y1314587D01*
X432927Y1314239D01*
X432955Y1314170D01*
X432981Y1314142D01*
G02X433387Y1313115I-1096J-1027D01*
G02X430383I-1502J0D01*
G02X430775Y1314126I1502J-1D01*
G01X430800Y1314155D01*
X430827Y1314224D01*
G37*
G36*
G01X403129Y1321346D02*
X403395Y1321618D01*
X403424Y1321695D01*
X403421Y1321738D01*
G02X403419Y1321819I1500J78D01*
G02X404921Y1320317I1502J0D01*
G02X404878Y1320318I13J1502D01*
G01X404835Y1320319D01*
X404759Y1320288D01*
X404493Y1320016D01*
X404464Y1319939D01*
X404467Y1319896D01*
G02X404469Y1319815I-1500J-78D01*
G02X402967Y1321317I-1502J0D01*
G02X403010Y1321316I-13J-1502D01*
G01X403053Y1321315D01*
X403129Y1321346D01*
G37*
G36*
G01X417501Y1370532D02*
X417153Y1370530D01*
X417084Y1370502D01*
X417056Y1370476D01*
G02X416029Y1370070I-1027J1096D01*
G02Y1373074I0J1502D01*
G02X417040Y1372682I-1J-1502D01*
G01X417069Y1372657D01*
X417138Y1372630D01*
X417486Y1372632D01*
X417555Y1372660D01*
X417583Y1372686D01*
G02X418610Y1373092I1027J-1096D01*
G02Y1370088I0J-1502D01*
G02X417599Y1370480I1J1502D01*
G01X417570Y1370505D01*
X417501Y1370532D01*
G37*
G36*
G01X420176Y1416438D02*
X420162Y1416775D01*
X420134Y1416841D01*
X420109Y1416868D01*
G02X419698Y1417900I1090J1032D01*
G02X422702I1502J0D01*
G02X422370Y1416958I-1502J0D01*
G01X422347Y1416929D01*
X422324Y1416862D01*
X422338Y1416525D01*
X422366Y1416459D01*
X422391Y1416432D01*
G02X422802Y1415400I-1090J-1032D01*
G02X419798I-1502J0D01*
G02X420130Y1416342I1502J0D01*
G01X420153Y1416371D01*
X420176Y1416438D01*
G37*
G36*
G01X410154Y1461842D02*
Y1462158D01*
G03X410077Y1462315I-200J-1D01*
G02X409498Y1463500I923J1185D01*
G02X412502I1502J0D01*
G02X411923Y1462315I-1502J0D01*
G03X411846Y1462158I123J-158D01*
G01Y1461842D01*
G03X411923Y1461685I200J1D01*
G02Y1459315I-923J-1185D01*
G03X411846Y1459158I123J-158D01*
G01Y1458842D01*
G03X411923Y1458685I200J1D01*
G02Y1456315I-923J-1185D01*
G03X411846Y1456158I123J-158D01*
G01Y1455842D01*
G03X411923Y1455685I200J1D01*
G02X412502Y1454500I-923J-1185D01*
G02X409498I-1502J0D01*
G02X410077Y1455685I1502J0D01*
G03X410154Y1455842I-123J158D01*
G01Y1456158D01*
G03X410077Y1456315I-200J-1D01*
G02Y1458685I923J1185D01*
G03X410154Y1458842I-123J158D01*
G01Y1459158D01*
G03X410077Y1459315I-200J-1D01*
G02Y1461685I923J1185D01*
G03X410154Y1461842I-123J158D01*
G37*
G36*
G01X454726Y1464825D02*
Y1465951D01*
G02X454929Y1466154I203J0D01*
G01X457749D01*
G02X457952Y1465951I0J-203D01*
G01Y1464825D01*
G03X457980Y1464722I200J-1D01*
G02Y1462760I-1640J-981D01*
G03X457952Y1462657I172J-102D01*
G01Y1459706D01*
G03X457980Y1459603I200J-1D01*
G02Y1457641I-1640J-981D01*
G03X457952Y1457538I172J-102D01*
G01Y1456413D01*
G02X457749Y1456210I-203J0D01*
G01X454929D01*
G02X454726Y1456413I0J203D01*
G01Y1457538D01*
G03X454698Y1457641I-200J1D01*
G02Y1459603I1640J981D01*
G03X454726Y1459706I-172J102D01*
G01Y1462657D01*
G03X454698Y1462760I-200J1D01*
G02Y1464722I1640J981D01*
G03X454726Y1464825I-172J102D01*
G37*
G36*
G01X472050D02*
Y1465951D01*
G02X472252Y1466154I202J1D01*
G01X475072D01*
G02X475274Y1465951I-1J-203D01*
G01Y1464825D01*
G03X475303Y1464722I200J1D01*
G02Y1462760I-1640J-981D01*
G03X475274Y1462657I171J-104D01*
G01Y1459706D01*
G03X475303Y1459603I200J1D01*
G02Y1457641I-1640J-981D01*
G03X475274Y1457538I171J-104D01*
G01Y1456413D01*
G02X475072Y1456210I-202J-1D01*
G01X472252D01*
G02X472050Y1456413I1J203D01*
G01Y1457538D01*
G03X472021Y1457641I-200J-1D01*
G02Y1459603I1640J981D01*
G03X472050Y1459706I-171J104D01*
G01Y1462657D01*
G03X472021Y1462760I-200J-1D01*
G02Y1464722I1640J981D01*
G03X472050Y1464825I-171J104D01*
G37*
G36*
G01X489372D02*
Y1465951D01*
G02X489575Y1466154I203J0D01*
G01X492395D01*
G02X492598Y1465951I0J-203D01*
G01Y1464825D01*
G03X492626Y1464722I200J-1D01*
G02Y1462760I-1640J-981D01*
G03X492598Y1462657I172J-102D01*
G01Y1459706D01*
G03X492626Y1459603I200J-1D01*
G02Y1457641I-1640J-981D01*
G03X492598Y1457538I172J-102D01*
G01Y1456413D01*
G02X492395Y1456210I-203J0D01*
G01X489575D01*
G02X489372Y1456413I0J203D01*
G01Y1457538D01*
G03X489344Y1457641I-200J1D01*
G02Y1459603I1640J981D01*
G03X489372Y1459706I-172J102D01*
G01Y1462657D01*
G03X489344Y1462760I-200J1D01*
G02Y1464722I1640J981D01*
G03X489372Y1464825I-172J102D01*
G37*
G36*
G01X506694D02*
Y1465951D01*
G02X506897Y1466154I203J0D01*
G01X509717D01*
G02X509920Y1465951I0J-203D01*
G01Y1464825D01*
G03X509948Y1464722I200J-1D01*
G02Y1462760I-1640J-981D01*
G03X509920Y1462657I172J-102D01*
G01Y1459706D01*
G03X509948Y1459603I200J-1D01*
G02Y1457641I-1640J-981D01*
G03X509920Y1457538I172J-102D01*
G01Y1456413D01*
G02X509717Y1456210I-203J0D01*
G01X506897D01*
G02X506694Y1456413I0J203D01*
G01Y1457538D01*
G03X506666Y1457641I-200J1D01*
G02Y1459603I1640J981D01*
G03X506694Y1459706I-172J102D01*
G01Y1462657D01*
G03X506666Y1462760I-200J1D01*
G02Y1464722I1640J981D01*
G03X506694Y1464825I-172J102D01*
G37*
G36*
G01X463388Y1469155D02*
Y1470281D01*
G02X463590Y1470484I202J1D01*
G01X466410D01*
G02X466612Y1470281I-1J-203D01*
G01Y1469155D01*
G03X466641Y1469052I200J1D01*
G02Y1467090I-1640J-981D01*
G03X466612Y1466987I171J-104D01*
G01Y1464037D01*
G03X466641Y1463934I200J1D01*
G02Y1461972I-1640J-981D01*
G03X466612Y1461869I171J-104D01*
G01Y1460743D01*
G02X466410Y1460540I-202J-1D01*
G01X463590D01*
G02X463388Y1460743I1J203D01*
G01Y1461869D01*
G03X463359Y1461972I-200J-1D01*
G02Y1463934I1640J981D01*
G03X463388Y1464037I-171J104D01*
G01Y1466987D01*
G03X463359Y1467090I-200J-1D01*
G02Y1469052I1640J981D01*
G03X463388Y1469155I-171J104D01*
G37*
G36*
G01X480710D02*
Y1470281D01*
G02X480913Y1470484I203J0D01*
G01X483733D01*
G02X483936Y1470281I0J-203D01*
G01Y1469155D01*
G03X483964Y1469052I200J-1D01*
G02Y1467090I-1640J-981D01*
G03X483936Y1466987I172J-102D01*
G01Y1464037D01*
G03X483964Y1463934I200J-1D01*
G02Y1461972I-1640J-981D01*
G03X483936Y1461869I172J-102D01*
G01Y1460743D01*
G02X483733Y1460540I-203J0D01*
G01X480913D01*
G02X480710Y1460743I0J203D01*
G01Y1461869D01*
G03X480682Y1461972I-200J1D01*
G02Y1463934I1640J981D01*
G03X480710Y1464037I-172J102D01*
G01Y1466987D01*
G03X480682Y1467090I-200J1D01*
G02Y1469052I1640J981D01*
G03X480710Y1469155I-172J102D01*
G37*
G36*
G01X498034D02*
Y1470281D01*
G02X498236Y1470484I202J1D01*
G01X501056D01*
G02X501258Y1470281I-1J-203D01*
G01Y1469155D01*
G03X501287Y1469052I200J1D01*
G02Y1467090I-1640J-981D01*
G03X501258Y1466987I171J-104D01*
G01Y1464037D01*
G03X501287Y1463934I200J1D01*
G02Y1461972I-1640J-981D01*
G03X501258Y1461869I171J-104D01*
G01Y1460743D01*
G02X501056Y1460540I-202J-1D01*
G01X498236D01*
G02X498034Y1460743I1J203D01*
G01Y1461869D01*
G03X498005Y1461972I-200J-1D01*
G02Y1463934I1640J981D01*
G03X498034Y1464037I-171J104D01*
G01Y1466987D01*
G03X498005Y1467090I-200J-1D01*
G02Y1469052I1640J981D01*
G03X498034Y1469155I-171J104D01*
G37*
G36*
G01X515356D02*
Y1470281D01*
G02X515559Y1470484I203J0D01*
G01X518379D01*
G02X518582Y1470281I0J-203D01*
G01Y1469155D01*
G03X518610Y1469052I200J-1D01*
G02Y1467090I-1640J-981D01*
G03X518582Y1466987I172J-102D01*
G01Y1464037D01*
G03X518610Y1463934I200J-1D01*
G02Y1461972I-1640J-981D01*
G03X518582Y1461869I172J-102D01*
G01Y1460743D01*
G02X518379Y1460540I-203J0D01*
G01X515559D01*
G02X515356Y1460743I0J203D01*
G01Y1461869D01*
G03X515328Y1461972I-200J1D01*
G02Y1463934I1640J981D01*
G03X515356Y1464037I-172J102D01*
G01Y1466987D01*
G03X515328Y1467090I-200J1D01*
G02Y1469052I1640J981D01*
G03X515356Y1469155I-172J102D01*
G37*
G36*
G01X454726Y1480179D02*
Y1481305D01*
G02X454929Y1481508I203J0D01*
G01X457749D01*
G02X457952Y1481305I0J-203D01*
G01Y1480179D01*
G03X457980Y1480076I200J-1D01*
G02Y1478114I-1640J-981D01*
G03X457952Y1478011I172J-102D01*
G01Y1475061D01*
G03X457980Y1474958I200J-1D01*
G02Y1472996I-1640J-981D01*
G03X457952Y1472893I172J-102D01*
G01Y1471767D01*
G02X457749Y1471564I-203J0D01*
G01X454929D01*
G02X454726Y1471767I0J203D01*
G01Y1472893D01*
G03X454698Y1472996I-200J1D01*
G02Y1474958I1640J981D01*
G03X454726Y1475061I-172J102D01*
G01Y1478011D01*
G03X454698Y1478114I-200J1D01*
G02Y1480076I1640J981D01*
G03X454726Y1480179I-172J102D01*
G37*
G36*
G01X472050D02*
Y1481305D01*
G02X472252Y1481508I202J1D01*
G01X475072D01*
G02X475274Y1481305I-1J-203D01*
G01Y1480179D01*
G03X475303Y1480076I200J1D01*
G02Y1478114I-1640J-981D01*
G03X475274Y1478011I171J-104D01*
G01Y1475061D01*
G03X475303Y1474958I200J1D01*
G02Y1472996I-1640J-981D01*
G03X475274Y1472893I171J-104D01*
G01Y1471767D01*
G02X475072Y1471564I-202J-1D01*
G01X472252D01*
G02X472050Y1471767I1J203D01*
G01Y1472893D01*
G03X472021Y1472996I-200J-1D01*
G02Y1474958I1640J981D01*
G03X472050Y1475061I-171J104D01*
G01Y1478011D01*
G03X472021Y1478114I-200J-1D01*
G02Y1480076I1640J981D01*
G03X472050Y1480179I-171J104D01*
G37*
G36*
G01X489372D02*
Y1481305D01*
G02X489575Y1481508I203J0D01*
G01X492395D01*
G02X492598Y1481305I0J-203D01*
G01Y1480179D01*
G03X492626Y1480076I200J-1D01*
G02Y1478114I-1640J-981D01*
G03X492598Y1478011I172J-102D01*
G01Y1475061D01*
G03X492626Y1474958I200J-1D01*
G02Y1472996I-1640J-981D01*
G03X492598Y1472893I172J-102D01*
G01Y1471767D01*
G02X492395Y1471564I-203J0D01*
G01X489575D01*
G02X489372Y1471767I0J203D01*
G01Y1472893D01*
G03X489344Y1472996I-200J1D01*
G02Y1474958I1640J981D01*
G03X489372Y1475061I-172J102D01*
G01Y1478011D01*
G03X489344Y1478114I-200J1D01*
G02Y1480076I1640J981D01*
G03X489372Y1480179I-172J102D01*
G37*
G36*
G01X506694D02*
Y1481305D01*
G02X506897Y1481508I203J0D01*
G01X509717D01*
G02X509920Y1481305I0J-203D01*
G01Y1480179D01*
G03X509948Y1480076I200J-1D01*
G02Y1478114I-1640J-981D01*
G03X509920Y1478011I172J-102D01*
G01Y1475061D01*
G03X509948Y1474958I200J-1D01*
G02Y1472996I-1640J-981D01*
G03X509920Y1472893I172J-102D01*
G01Y1471767D01*
G02X509717Y1471564I-203J0D01*
G01X506897D01*
G02X506694Y1471767I0J203D01*
G01Y1472893D01*
G03X506666Y1472996I-200J1D01*
G02Y1474958I1640J981D01*
G03X506694Y1475061I-172J102D01*
G01Y1478011D01*
G03X506666Y1478114I-200J1D01*
G02Y1480076I1640J981D01*
G03X506694Y1480179I-172J102D01*
G37*
G36*
G01X463388Y1484510D02*
Y1485635D01*
G02X463590Y1485838I202J1D01*
G01X466410D01*
G02X466612Y1485635I-1J-203D01*
G01Y1484510D01*
G03X466641Y1484407I200J1D01*
G02Y1482445I-1640J-981D01*
G03X466612Y1482342I171J-104D01*
G01Y1479392D01*
G03X466641Y1479289I200J1D01*
G02Y1477327I-1640J-981D01*
G03X466612Y1477224I171J-104D01*
G01Y1476097D01*
G02X466410Y1475894I-202J-1D01*
G01X463590D01*
G02X463388Y1476097I1J203D01*
G01Y1477224D01*
G03X463359Y1477327I-200J-1D01*
G02Y1479289I1640J981D01*
G03X463388Y1479392I-171J104D01*
G01Y1482342D01*
G03X463359Y1482445I-200J-1D01*
G02Y1484407I1640J981D01*
G03X463388Y1484510I-171J104D01*
G37*
G36*
G01X480710D02*
Y1485635D01*
G02X480913Y1485838I203J0D01*
G01X483733D01*
G02X483936Y1485635I0J-203D01*
G01Y1484510D01*
G03X483964Y1484407I200J-1D01*
G02Y1482445I-1640J-981D01*
G03X483936Y1482342I172J-102D01*
G01Y1479392D01*
G03X483964Y1479289I200J-1D01*
G02Y1477327I-1640J-981D01*
G03X483936Y1477224I172J-102D01*
G01Y1476097D01*
G02X483733Y1475894I-203J0D01*
G01X480913D01*
G02X480710Y1476097I0J203D01*
G01Y1477224D01*
G03X480682Y1477327I-200J1D01*
G02Y1479289I1640J981D01*
G03X480710Y1479392I-172J102D01*
G01Y1482342D01*
G03X480682Y1482445I-200J1D01*
G02Y1484407I1640J981D01*
G03X480710Y1484510I-172J102D01*
G37*
G36*
G01X498034D02*
Y1485635D01*
G02X498236Y1485838I202J1D01*
G01X501056D01*
G02X501258Y1485635I-1J-203D01*
G01Y1484510D01*
G03X501287Y1484407I200J1D01*
G02Y1482445I-1640J-981D01*
G03X501258Y1482342I171J-104D01*
G01Y1479392D01*
G03X501287Y1479289I200J1D01*
G02Y1477327I-1640J-981D01*
G03X501258Y1477224I171J-104D01*
G01Y1476097D01*
G02X501056Y1475894I-202J-1D01*
G01X498236D01*
G02X498034Y1476097I1J203D01*
G01Y1477224D01*
G03X498005Y1477327I-200J-1D01*
G02Y1479289I1640J981D01*
G03X498034Y1479392I-171J104D01*
G01Y1482342D01*
G03X498005Y1482445I-200J-1D01*
G02Y1484407I1640J981D01*
G03X498034Y1484510I-171J104D01*
G37*
G36*
G01X515356D02*
Y1485635D01*
G02X515559Y1485838I203J0D01*
G01X518379D01*
G02X518582Y1485635I0J-203D01*
G01Y1484510D01*
G03X518610Y1484407I200J-1D01*
G02Y1482445I-1640J-981D01*
G03X518582Y1482342I172J-102D01*
G01Y1479392D01*
G03X518610Y1479289I200J-1D01*
G02Y1477327I-1640J-981D01*
G03X518582Y1477224I172J-102D01*
G01Y1476097D01*
G02X518379Y1475894I-203J0D01*
G01X515559D01*
G02X515356Y1476097I0J203D01*
G01Y1477224D01*
G03X515328Y1477327I-200J1D01*
G02Y1479289I1640J981D01*
G03X515356Y1479392I-172J102D01*
G01Y1482342D01*
G03X515328Y1482445I-200J1D01*
G02Y1484407I1640J981D01*
G03X515356Y1484510I-172J102D01*
G37*
G36*
G01X454726Y1495533D02*
Y1496659D01*
G02X454929Y1496862I203J0D01*
G01X457749D01*
G02X457952Y1496659I0J-203D01*
G01Y1495533D01*
G03X457980Y1495430I200J-1D01*
G02Y1493468I-1640J-981D01*
G03X457952Y1493365I172J-102D01*
G01Y1490415D01*
G03X457980Y1490312I200J-1D01*
G02Y1488350I-1640J-981D01*
G03X457952Y1488247I172J-102D01*
G01Y1487121D01*
G02X457749Y1486918I-203J0D01*
G01X454929D01*
G02X454726Y1487121I0J203D01*
G01Y1488247D01*
G03X454698Y1488350I-200J1D01*
G02Y1490312I1640J981D01*
G03X454726Y1490415I-172J102D01*
G01Y1493365D01*
G03X454698Y1493468I-200J1D01*
G02Y1495430I1640J981D01*
G03X454726Y1495533I-172J102D01*
G37*
G36*
G01X472050D02*
Y1496659D01*
G02X472252Y1496862I202J1D01*
G01X475072D01*
G02X475274Y1496659I-1J-203D01*
G01Y1495533D01*
G03X475303Y1495430I200J1D01*
G02Y1493468I-1640J-981D01*
G03X475274Y1493365I171J-104D01*
G01Y1490415D01*
G03X475303Y1490312I200J1D01*
G02Y1488350I-1640J-981D01*
G03X475274Y1488247I171J-104D01*
G01Y1487121D01*
G02X475072Y1486918I-202J-1D01*
G01X472252D01*
G02X472050Y1487121I1J203D01*
G01Y1488247D01*
G03X472021Y1488350I-200J-1D01*
G02Y1490312I1640J981D01*
G03X472050Y1490415I-171J104D01*
G01Y1493365D01*
G03X472021Y1493468I-200J-1D01*
G02Y1495430I1640J981D01*
G03X472050Y1495533I-171J104D01*
G37*
G36*
G01X489372D02*
Y1496659D01*
G02X489575Y1496862I203J0D01*
G01X492395D01*
G02X492598Y1496659I0J-203D01*
G01Y1495533D01*
G03X492626Y1495430I200J-1D01*
G02Y1493468I-1640J-981D01*
G03X492598Y1493365I172J-102D01*
G01Y1490415D01*
G03X492626Y1490312I200J-1D01*
G02Y1488350I-1640J-981D01*
G03X492598Y1488247I172J-102D01*
G01Y1487121D01*
G02X492395Y1486918I-203J0D01*
G01X489575D01*
G02X489372Y1487121I0J203D01*
G01Y1488247D01*
G03X489344Y1488350I-200J1D01*
G02Y1490312I1640J981D01*
G03X489372Y1490415I-172J102D01*
G01Y1493365D01*
G03X489344Y1493468I-200J1D01*
G02Y1495430I1640J981D01*
G03X489372Y1495533I-172J102D01*
G37*
G36*
G01X506694D02*
Y1496659D01*
G02X506897Y1496862I203J0D01*
G01X509717D01*
G02X509920Y1496659I0J-203D01*
G01Y1495533D01*
G03X509948Y1495430I200J-1D01*
G02Y1493468I-1640J-981D01*
G03X509920Y1493365I172J-102D01*
G01Y1490415D01*
G03X509948Y1490312I200J-1D01*
G02Y1488350I-1640J-981D01*
G03X509920Y1488247I172J-102D01*
G01Y1487121D01*
G02X509717Y1486918I-203J0D01*
G01X506897D01*
G02X506694Y1487121I0J203D01*
G01Y1488247D01*
G03X506666Y1488350I-200J1D01*
G02Y1490312I1640J981D01*
G03X506694Y1490415I-172J102D01*
G01Y1493365D01*
G03X506666Y1493468I-200J1D01*
G02Y1495430I1640J981D01*
G03X506694Y1495533I-172J102D01*
G37*
G36*
G01X463388Y1499864D02*
Y1500989D01*
G02X463590Y1501192I202J1D01*
G01X466410D01*
G02X466612Y1500989I-1J-203D01*
G01Y1499864D01*
G03X466641Y1499761I200J1D01*
G02Y1497799I-1640J-981D01*
G03X466612Y1497696I171J-104D01*
G01Y1494746D01*
G03X466641Y1494643I200J1D01*
G02Y1492681I-1640J-981D01*
G03X466612Y1492578I171J-104D01*
G01Y1491451D01*
G02X466410Y1491248I-202J-1D01*
G01X463590D01*
G02X463388Y1491451I1J203D01*
G01Y1492578D01*
G03X463359Y1492681I-200J-1D01*
G02Y1494643I1640J981D01*
G03X463388Y1494746I-171J104D01*
G01Y1497696D01*
G03X463359Y1497799I-200J-1D01*
G02Y1499761I1640J981D01*
G03X463388Y1499864I-171J104D01*
G37*
G36*
G01X480710D02*
Y1500989D01*
G02X480913Y1501192I203J0D01*
G01X483733D01*
G02X483936Y1500989I0J-203D01*
G01Y1499864D01*
G03X483964Y1499761I200J-1D01*
G02Y1497799I-1640J-981D01*
G03X483936Y1497696I172J-102D01*
G01Y1494746D01*
G03X483964Y1494643I200J-1D01*
G02Y1492681I-1640J-981D01*
G03X483936Y1492578I172J-102D01*
G01Y1491451D01*
G02X483733Y1491248I-203J0D01*
G01X480913D01*
G02X480710Y1491451I0J203D01*
G01Y1492578D01*
G03X480682Y1492681I-200J1D01*
G02Y1494643I1640J981D01*
G03X480710Y1494746I-172J102D01*
G01Y1497696D01*
G03X480682Y1497799I-200J1D01*
G02Y1499761I1640J981D01*
G03X480710Y1499864I-172J102D01*
G37*
G36*
G01X498034D02*
Y1500989D01*
G02X498236Y1501192I202J1D01*
G01X501056D01*
G02X501258Y1500989I-1J-203D01*
G01Y1499864D01*
G03X501287Y1499761I200J1D01*
G02Y1497799I-1640J-981D01*
G03X501258Y1497696I171J-104D01*
G01Y1494746D01*
G03X501287Y1494643I200J1D01*
G02Y1492681I-1640J-981D01*
G03X501258Y1492578I171J-104D01*
G01Y1491451D01*
G02X501056Y1491248I-202J-1D01*
G01X498236D01*
G02X498034Y1491451I1J203D01*
G01Y1492578D01*
G03X498005Y1492681I-200J-1D01*
G02Y1494643I1640J981D01*
G03X498034Y1494746I-171J104D01*
G01Y1497696D01*
G03X498005Y1497799I-200J-1D01*
G02Y1499761I1640J981D01*
G03X498034Y1499864I-171J104D01*
G37*
G36*
G01X515356D02*
Y1500989D01*
G02X515559Y1501192I203J0D01*
G01X518379D01*
G02X518582Y1500989I0J-203D01*
G01Y1499864D01*
G03X518610Y1499761I200J-1D01*
G02Y1497799I-1640J-981D01*
G03X518582Y1497696I172J-102D01*
G01Y1494746D01*
G03X518610Y1494643I200J-1D01*
G02Y1492681I-1640J-981D01*
G03X518582Y1492578I172J-102D01*
G01Y1491451D01*
G02X518379Y1491248I-203J0D01*
G01X515559D01*
G02X515356Y1491451I0J203D01*
G01Y1492578D01*
G03X515328Y1492681I-200J1D01*
G02Y1494643I1640J981D01*
G03X515356Y1494746I-172J102D01*
G01Y1497696D01*
G03X515328Y1497799I-200J1D01*
G02Y1499761I1640J981D01*
G03X515356Y1499864I-172J102D01*
G37*
G36*
G01X576792Y1511318D02*
G02X578423Y1511994I1632J-1631D01*
G01X581803D01*
G02Y1507380I0J-2307D01*
G01X579461D01*
G03X579320Y1507322I0J-200D01*
G01X579069Y1507071D01*
G03X579011Y1506931I142J-141D01*
G01X579010Y1506812D01*
G03X579059Y1506678I200J-3D01*
G02X579433Y1505687I-1128J-992D01*
G02X579260Y1504988I-1502J1D01*
G01X579249Y1504966D01*
X579238Y1504919D01*
Y1503638D01*
G02X579222Y1503441I-1306J7D01*
G01X579215Y1503394D01*
X579244Y1503305D01*
X579533Y1503008D01*
X579621Y1502977D01*
X579668Y1502983D01*
G02X579831Y1502994I169J-1296D01*
G01X580290D01*
G03X580431Y1503052I0J200D01*
G01X580560Y1503181D01*
X580585Y1503223D01*
X580593Y1503246D01*
G02X582027Y1504302I1434J-446D01*
G02X583529Y1502800I0J-1502D01*
G02X582473Y1501366I-1502J0D01*
G01X582450Y1501358D01*
X582408Y1501333D01*
X581838Y1500763D01*
G02X580914Y1500380I-924J923D01*
G01X580455D01*
G03X580314Y1500322I0J-200D01*
G01X579621Y1499630D01*
G03X579564Y1499468I142J-141D01*
G01X579600Y1499114D01*
X579646Y1499038D01*
X579684Y1499013D01*
G02X580361Y1497758I-825J-1255D01*
G02X580188Y1497059I-1502J1D01*
G01X580177Y1497037D01*
X580166Y1496990D01*
Y1495131D01*
G03X580282Y1494950I200J0D01*
G01X580666Y1494773D01*
X580781Y1494789D01*
X580826Y1494828D01*
G02X581803Y1495189I977J-1142D01*
G02X583305Y1493687I0J-1502D01*
G02X583132Y1492988I-1502J1D01*
G01X583121Y1492966D01*
X583110Y1492919D01*
Y1488402D01*
G02X582727Y1487478I-1306J0D01*
G01X538025Y1442776D01*
G02X537101Y1442394I-923J924D01*
G01X474017D01*
G02X473093Y1442776I-1J1306D01*
G01X465095Y1450775D01*
X465023Y1450805D01*
X464983D01*
G02X463088Y1452717I17J1912D01*
G02X465000Y1454629I1912J0D01*
G02X466912Y1452734I0J-1912D01*
G01Y1452694D01*
X466942Y1452622D01*
X474500Y1445065D01*
G03X474641Y1445006I142J141D01*
G01X487703D01*
G03X487888Y1445130I0J200D01*
G01X487911Y1445187D01*
X487888Y1445304D01*
X482418Y1450775D01*
X482346Y1450805D01*
X482306D01*
G02X480411Y1452717I17J1912D01*
G02X482323Y1454629I1912J0D01*
G02X484235Y1452734I0J-1912D01*
G01Y1452694D01*
X484265Y1452622D01*
X489741Y1447147D01*
G03X489882Y1447088I142J141D01*
G01X502944D01*
G03X503129Y1447212I0J200D01*
G01X503152Y1447269D01*
X503129Y1447386D01*
X499741Y1450775D01*
X499669Y1450805D01*
X499629D01*
G02X497734Y1452717I17J1912D01*
G02X499646Y1454629I1912J0D01*
G02X501558Y1452734I0J-1912D01*
G01Y1452694D01*
X501588Y1452622D01*
X505234Y1448977D01*
G03X505375Y1448918I142J141D01*
G01X518437D01*
G03X518622Y1449042I0J200D01*
G01X518645Y1449099D01*
X518622Y1449216D01*
X517064Y1450775D01*
X516992Y1450805D01*
X516952D01*
G02X515057Y1452717I17J1912D01*
G02X516969Y1454629I1912J0D01*
G02X518881Y1452734I0J-1912D01*
G01Y1452694D01*
X518911Y1452622D01*
X520427Y1451107D01*
G03X520568Y1451048I142J141D01*
G01X531901D01*
G03X532073Y1451145I0J200D01*
G01X532277Y1451485D01*
X532279Y1451589D01*
X532255Y1451636D01*
G02X531986Y1452717I2038J1081D01*
G02X532661Y1454348I2306J1D01*
G01X569772Y1491459D01*
G03X569830Y1491600I-142J141D01*
G01Y1503401D01*
G02X570506Y1505032I2307J-1D01*
G01X576792Y1511318D01*
G37*
G36*
G01X454726Y1510888D02*
Y1512014D01*
G02X454929Y1512216I203J-1D01*
G01X457749D01*
G02X457952Y1512014I1J-202D01*
G01Y1510888D01*
G03X457980Y1510785I200J-1D01*
G02Y1508823I-1640J-981D01*
G03X457952Y1508720I172J-102D01*
G01Y1505769D01*
G03X457980Y1505666I200J-1D01*
G02Y1503704I-1640J-981D01*
G03X457952Y1503601I172J-102D01*
G01Y1502476D01*
G02X457749Y1502274I-203J1D01*
G01X454929D01*
G02X454726Y1502476I-1J202D01*
G01Y1503601D01*
G03X454698Y1503704I-200J1D01*
G02Y1505666I1640J981D01*
G03X454726Y1505769I-172J102D01*
G01Y1508720D01*
G03X454698Y1508823I-200J1D01*
G02Y1510785I1640J981D01*
G03X454726Y1510888I-172J102D01*
G37*
G36*
G01X472050D02*
Y1512014D01*
G02X472252Y1512216I202J0D01*
G01X475072D01*
G02X475274Y1512014I0J-202D01*
G01Y1510888D01*
G03X475303Y1510785I200J1D01*
G02Y1508823I-1640J-981D01*
G03X475274Y1508720I171J-104D01*
G01Y1505769D01*
G03X475303Y1505666I200J1D01*
G02Y1503704I-1640J-981D01*
G03X475274Y1503601I171J-104D01*
G01Y1502476D01*
G02X475072Y1502274I-202J0D01*
G01X472252D01*
G02X472050Y1502476I0J202D01*
G01Y1503601D01*
G03X472021Y1503704I-200J-1D01*
G02Y1505666I1640J981D01*
G03X472050Y1505769I-171J104D01*
G01Y1508720D01*
G03X472021Y1508823I-200J-1D01*
G02Y1510785I1640J981D01*
G03X472050Y1510888I-171J104D01*
G37*
G36*
G01X489372D02*
Y1512014D01*
G02X489575Y1512216I203J-1D01*
G01X492395D01*
G02X492598Y1512014I1J-202D01*
G01Y1510888D01*
G03X492626Y1510785I200J-1D01*
G02Y1508823I-1640J-981D01*
G03X492598Y1508720I172J-102D01*
G01Y1505769D01*
G03X492626Y1505666I200J-1D01*
G02Y1503704I-1640J-981D01*
G03X492598Y1503601I172J-102D01*
G01Y1502476D01*
G02X492395Y1502274I-203J1D01*
G01X489575D01*
G02X489372Y1502476I-1J202D01*
G01Y1503601D01*
G03X489344Y1503704I-200J1D01*
G02Y1505666I1640J981D01*
G03X489372Y1505769I-172J102D01*
G01Y1508720D01*
G03X489344Y1508823I-200J1D01*
G02Y1510785I1640J981D01*
G03X489372Y1510888I-172J102D01*
G37*
G36*
G01X506694D02*
Y1512014D01*
G02X506897Y1512216I203J-1D01*
G01X509717D01*
G02X509920Y1512014I1J-202D01*
G01Y1510888D01*
G03X509948Y1510785I200J-1D01*
G02Y1508823I-1640J-981D01*
G03X509920Y1508720I172J-102D01*
G01Y1505769D01*
G03X509948Y1505666I200J-1D01*
G02Y1503704I-1640J-981D01*
G03X509920Y1503601I172J-102D01*
G01Y1502476D01*
G02X509717Y1502274I-203J1D01*
G01X506897D01*
G02X506694Y1502476I-1J202D01*
G01Y1503601D01*
G03X506666Y1503704I-200J1D01*
G02Y1505666I1640J981D01*
G03X506694Y1505769I-172J102D01*
G01Y1508720D01*
G03X506666Y1508823I-200J1D01*
G02Y1510785I1640J981D01*
G03X506694Y1510888I-172J102D01*
G37*
G36*
G01X463388Y1515218D02*
Y1516344D01*
G02X463590Y1516546I202J0D01*
G01X466410D01*
G02X466612Y1516344I0J-202D01*
G01Y1515218D01*
G03X466641Y1515115I200J1D01*
G02Y1513153I-1640J-981D01*
G03X466612Y1513050I171J-104D01*
G01Y1510100D01*
G03X466641Y1509997I200J1D01*
G02Y1508035I-1640J-981D01*
G03X466612Y1507932I171J-104D01*
G01Y1506806D01*
G02X466410Y1506604I-202J0D01*
G01X463590D01*
G02X463388Y1506806I0J202D01*
G01Y1507932D01*
G03X463359Y1508035I-200J-1D01*
G02Y1509997I1640J981D01*
G03X463388Y1510100I-171J104D01*
G01Y1513050D01*
G03X463359Y1513153I-200J-1D01*
G02Y1515115I1640J981D01*
G03X463388Y1515218I-171J104D01*
G37*
G36*
G01X480710D02*
Y1516344D01*
G02X480913Y1516546I203J-1D01*
G01X483733D01*
G02X483936Y1516344I1J-202D01*
G01Y1515218D01*
G03X483964Y1515115I200J-1D01*
G02Y1513153I-1640J-981D01*
G03X483936Y1513050I172J-102D01*
G01Y1510100D01*
G03X483964Y1509997I200J-1D01*
G02Y1508035I-1640J-981D01*
G03X483936Y1507932I172J-102D01*
G01Y1506806D01*
G02X483733Y1506604I-203J1D01*
G01X480913D01*
G02X480710Y1506806I-1J202D01*
G01Y1507932D01*
G03X480682Y1508035I-200J1D01*
G02Y1509997I1640J981D01*
G03X480710Y1510100I-172J102D01*
G01Y1513050D01*
G03X480682Y1513153I-200J1D01*
G02Y1515115I1640J981D01*
G03X480710Y1515218I-172J102D01*
G37*
G36*
G01X498034D02*
Y1516344D01*
G02X498236Y1516546I202J0D01*
G01X501056D01*
G02X501258Y1516344I0J-202D01*
G01Y1515218D01*
G03X501287Y1515115I200J1D01*
G02Y1513153I-1640J-981D01*
G03X501258Y1513050I171J-104D01*
G01Y1510100D01*
G03X501287Y1509997I200J1D01*
G02Y1508035I-1640J-981D01*
G03X501258Y1507932I171J-104D01*
G01Y1506806D01*
G02X501056Y1506604I-202J0D01*
G01X498236D01*
G02X498034Y1506806I0J202D01*
G01Y1507932D01*
G03X498005Y1508035I-200J-1D01*
G02Y1509997I1640J981D01*
G03X498034Y1510100I-171J104D01*
G01Y1513050D01*
G03X498005Y1513153I-200J-1D01*
G02Y1515115I1640J981D01*
G03X498034Y1515218I-171J104D01*
G37*
G36*
G01X515356D02*
Y1516344D01*
G02X515559Y1516546I203J-1D01*
G01X518379D01*
G02X518582Y1516344I1J-202D01*
G01Y1515218D01*
G03X518610Y1515115I200J-1D01*
G02Y1513153I-1640J-981D01*
G03X518582Y1513050I172J-102D01*
G01Y1510100D01*
G03X518610Y1509997I200J-1D01*
G02Y1508035I-1640J-981D01*
G03X518582Y1507932I172J-102D01*
G01Y1506806D01*
G02X518379Y1506604I-203J1D01*
G01X515559D01*
G02X515356Y1506806I-1J202D01*
G01Y1507932D01*
G03X515328Y1508035I-200J1D01*
G02Y1509997I1640J981D01*
G03X515356Y1510100I-172J102D01*
G01Y1513050D01*
G03X515328Y1513153I-200J1D01*
G02Y1515115I1640J981D01*
G03X515356Y1515218I-172J102D01*
G37*
G36*
G01X571723Y1519752D02*
X571667Y1520126D01*
X571623Y1520196D01*
X571588Y1520220D01*
G02X570930Y1521462I843J1242D01*
G02X573934I1502J0D01*
G02X573606Y1520525I-1502J0D01*
G01X573579Y1520492D01*
X573558Y1520412D01*
X573614Y1520038D01*
X573658Y1519968D01*
X573693Y1519944D01*
G02X574351Y1518702I-843J-1242D01*
G02X571347I-1502J0D01*
G02X571675Y1519639I1502J0D01*
G01X571702Y1519672D01*
X571723Y1519752D01*
G37*
G36*
G01X393308Y1536368D02*
Y1536704D01*
X393283Y1536771D01*
X393259Y1536799D01*
G02X392889Y1537786I1131J987D01*
G02X395893I1502J0D01*
G02X395523Y1536799I-1501J0D01*
G01X395499Y1536771D01*
X395474Y1536704D01*
Y1536368D01*
X395499Y1536301D01*
X395523Y1536273D01*
G02X395893Y1535286I-1131J-987D01*
G02X392889I-1502J0D01*
G02X393259Y1536273I1501J0D01*
G01X393283Y1536301D01*
X393308Y1536368D01*
G37*
G36*
G01X454726Y1567187D02*
Y1568313D01*
G02X454929Y1568516I203J0D01*
G01X457749D01*
G02X457952Y1568313I0J-203D01*
G01Y1567187D01*
G03X457980Y1567084I200J-1D01*
G02Y1565122I-1640J-981D01*
G03X457952Y1565019I172J-102D01*
G01Y1562069D01*
G03X457980Y1561966I200J-1D01*
G02Y1560004I-1640J-981D01*
G03X457952Y1559901I172J-102D01*
G01Y1558775D01*
G02X457749Y1558572I-203J0D01*
G01X454929D01*
G02X454726Y1558775I0J203D01*
G01Y1559901D01*
G03X454698Y1560004I-200J1D01*
G02Y1561966I1640J981D01*
G03X454726Y1562069I-172J102D01*
G01Y1565019D01*
G03X454698Y1565122I-200J1D01*
G02Y1567084I1640J981D01*
G03X454726Y1567187I-172J102D01*
G37*
G36*
G01X472050D02*
Y1568313D01*
G02X472252Y1568516I202J1D01*
G01X475072D01*
G02X475274Y1568313I-1J-203D01*
G01Y1567187D01*
G03X475303Y1567084I200J1D01*
G02Y1565122I-1640J-981D01*
G03X475274Y1565019I171J-104D01*
G01Y1562069D01*
G03X475303Y1561966I200J1D01*
G02Y1560004I-1640J-981D01*
G03X475274Y1559901I171J-104D01*
G01Y1558775D01*
G02X475072Y1558572I-202J-1D01*
G01X472252D01*
G02X472050Y1558775I1J203D01*
G01Y1559901D01*
G03X472021Y1560004I-200J-1D01*
G02Y1561966I1640J981D01*
G03X472050Y1562069I-171J104D01*
G01Y1565019D01*
G03X472021Y1565122I-200J-1D01*
G02Y1567084I1640J981D01*
G03X472050Y1567187I-171J104D01*
G37*
G36*
G01X489372D02*
Y1568313D01*
G02X489575Y1568516I203J0D01*
G01X492395D01*
G02X492598Y1568313I0J-203D01*
G01Y1567187D01*
G03X492626Y1567084I200J-1D01*
G02Y1565122I-1640J-981D01*
G03X492598Y1565019I172J-102D01*
G01Y1562069D01*
G03X492626Y1561966I200J-1D01*
G02Y1560004I-1640J-981D01*
G03X492598Y1559901I172J-102D01*
G01Y1558775D01*
G02X492395Y1558572I-203J0D01*
G01X489575D01*
G02X489372Y1558775I0J203D01*
G01Y1559901D01*
G03X489344Y1560004I-200J1D01*
G02Y1561966I1640J981D01*
G03X489372Y1562069I-172J102D01*
G01Y1565019D01*
G03X489344Y1565122I-200J1D01*
G02Y1567084I1640J981D01*
G03X489372Y1567187I-172J102D01*
G37*
G36*
G01X506694D02*
Y1568313D01*
G02X506897Y1568516I203J0D01*
G01X509717D01*
G02X509920Y1568313I0J-203D01*
G01Y1567187D01*
G03X509948Y1567084I200J-1D01*
G02Y1565122I-1640J-981D01*
G03X509920Y1565019I172J-102D01*
G01Y1562069D01*
G03X509948Y1561966I200J-1D01*
G02Y1560004I-1640J-981D01*
G03X509920Y1559901I172J-102D01*
G01Y1558775D01*
G02X509717Y1558572I-203J0D01*
G01X506897D01*
G02X506694Y1558775I0J203D01*
G01Y1559901D01*
G03X506666Y1560004I-200J1D01*
G02Y1561966I1640J981D01*
G03X506694Y1562069I-172J102D01*
G01Y1565019D01*
G03X506666Y1565122I-200J1D01*
G02Y1567084I1640J981D01*
G03X506694Y1567187I-172J102D01*
G37*
G36*
G01X463388Y1571518D02*
Y1572644D01*
G02X463590Y1572846I202J0D01*
G01X466410D01*
G02X466612Y1572644I0J-202D01*
G01Y1571518D01*
G03X466641Y1571415I200J1D01*
G02Y1569453I-1640J-981D01*
G03X466612Y1569350I171J-104D01*
G01Y1566399D01*
G03X466641Y1566296I200J1D01*
G02Y1564334I-1640J-981D01*
G03X466612Y1564231I171J-104D01*
G01Y1563106D01*
G02X466410Y1562904I-202J0D01*
G01X463590D01*
G02X463388Y1563106I0J202D01*
G01Y1564231D01*
G03X463359Y1564334I-200J-1D01*
G02Y1566296I1640J981D01*
G03X463388Y1566399I-171J104D01*
G01Y1569350D01*
G03X463359Y1569453I-200J-1D01*
G02Y1571415I1640J981D01*
G03X463388Y1571518I-171J104D01*
G37*
G36*
G01X480710D02*
Y1572644D01*
G02X480913Y1572846I203J-1D01*
G01X483733D01*
G02X483936Y1572644I1J-202D01*
G01Y1571518D01*
G03X483964Y1571415I200J-1D01*
G02Y1569453I-1640J-981D01*
G03X483936Y1569350I172J-102D01*
G01Y1566399D01*
G03X483964Y1566296I200J-1D01*
G02Y1564334I-1640J-981D01*
G03X483936Y1564231I172J-102D01*
G01Y1563106D01*
G02X483733Y1562904I-203J1D01*
G01X480913D01*
G02X480710Y1563106I-1J202D01*
G01Y1564231D01*
G03X480682Y1564334I-200J1D01*
G02Y1566296I1640J981D01*
G03X480710Y1566399I-172J102D01*
G01Y1569350D01*
G03X480682Y1569453I-200J1D01*
G02Y1571415I1640J981D01*
G03X480710Y1571518I-172J102D01*
G37*
G36*
G01X498034D02*
Y1572644D01*
G02X498236Y1572846I202J0D01*
G01X501056D01*
G02X501258Y1572644I0J-202D01*
G01Y1571518D01*
G03X501287Y1571415I200J1D01*
G02Y1569453I-1640J-981D01*
G03X501258Y1569350I171J-104D01*
G01Y1566399D01*
G03X501287Y1566296I200J1D01*
G02Y1564334I-1640J-981D01*
G03X501258Y1564231I171J-104D01*
G01Y1563106D01*
G02X501056Y1562904I-202J0D01*
G01X498236D01*
G02X498034Y1563106I0J202D01*
G01Y1564231D01*
G03X498005Y1564334I-200J-1D01*
G02Y1566296I1640J981D01*
G03X498034Y1566399I-171J104D01*
G01Y1569350D01*
G03X498005Y1569453I-200J-1D01*
G02Y1571415I1640J981D01*
G03X498034Y1571518I-171J104D01*
G37*
G36*
G01X515356D02*
Y1572644D01*
G02X515559Y1572846I203J-1D01*
G01X518379D01*
G02X518582Y1572644I1J-202D01*
G01Y1571518D01*
G03X518610Y1571415I200J-1D01*
G02Y1569453I-1640J-981D01*
G03X518582Y1569350I172J-102D01*
G01Y1566399D01*
G03X518610Y1566296I200J-1D01*
G02Y1564334I-1640J-981D01*
G03X518582Y1564231I172J-102D01*
G01Y1563106D01*
G02X518379Y1562904I-203J1D01*
G01X515559D01*
G02X515356Y1563106I-1J202D01*
G01Y1564231D01*
G03X515328Y1564334I-200J1D01*
G02Y1566296I1640J981D01*
G03X515356Y1566399I-172J102D01*
G01Y1569350D01*
G03X515328Y1569453I-200J1D01*
G02Y1571415I1640J981D01*
G03X515356Y1571518I-172J102D01*
G37*
G36*
G01X454726Y1582541D02*
Y1583667D01*
G02X454929Y1583870I203J0D01*
G01X457749D01*
G02X457952Y1583667I0J-203D01*
G01Y1582541D01*
G03X457980Y1582438I200J-1D01*
G02Y1580476I-1640J-981D01*
G03X457952Y1580373I172J-102D01*
G01Y1577423D01*
G03X457980Y1577320I200J-1D01*
G02Y1575358I-1640J-981D01*
G03X457952Y1575255I172J-102D01*
G01Y1574129D01*
G02X457749Y1573926I-203J0D01*
G01X454929D01*
G02X454726Y1574129I0J203D01*
G01Y1575255D01*
G03X454698Y1575358I-200J1D01*
G02Y1577320I1640J981D01*
G03X454726Y1577423I-172J102D01*
G01Y1580373D01*
G03X454698Y1580476I-200J1D01*
G02Y1582438I1640J981D01*
G03X454726Y1582541I-172J102D01*
G37*
G36*
G01X472050D02*
Y1583667D01*
G02X472252Y1583870I202J1D01*
G01X475072D01*
G02X475274Y1583667I-1J-203D01*
G01Y1582541D01*
G03X475303Y1582438I200J1D01*
G02Y1580476I-1640J-981D01*
G03X475274Y1580373I171J-104D01*
G01Y1577423D01*
G03X475303Y1577320I200J1D01*
G02Y1575358I-1640J-981D01*
G03X475274Y1575255I171J-104D01*
G01Y1574129D01*
G02X475072Y1573926I-202J-1D01*
G01X472252D01*
G02X472050Y1574129I1J203D01*
G01Y1575255D01*
G03X472021Y1575358I-200J-1D01*
G02Y1577320I1640J981D01*
G03X472050Y1577423I-171J104D01*
G01Y1580373D01*
G03X472021Y1580476I-200J-1D01*
G02Y1582438I1640J981D01*
G03X472050Y1582541I-171J104D01*
G37*
G36*
G01X489372D02*
Y1583667D01*
G02X489575Y1583870I203J0D01*
G01X492395D01*
G02X492598Y1583667I0J-203D01*
G01Y1582541D01*
G03X492626Y1582438I200J-1D01*
G02Y1580476I-1640J-981D01*
G03X492598Y1580373I172J-102D01*
G01Y1577423D01*
G03X492626Y1577320I200J-1D01*
G02Y1575358I-1640J-981D01*
G03X492598Y1575255I172J-102D01*
G01Y1574129D01*
G02X492395Y1573926I-203J0D01*
G01X489575D01*
G02X489372Y1574129I0J203D01*
G01Y1575255D01*
G03X489344Y1575358I-200J1D01*
G02Y1577320I1640J981D01*
G03X489372Y1577423I-172J102D01*
G01Y1580373D01*
G03X489344Y1580476I-200J1D01*
G02Y1582438I1640J981D01*
G03X489372Y1582541I-172J102D01*
G37*
G36*
G01X506694D02*
Y1583667D01*
G02X506897Y1583870I203J0D01*
G01X509717D01*
G02X509920Y1583667I0J-203D01*
G01Y1582541D01*
G03X509948Y1582438I200J-1D01*
G02Y1580476I-1640J-981D01*
G03X509920Y1580373I172J-102D01*
G01Y1577423D01*
G03X509948Y1577320I200J-1D01*
G02Y1575358I-1640J-981D01*
G03X509920Y1575255I172J-102D01*
G01Y1574129D01*
G02X509717Y1573926I-203J0D01*
G01X506897D01*
G02X506694Y1574129I0J203D01*
G01Y1575255D01*
G03X506666Y1575358I-200J1D01*
G02Y1577320I1640J981D01*
G03X506694Y1577423I-172J102D01*
G01Y1580373D01*
G03X506666Y1580476I-200J1D01*
G02Y1582438I1640J981D01*
G03X506694Y1582541I-172J102D01*
G37*
G36*
G01X463388Y1586872D02*
Y1587998D01*
G02X463590Y1588200I202J0D01*
G01X466410D01*
G02X466612Y1587998I0J-202D01*
G01Y1586872D01*
G03X466641Y1586769I200J1D01*
G02Y1584807I-1640J-981D01*
G03X466612Y1584704I171J-104D01*
G01Y1581754D01*
G03X466641Y1581651I200J1D01*
G02Y1579689I-1640J-981D01*
G03X466612Y1579586I171J-104D01*
G01Y1578460D01*
G02X466410Y1578258I-202J0D01*
G01X463590D01*
G02X463388Y1578460I0J202D01*
G01Y1579586D01*
G03X463359Y1579689I-200J-1D01*
G02Y1581651I1640J981D01*
G03X463388Y1581754I-171J104D01*
G01Y1584704D01*
G03X463359Y1584807I-200J-1D01*
G02Y1586769I1640J981D01*
G03X463388Y1586872I-171J104D01*
G37*
G36*
G01X480710D02*
Y1587998D01*
G02X480913Y1588200I203J-1D01*
G01X483733D01*
G02X483936Y1587998I1J-202D01*
G01Y1586872D01*
G03X483964Y1586769I200J-1D01*
G02Y1584807I-1640J-981D01*
G03X483936Y1584704I172J-102D01*
G01Y1581754D01*
G03X483964Y1581651I200J-1D01*
G02Y1579689I-1640J-981D01*
G03X483936Y1579586I172J-102D01*
G01Y1578460D01*
G02X483733Y1578258I-203J1D01*
G01X480913D01*
G02X480710Y1578460I-1J202D01*
G01Y1579586D01*
G03X480682Y1579689I-200J1D01*
G02Y1581651I1640J981D01*
G03X480710Y1581754I-172J102D01*
G01Y1584704D01*
G03X480682Y1584807I-200J1D01*
G02Y1586769I1640J981D01*
G03X480710Y1586872I-172J102D01*
G37*
G36*
G01X498034D02*
Y1587998D01*
G02X498236Y1588200I202J0D01*
G01X501056D01*
G02X501258Y1587998I0J-202D01*
G01Y1586872D01*
G03X501287Y1586769I200J1D01*
G02Y1584807I-1640J-981D01*
G03X501258Y1584704I171J-104D01*
G01Y1581754D01*
G03X501287Y1581651I200J1D01*
G02Y1579689I-1640J-981D01*
G03X501258Y1579586I171J-104D01*
G01Y1578460D01*
G02X501056Y1578258I-202J0D01*
G01X498236D01*
G02X498034Y1578460I0J202D01*
G01Y1579586D01*
G03X498005Y1579689I-200J-1D01*
G02Y1581651I1640J981D01*
G03X498034Y1581754I-171J104D01*
G01Y1584704D01*
G03X498005Y1584807I-200J-1D01*
G02Y1586769I1640J981D01*
G03X498034Y1586872I-171J104D01*
G37*
G36*
G01X515356D02*
Y1587998D01*
G02X515559Y1588200I203J-1D01*
G01X518379D01*
G02X518582Y1587998I1J-202D01*
G01Y1586872D01*
G03X518610Y1586769I200J-1D01*
G02Y1584807I-1640J-981D01*
G03X518582Y1584704I172J-102D01*
G01Y1581754D01*
G03X518610Y1581651I200J-1D01*
G02Y1579689I-1640J-981D01*
G03X518582Y1579586I172J-102D01*
G01Y1578460D01*
G02X518379Y1578258I-203J1D01*
G01X515559D01*
G02X515356Y1578460I-1J202D01*
G01Y1579586D01*
G03X515328Y1579689I-200J1D01*
G02Y1581651I1640J981D01*
G03X515356Y1581754I-172J102D01*
G01Y1584704D01*
G03X515328Y1584807I-200J1D01*
G02Y1586769I1640J981D01*
G03X515356Y1586872I-172J102D01*
G37*
G36*
G01X454726Y1597895D02*
Y1599021D01*
G02X454929Y1599224I203J0D01*
G01X457749D01*
G02X457952Y1599021I0J-203D01*
G01Y1597895D01*
G03X457980Y1597792I200J-1D01*
G02Y1595830I-1640J-981D01*
G03X457952Y1595727I172J-102D01*
G01Y1592777D01*
G03X457980Y1592674I200J-1D01*
G02Y1590712I-1640J-981D01*
G03X457952Y1590609I172J-102D01*
G01Y1589483D01*
G02X457749Y1589280I-203J0D01*
G01X454929D01*
G02X454726Y1589483I0J203D01*
G01Y1590609D01*
G03X454698Y1590712I-200J1D01*
G02Y1592674I1640J981D01*
G03X454726Y1592777I-172J102D01*
G01Y1595727D01*
G03X454698Y1595830I-200J1D01*
G02Y1597792I1640J981D01*
G03X454726Y1597895I-172J102D01*
G37*
G36*
G01X472050D02*
Y1599021D01*
G02X472252Y1599224I202J1D01*
G01X475072D01*
G02X475274Y1599021I-1J-203D01*
G01Y1597895D01*
G03X475303Y1597792I200J1D01*
G02Y1595830I-1640J-981D01*
G03X475274Y1595727I171J-104D01*
G01Y1592777D01*
G03X475303Y1592674I200J1D01*
G02Y1590712I-1640J-981D01*
G03X475274Y1590609I171J-104D01*
G01Y1589483D01*
G02X475072Y1589280I-202J-1D01*
G01X472252D01*
G02X472050Y1589483I1J203D01*
G01Y1590609D01*
G03X472021Y1590712I-200J-1D01*
G02Y1592674I1640J981D01*
G03X472050Y1592777I-171J104D01*
G01Y1595727D01*
G03X472021Y1595830I-200J-1D01*
G02Y1597792I1640J981D01*
G03X472050Y1597895I-171J104D01*
G37*
G36*
G01X489372D02*
Y1599021D01*
G02X489575Y1599224I203J0D01*
G01X492395D01*
G02X492598Y1599021I0J-203D01*
G01Y1597895D01*
G03X492626Y1597792I200J-1D01*
G02Y1595830I-1640J-981D01*
G03X492598Y1595727I172J-102D01*
G01Y1592777D01*
G03X492626Y1592674I200J-1D01*
G02Y1590712I-1640J-981D01*
G03X492598Y1590609I172J-102D01*
G01Y1589483D01*
G02X492395Y1589280I-203J0D01*
G01X489575D01*
G02X489372Y1589483I0J203D01*
G01Y1590609D01*
G03X489344Y1590712I-200J1D01*
G02Y1592674I1640J981D01*
G03X489372Y1592777I-172J102D01*
G01Y1595727D01*
G03X489344Y1595830I-200J1D01*
G02Y1597792I1640J981D01*
G03X489372Y1597895I-172J102D01*
G37*
G36*
G01X506694D02*
Y1599021D01*
G02X506897Y1599224I203J0D01*
G01X509717D01*
G02X509920Y1599021I0J-203D01*
G01Y1597895D01*
G03X509948Y1597792I200J-1D01*
G02Y1595830I-1640J-981D01*
G03X509920Y1595727I172J-102D01*
G01Y1592777D01*
G03X509948Y1592674I200J-1D01*
G02Y1590712I-1640J-981D01*
G03X509920Y1590609I172J-102D01*
G01Y1589483D01*
G02X509717Y1589280I-203J0D01*
G01X506897D01*
G02X506694Y1589483I0J203D01*
G01Y1590609D01*
G03X506666Y1590712I-200J1D01*
G02Y1592674I1640J981D01*
G03X506694Y1592777I-172J102D01*
G01Y1595727D01*
G03X506666Y1595830I-200J1D01*
G02Y1597792I1640J981D01*
G03X506694Y1597895I-172J102D01*
G37*
G36*
G01X463388Y1602226D02*
Y1603352D01*
G02X463590Y1603554I202J0D01*
G01X466410D01*
G02X466612Y1603352I0J-202D01*
G01Y1602226D01*
G03X466641Y1602123I200J1D01*
G02Y1600161I-1640J-981D01*
G03X466612Y1600058I171J-104D01*
G01Y1597108D01*
G03X466641Y1597005I200J1D01*
G02Y1595043I-1640J-981D01*
G03X466612Y1594940I171J-104D01*
G01Y1593814D01*
G02X466410Y1593612I-202J0D01*
G01X463590D01*
G02X463388Y1593814I0J202D01*
G01Y1594940D01*
G03X463359Y1595043I-200J-1D01*
G02Y1597005I1640J981D01*
G03X463388Y1597108I-171J104D01*
G01Y1600058D01*
G03X463359Y1600161I-200J-1D01*
G02Y1602123I1640J981D01*
G03X463388Y1602226I-171J104D01*
G37*
G36*
G01X480710D02*
Y1603352D01*
G02X480913Y1603554I203J-1D01*
G01X483733D01*
G02X483936Y1603352I1J-202D01*
G01Y1602226D01*
G03X483964Y1602123I200J-1D01*
G02Y1600161I-1640J-981D01*
G03X483936Y1600058I172J-102D01*
G01Y1597108D01*
G03X483964Y1597005I200J-1D01*
G02Y1595043I-1640J-981D01*
G03X483936Y1594940I172J-102D01*
G01Y1593814D01*
G02X483733Y1593612I-203J1D01*
G01X480913D01*
G02X480710Y1593814I-1J202D01*
G01Y1594940D01*
G03X480682Y1595043I-200J1D01*
G02Y1597005I1640J981D01*
G03X480710Y1597108I-172J102D01*
G01Y1600058D01*
G03X480682Y1600161I-200J1D01*
G02Y1602123I1640J981D01*
G03X480710Y1602226I-172J102D01*
G37*
G36*
G01X498034D02*
Y1603352D01*
G02X498236Y1603554I202J0D01*
G01X501056D01*
G02X501258Y1603352I0J-202D01*
G01Y1602226D01*
G03X501287Y1602123I200J1D01*
G02Y1600161I-1640J-981D01*
G03X501258Y1600058I171J-104D01*
G01Y1597108D01*
G03X501287Y1597005I200J1D01*
G02Y1595043I-1640J-981D01*
G03X501258Y1594940I171J-104D01*
G01Y1593814D01*
G02X501056Y1593612I-202J0D01*
G01X498236D01*
G02X498034Y1593814I0J202D01*
G01Y1594940D01*
G03X498005Y1595043I-200J-1D01*
G02Y1597005I1640J981D01*
G03X498034Y1597108I-171J104D01*
G01Y1600058D01*
G03X498005Y1600161I-200J-1D01*
G02Y1602123I1640J981D01*
G03X498034Y1602226I-171J104D01*
G37*
G36*
G01X515356D02*
Y1603352D01*
G02X515559Y1603554I203J-1D01*
G01X518379D01*
G02X518582Y1603352I1J-202D01*
G01Y1602226D01*
G03X518610Y1602123I200J-1D01*
G02Y1600161I-1640J-981D01*
G03X518582Y1600058I172J-102D01*
G01Y1597108D01*
G03X518610Y1597005I200J-1D01*
G02Y1595043I-1640J-981D01*
G03X518582Y1594940I172J-102D01*
G01Y1593814D01*
G02X518379Y1593612I-203J1D01*
G01X515559D01*
G02X515356Y1593814I-1J202D01*
G01Y1594940D01*
G03X515328Y1595043I-200J1D01*
G02Y1597005I1640J981D01*
G03X515356Y1597108I-172J102D01*
G01Y1600058D01*
G03X515328Y1600161I-200J1D01*
G02Y1602123I1640J981D01*
G03X515356Y1602226I-172J102D01*
G37*
G36*
G01X454726Y1613250D02*
Y1614376D01*
G02X454929Y1614578I203J-1D01*
G01X457749D01*
G02X457952Y1614376I1J-202D01*
G01Y1613250D01*
G03X457980Y1613147I200J-1D01*
G02Y1611185I-1640J-981D01*
G03X457952Y1611082I172J-102D01*
G01Y1608132D01*
G03X457980Y1608029I200J-1D01*
G02Y1606067I-1640J-981D01*
G03X457952Y1605964I172J-102D01*
G01Y1604838D01*
G02X457749Y1604636I-203J1D01*
G01X454929D01*
G02X454726Y1604838I-1J202D01*
G01Y1605964D01*
G03X454698Y1606067I-200J1D01*
G02Y1608029I1640J981D01*
G03X454726Y1608132I-172J102D01*
G01Y1611082D01*
G03X454698Y1611185I-200J1D01*
G02Y1613147I1640J981D01*
G03X454726Y1613250I-172J102D01*
G37*
G36*
G01X472050D02*
Y1614376D01*
G02X472252Y1614578I202J0D01*
G01X475072D01*
G02X475274Y1614376I0J-202D01*
G01Y1613250D01*
G03X475303Y1613147I200J1D01*
G02Y1611185I-1640J-981D01*
G03X475274Y1611082I171J-104D01*
G01Y1608132D01*
G03X475303Y1608029I200J1D01*
G02Y1606067I-1640J-981D01*
G03X475274Y1605964I171J-104D01*
G01Y1604838D01*
G02X475072Y1604636I-202J0D01*
G01X472252D01*
G02X472050Y1604838I0J202D01*
G01Y1605964D01*
G03X472021Y1606067I-200J-1D01*
G02Y1608029I1640J981D01*
G03X472050Y1608132I-171J104D01*
G01Y1611082D01*
G03X472021Y1611185I-200J-1D01*
G02Y1613147I1640J981D01*
G03X472050Y1613250I-171J104D01*
G37*
G36*
G01X489372D02*
Y1614376D01*
G02X489575Y1614578I203J-1D01*
G01X492395D01*
G02X492598Y1614376I1J-202D01*
G01Y1613250D01*
G03X492626Y1613147I200J-1D01*
G02Y1611185I-1640J-981D01*
G03X492598Y1611082I172J-102D01*
G01Y1608132D01*
G03X492626Y1608029I200J-1D01*
G02Y1606067I-1640J-981D01*
G03X492598Y1605964I172J-102D01*
G01Y1604838D01*
G02X492395Y1604636I-203J1D01*
G01X489575D01*
G02X489372Y1604838I-1J202D01*
G01Y1605964D01*
G03X489344Y1606067I-200J1D01*
G02Y1608029I1640J981D01*
G03X489372Y1608132I-172J102D01*
G01Y1611082D01*
G03X489344Y1611185I-200J1D01*
G02Y1613147I1640J981D01*
G03X489372Y1613250I-172J102D01*
G37*
G36*
G01X506694D02*
Y1614376D01*
G02X506897Y1614578I203J-1D01*
G01X509717D01*
G02X509920Y1614376I1J-202D01*
G01Y1613250D01*
G03X509948Y1613147I200J-1D01*
G02Y1611185I-1640J-981D01*
G03X509920Y1611082I172J-102D01*
G01Y1608132D01*
G03X509948Y1608029I200J-1D01*
G02Y1606067I-1640J-981D01*
G03X509920Y1605964I172J-102D01*
G01Y1604838D01*
G02X509717Y1604636I-203J1D01*
G01X506897D01*
G02X506694Y1604838I-1J202D01*
G01Y1605964D01*
G03X506666Y1606067I-200J1D01*
G02Y1608029I1640J981D01*
G03X506694Y1608132I-172J102D01*
G01Y1611082D01*
G03X506666Y1611185I-200J1D01*
G02Y1613147I1640J981D01*
G03X506694Y1613250I-172J102D01*
G37*
G36*
G01X463388Y1617580D02*
Y1618706D01*
G02X463590Y1618908I202J0D01*
G01X466410D01*
G02X466612Y1618706I0J-202D01*
G01Y1617580D01*
G03X466641Y1617477I200J1D01*
G02Y1615515I-1640J-981D01*
G03X466612Y1615412I171J-104D01*
G01Y1612462D01*
G03X466641Y1612359I200J1D01*
G02Y1610397I-1640J-981D01*
G03X466612Y1610294I171J-104D01*
G01Y1609168D01*
G02X466410Y1608966I-202J0D01*
G01X463590D01*
G02X463388Y1609168I0J202D01*
G01Y1610294D01*
G03X463359Y1610397I-200J-1D01*
G02Y1612359I1640J981D01*
G03X463388Y1612462I-171J104D01*
G01Y1615412D01*
G03X463359Y1615515I-200J-1D01*
G02Y1617477I1640J981D01*
G03X463388Y1617580I-171J104D01*
G37*
G36*
G01X480710D02*
Y1618706D01*
G02X480913Y1618908I203J-1D01*
G01X483733D01*
G02X483936Y1618706I1J-202D01*
G01Y1617580D01*
G03X483964Y1617477I200J-1D01*
G02Y1615515I-1640J-981D01*
G03X483936Y1615412I172J-102D01*
G01Y1612462D01*
G03X483964Y1612359I200J-1D01*
G02Y1610397I-1640J-981D01*
G03X483936Y1610294I172J-102D01*
G01Y1609168D01*
G02X483733Y1608966I-203J1D01*
G01X480913D01*
G02X480710Y1609168I-1J202D01*
G01Y1610294D01*
G03X480682Y1610397I-200J1D01*
G02Y1612359I1640J981D01*
G03X480710Y1612462I-172J102D01*
G01Y1615412D01*
G03X480682Y1615515I-200J1D01*
G02Y1617477I1640J981D01*
G03X480710Y1617580I-172J102D01*
G37*
G36*
G01X498034D02*
Y1618706D01*
G02X498236Y1618908I202J0D01*
G01X501056D01*
G02X501258Y1618706I0J-202D01*
G01Y1617580D01*
G03X501287Y1617477I200J1D01*
G02Y1615515I-1640J-981D01*
G03X501258Y1615412I171J-104D01*
G01Y1612462D01*
G03X501287Y1612359I200J1D01*
G02Y1610397I-1640J-981D01*
G03X501258Y1610294I171J-104D01*
G01Y1609168D01*
G02X501056Y1608966I-202J0D01*
G01X498236D01*
G02X498034Y1609168I0J202D01*
G01Y1610294D01*
G03X498005Y1610397I-200J-1D01*
G02Y1612359I1640J981D01*
G03X498034Y1612462I-171J104D01*
G01Y1615412D01*
G03X498005Y1615515I-200J-1D01*
G02Y1617477I1640J981D01*
G03X498034Y1617580I-171J104D01*
G37*
G36*
G01X515356D02*
Y1618706D01*
G02X515559Y1618908I203J-1D01*
G01X518379D01*
G02X518582Y1618706I1J-202D01*
G01Y1617580D01*
G03X518610Y1617477I200J-1D01*
G02Y1615515I-1640J-981D01*
G03X518582Y1615412I172J-102D01*
G01Y1612462D01*
G03X518610Y1612359I200J-1D01*
G02Y1610397I-1640J-981D01*
G03X518582Y1610294I172J-102D01*
G01Y1609168D01*
G02X518379Y1608966I-203J1D01*
G01X515559D01*
G02X515356Y1609168I-1J202D01*
G01Y1610294D01*
G03X515328Y1610397I-200J1D01*
G02Y1612359I1640J981D01*
G03X515356Y1612462I-172J102D01*
G01Y1615412D01*
G03X515328Y1615515I-200J1D01*
G02Y1617477I1640J981D01*
G03X515356Y1617580I-172J102D01*
G37*
G36*
G01X425169Y1359159D02*
G02X424353Y1360495I686J1336D01*
G02X427357I1502J0D01*
G02X426586Y1359183I-1502J0D01*
G03X426598Y1358477I194J-350D01*
G02X427414Y1357141I-686J-1336D01*
G02X424410I-1502J0D01*
G02X425181Y1358453I1502J0D01*
G03X425169Y1359159I-194J350D01*
G37*
G36*
G01X422058Y1399145D02*
X422016Y1399168D01*
G02X421227Y1400490I713J1322D01*
G02X424231I1502J0D01*
G02X423814Y1399451I-1503J0D01*
G01X423781Y1399417D01*
X423753Y1399328D01*
X423817Y1398921D01*
X423871Y1398845D01*
X423913Y1398822D01*
G02X424702Y1397500I-713J-1322D01*
G02X424197Y1396377I-1501J0D01*
G01X424162Y1396345D01*
X424127Y1396261D01*
X424154Y1395851D01*
X424200Y1395772D01*
X424239Y1395746D01*
G02X424902Y1394500I-839J-1246D01*
G02X421898I-1502J0D01*
G02X422403Y1395623I1501J0D01*
G01X422438Y1395655D01*
X422473Y1395739D01*
X422446Y1396149D01*
X422400Y1396228D01*
X422361Y1396254D01*
G02X421698Y1397500I839J1246D01*
G02X422115Y1398539I1503J0D01*
G01X422148Y1398573D01*
X422176Y1398662D01*
X422112Y1399069D01*
X422058Y1399145D01*
G37*
G36*
G01X418350Y1400899D02*
G02X417598Y1402200I749J1301D01*
G02X420602I1502J0D01*
G02X419807Y1400875I-1502J0D01*
G03X419795Y1400175I188J-353D01*
G02X420547Y1398874I-749J-1301D01*
G02X417543I-1502J0D01*
G02X418338Y1400199I1502J0D01*
G03X418350Y1400899I-188J353D01*
G37*
G36*
G01X409513Y1451212D02*
G02X411000Y1452502I1487J-212D01*
G02Y1449498I0J-1502D01*
G02X410094Y1449802I0J1502D01*
G03X409457Y1449539I-241J-319D01*
G02X407970Y1448249I-1487J212D01*
G02Y1451253I0J1502D01*
G02X408876Y1450949I0J-1502D01*
G03X409513Y1451212I241J319D01*
G37*
G36*
G01X478808Y147959D02*
X478787Y147998D01*
G02X478604Y148717I1319J719D01*
G02X481608I1502J0D01*
G02X480603Y147300I-1501J0D01*
G01X480561Y147285D01*
X480498Y147224D01*
X480357Y146857D01*
X480363Y146770D01*
X480384Y146731D01*
G02X480567Y146012I-1319J-719D01*
G02X479907Y144768I-1502J0D01*
G03X479819Y144603I112J-166D01*
G01Y144271D01*
G03X479907Y144106I200J1D01*
G02X480552Y143074I-842J-1244D01*
G01X480557Y143037D01*
X480591Y142974D01*
X480849Y142754D01*
X480915Y142729D01*
X480953Y142730D01*
X480971D01*
G02Y139726I0J-1502D01*
G02X479484Y141016I0J1502D01*
G01X479479Y141053D01*
X479445Y141116D01*
X479187Y141336D01*
X479121Y141361D01*
X479083Y141360D01*
X479065D01*
G02X477563Y142862I0J1502D01*
G02X478223Y144106I1502J0D01*
G03X478311Y144271I-112J166D01*
G01Y144603D01*
G03X478223Y144768I-200J-1D01*
G02X477563Y146012I842J1244D01*
G02X478568Y147429I1501J0D01*
G01X478610Y147444D01*
X478673Y147505D01*
X478814Y147872D01*
X478808Y147959D01*
G37*
G36*
G01X478666Y110018D02*
X478982D01*
G03X479139Y110095I-1J200D01*
G02X480324Y110674I1185J-923D01*
G02X481826Y109172I0J-1502D01*
G02X480862Y107770I-1502J0D01*
G01X480822Y107754D01*
X480762Y107693D01*
X480627Y107331D01*
X480633Y107245D01*
X480654Y107207D01*
G02X480833Y106495I-1323J-711D01*
G02X477829I-1502J0D01*
G02X477967Y107123I1502J-1D01*
G01X477990Y107173D01*
X477978Y107283D01*
X477701Y107653D01*
X477599Y107694D01*
X477545Y107686D01*
G02X477324Y107670I-219J1486D01*
G02Y110674I0J1502D01*
G02X478509Y110095I0J-1502D01*
G03X478666Y110018I158J123D01*
G37*
G36*
G01X491433Y105329D02*
X491393Y105360D01*
G02X490792Y106561I901J1202D01*
G02X493796I1502J0D01*
G02X493070Y105275I-1502J0D01*
G01X493027Y105249D01*
X492976Y105164D01*
X492954Y104732D01*
X492996Y104643D01*
X493036Y104612D01*
G02X493591Y103779I-901J-1202D01*
G01X493603Y103731D01*
X493669Y103658D01*
X494072Y103509D01*
X494168Y103522D01*
X494209Y103550D01*
G02X495075Y103825I866J-1226D01*
G02Y100821I0J-1502D01*
G02X493619Y101955I0J1502D01*
G01X493607Y102003D01*
X493541Y102076D01*
X493138Y102225D01*
X493042Y102212D01*
X493001Y102184D01*
G02X492135Y101909I-866J1226D01*
G02X490633Y103411I0J1502D01*
G02X491359Y104697I1502J0D01*
G01X491402Y104723D01*
X491453Y104808D01*
X491475Y105240D01*
X491433Y105329D01*
G37*
G36*
G01X547704Y102731D02*
G02X547412Y103621I1210J890D01*
G02X550416I1502J0D01*
G02X549191Y102145I-1502J0D01*
G03X548942Y101515I73J-393D01*
G02X549234Y100625I-1210J-890D01*
G02X546230I-1502J0D01*
G02X547455Y102101I1502J0D01*
G03X547704Y102731I-73J393D01*
G37*
G36*
G01X512132Y101849D02*
G02X511549Y103037I919J1188D01*
G02X514553I1502J0D01*
G02X513897Y101796I-1502J0D01*
G03X513877Y101149I225J-331D01*
G02X514460Y99961I-919J-1188D01*
G02X511456I-1502J0D01*
G02X512112Y101202I1502J0D01*
G03X512132Y101849I-225J331D01*
G37*
G36*
G01X506645Y91453D02*
G02X506091Y91347I-554J1395D01*
G02X507593Y92849I0J1502D01*
G02X507547Y92481I-1502J1D01*
G03X508083Y92011I388J-98D01*
G02X508637Y92117I554J-1395D01*
G02X507135Y90615I0J-1502D01*
G02X507181Y90983I1502J-1D01*
G03X506645Y91453I-388J98D01*
G37*
G36*
G01X557484Y90701D02*
G02X556814Y91951I831J1250D01*
G02X559818I1502J0D01*
G02X559168Y90714I-1502J0D01*
G03X559173Y90051I227J-330D01*
G02X559843Y88801I-831J-1250D01*
G02X556839I-1502J0D01*
G02X557489Y90038I1502J0D01*
G03X557484Y90701I-227J330D01*
G37*
G36*
G01X468893Y217133D02*
X468599D01*
G03X468452Y217068I1J-200D01*
G02X467346Y216583I-1105J1017D01*
G02Y219587I0J1502D01*
G02X468452Y219102I1J-1502D01*
G03X468599Y219037I148J135D01*
G01X468893D01*
G03X469040Y219102I-1J200D01*
G02X470146Y219587I1105J-1017D01*
G02Y216583I0J-1502D01*
G02X469040Y217068I-1J1502D01*
G03X468893Y217133I-148J-135D01*
G37*
G36*
G01X475073Y205755D02*
X474737D01*
X474670Y205730D01*
X474642Y205706D01*
G02X473655Y205336I-987J1131D01*
G02Y208340I0J1502D01*
G02X474642Y207970I0J-1501D01*
G01X474670Y207946D01*
X474737Y207921D01*
X475073D01*
X475140Y207946D01*
X475168Y207970D01*
G02X476155Y208340I987J-1131D01*
G02Y205336I0J-1502D01*
G02X475168Y205706I0J1501D01*
G01X475140Y205730D01*
X475073Y205755D01*
G37*
G36*
G01X468885Y202310D02*
X468549D01*
X468482Y202285D01*
X468454Y202261D01*
G02X467467Y201891I-987J1131D01*
G02Y204895I0J1502D01*
G02X468454Y204525I0J-1501D01*
G01X468482Y204501D01*
X468549Y204476D01*
X468885D01*
X468952Y204501D01*
X468980Y204525D01*
G02X469967Y204895I987J-1131D01*
G02X471464Y203517I0J-1502D01*
G01X471467Y203474D01*
X471508Y203400D01*
X471815Y203168D01*
X471896Y203149D01*
X471939Y203157D01*
G02X472226Y203185I289J-1474D01*
G02X473728Y201683I0J-1502D01*
G02X473243Y200577I-1502J-1D01*
G03X473178Y200430I135J-148D01*
G01Y200136D01*
G03X473243Y199989I200J1D01*
G02X473728Y198883I-1017J-1105D01*
G02X470724I-1502J0D01*
G02X471209Y199989I1502J1D01*
G03X471274Y200136I-135J148D01*
G01Y200430D01*
G03X471209Y200577I-200J-1D01*
G02X470729Y201559I1017J1105D01*
G01X470726Y201602D01*
X470685Y201676D01*
X470378Y201908D01*
X470297Y201927D01*
X470254Y201919D01*
G02X469967Y201891I-289J1474D01*
G02X468980Y202261I0J1501D01*
G01X468952Y202285D01*
X468885Y202310D01*
G37*
G36*
G01X471189Y196259D02*
X471525D01*
X471592Y196284D01*
X471620Y196308D01*
G02X472607Y196678I987J-1131D01*
G02X473713Y196193I1J-1502D01*
G03X473860Y196128I148J135D01*
G01X474154D01*
G03X474301Y196193I-1J200D01*
G02X475407Y196678I1105J-1017D01*
G02Y193674I0J-1502D01*
G02X474301Y194159I-1J1502D01*
G03X474154Y194224I-148J-135D01*
G01X473860D01*
G03X473713Y194159I1J-200D01*
G02X472607Y193674I-1105J1017D01*
G02X471620Y194044I0J1501D01*
G01X471592Y194068D01*
X471525Y194093D01*
X471189D01*
X471122Y194068D01*
X471094Y194044D01*
G02X469120I-987J1131D01*
G01X469092Y194068D01*
X469025Y194093D01*
X468689D01*
X468622Y194068D01*
X468594Y194044D01*
G02X467607Y193674I-987J1131D01*
G02Y196678I0J1502D01*
G02X468594Y196308I0J-1501D01*
G01X468622Y196284D01*
X468689Y196259D01*
X469025D01*
X469092Y196284D01*
X469120Y196308D01*
G02X471094I987J-1131D01*
G01X471122Y196284D01*
X471189Y196259D01*
G37*
G36*
G01X486024Y137670D02*
X486340Y137881D01*
X486385Y137950D01*
X486392Y137992D01*
G02X487875Y139259I1483J-234D01*
G02Y136255I0J-1502D01*
G02X487607Y136279I-1J1502D01*
G03X487441Y136234I-36J-197D01*
G01X487345Y136151D01*
G03X487276Y135991I131J-151D01*
G02X487278Y135915I-1801J-85D01*
G01Y132515D01*
G02X487276Y132436I-1803J6D01*
G03X487345Y132276I200J-9D01*
G01X487441Y132193D01*
G03X487607Y132148I130J152D01*
G02X487875Y132172I267J-1478D01*
G02X488862Y131802I0J-1501D01*
G01X488890Y131778D01*
X488957Y131753D01*
X489293D01*
X489360Y131778D01*
X489388Y131802D01*
G02X490375Y132172I987J-1131D01*
G02X491858Y130905I0J-1501D01*
G01X491865Y130863D01*
X491910Y130794D01*
X492226Y130583D01*
X492307Y130569D01*
X492348Y130579D01*
G02X492775Y130630I426J-1751D01*
G02X493123Y130597I5J-1802D01*
G01X493163Y130589D01*
X493241Y130605D01*
X493545Y130814D01*
X493587Y130881D01*
X493594Y130922D01*
G02X495075Y132172I1481J-252D01*
G02Y129168I0J-1502D01*
G02X494894Y129179I0J1502D01*
G03X494736Y129128I-23J-199D01*
G01X494642Y129043D01*
G03X494576Y128888I134J-149D01*
G02X494578Y128828I-1800J-90D01*
G01Y125428D01*
G02X494576Y125365I-1802J26D01*
G03X494642Y125210I200J-6D01*
G01X494736Y125125D01*
G03X494894Y125074I135J148D01*
G02X495075Y125085I181J-1491D01*
G02Y122081I0J-1502D01*
G02X493594Y123333I0J1502D01*
G01X493587Y123374D01*
X493544Y123441D01*
X493241Y123651D01*
X493163Y123667D01*
X493122Y123659D01*
G02X492775Y123626I-343J1769D01*
G02X492349Y123677I0J1802D01*
G01X492307Y123687D01*
X492226Y123672D01*
X491910Y123462D01*
X491865Y123392D01*
X491859Y123350D01*
G02X490375Y122081I-1484J233D01*
G02X489387Y122451I-1J1502D01*
G01X489360Y122476D01*
X489293Y122501D01*
X488956D01*
X488890Y122476D01*
X488862Y122452D01*
G02X487875Y122082I-987J1131D01*
G02X487607Y122106I-1J1502D01*
G03X487441Y122061I-36J-197D01*
G01X487345Y121978D01*
G03X487276Y121818I131J-151D01*
G02X487278Y121742I-1801J-85D01*
G01Y118342D01*
G02X487276Y118263I-1803J6D01*
G03X487345Y118103I200J-9D01*
G01X487441Y118020D01*
G03X487607Y117975I130J152D01*
G02X487875Y117999I267J-1478D01*
G02X488862Y117629I0J-1501D01*
G01X488890Y117605D01*
X488957Y117580D01*
X489293D01*
X489360Y117605D01*
X489388Y117629D01*
G02X490375Y117999I987J-1131D01*
G02X491858Y116732I0J-1501D01*
G01X491865Y116690D01*
X491910Y116621D01*
X492226Y116410D01*
X492307Y116396D01*
X492348Y116406D01*
G02X492775Y116458I430J-1751D01*
G02X493123Y116424I0J-1803D01*
G01X493163Y116416D01*
X493241Y116432D01*
X493545Y116641D01*
X493587Y116708D01*
X493594Y116749D01*
G02X495075Y117998I1481J-254D01*
G02Y114994I0J-1502D01*
G02X494894Y115005I0J1502D01*
G03X494736Y114954I-23J-199D01*
G01X494642Y114869D01*
G03X494577Y114714I135J-148D01*
G02X494578Y114655I-1802J-60D01*
G01Y111255D01*
G02X494576Y111192I-1802J26D01*
G03X494642Y111037I200J-6D01*
G01X494736Y110952D01*
G03X494894Y110901I135J148D01*
G02X495075Y110912I181J-1491D01*
G02Y107908I0J-1502D01*
G02X493594Y109160I0J1502D01*
G01X493587Y109201D01*
X493544Y109268D01*
X493241Y109478D01*
X493163Y109494D01*
X493122Y109486D01*
G02X492775Y109452I-348J1769D01*
G02X492349Y109504I4J1803D01*
G01X492307Y109514D01*
X492226Y109499D01*
X491910Y109289D01*
X491865Y109219D01*
X491859Y109177D01*
G02X490375Y107908I-1484J233D01*
G02Y110912I0J1502D01*
G02X490643Y110888I1J-1502D01*
G03X490809Y110933I36J197D01*
G01X490905Y111016D01*
G03X490974Y111176I-131J151D01*
G02X490972Y111255I1801J85D01*
G01Y114655D01*
G02X490974Y114731I1803J-9D01*
G03X490905Y114891I-200J9D01*
G01X490809Y114974D01*
G03X490643Y115019I-130J-152D01*
G02X490375Y114995I-267J1478D01*
G02X489388Y115365I0J1501D01*
G01X489360Y115389D01*
X489293Y115414D01*
X488957D01*
X488890Y115389D01*
X488862Y115365D01*
G02X487875Y114995I-987J1131D01*
G02X486391Y116264I0J1502D01*
G01X486385Y116306D01*
X486340Y116376D01*
X486024Y116586D01*
X485943Y116601D01*
X485901Y116591D01*
G02X485475Y116540I-426J1751D01*
G02X485049Y116591I0J1802D01*
G01X485007Y116601D01*
X484926Y116586D01*
X484610Y116376D01*
X484565Y116306D01*
X484559Y116264D01*
G02X483075Y114995I-1484J233D01*
G02Y117999I0J1502D01*
G02X483343Y117975I1J-1502D01*
G03X483509Y118020I36J197D01*
G01X483605Y118103D01*
G03X483674Y118263I-131J151D01*
G02X483672Y118342I1801J85D01*
G01Y121742D01*
G02X483674Y121818I1803J-9D01*
G03X483605Y121978I-200J9D01*
G01X483509Y122061D01*
G03X483343Y122106I-130J-152D01*
G02X483075Y122082I-267J1478D01*
G02Y125086I0J1502D01*
G02X484558Y123819I0J-1501D01*
G01X484565Y123777D01*
X484610Y123708D01*
X484926Y123497D01*
X485007Y123483D01*
X485048Y123493D01*
G02X485475Y123544I426J-1751D01*
G02X485902Y123493I1J-1802D01*
G01X485943Y123483D01*
X486024Y123497D01*
X486340Y123708D01*
X486385Y123777D01*
X486392Y123819D01*
G02X487875Y125086I1483J-234D01*
G02X488863Y124716I1J-1502D01*
G01X488890Y124691D01*
X488957Y124666D01*
X489294D01*
X489360Y124691D01*
X489388Y124715D01*
G02X490375Y125085I987J-1131D01*
G02X490643Y125061I1J-1502D01*
G03X490809Y125106I36J197D01*
G01X490905Y125189D01*
G03X490974Y125349I-131J151D01*
G02X490972Y125428I1801J85D01*
G01Y128828D01*
G02X490974Y128904I1803J-9D01*
G03X490905Y129064I-200J9D01*
G01X490809Y129147D01*
G03X490643Y129192I-130J-152D01*
G02X490375Y129168I-267J1478D01*
G02X489388Y129538I0J1501D01*
G01X489360Y129562D01*
X489293Y129587D01*
X488957D01*
X488890Y129562D01*
X488862Y129538D01*
G02X487875Y129168I-987J1131D01*
G02X486391Y130437I0J1502D01*
G01X486385Y130479D01*
X486340Y130549D01*
X486024Y130759D01*
X485943Y130774D01*
X485901Y130764D01*
G02X485475Y130712I-430J1751D01*
G02X485049Y130764I4J1803D01*
G01X485007Y130774D01*
X484926Y130759D01*
X484610Y130549D01*
X484565Y130479D01*
X484559Y130437D01*
G02X483075Y129168I-1484J233D01*
G02Y132172I0J1502D01*
G02X483343Y132148I1J-1502D01*
G03X483509Y132193I36J197D01*
G01X483605Y132276D01*
G03X483674Y132436I-131J151D01*
G02X483672Y132515I1801J85D01*
G01Y135915D01*
G02X483674Y135991I1803J-9D01*
G03X483605Y136151I-200J9D01*
G01X483509Y136234D01*
G03X483343Y136279I-130J-152D01*
G02X483075Y136255I-267J1478D01*
G02Y139259I0J1502D01*
G02X484558Y137992I0J-1501D01*
G01X484565Y137950D01*
X484610Y137881D01*
X484926Y137670D01*
X485007Y137656D01*
X485048Y137666D01*
G02X485475Y137718I430J-1751D01*
G02X485902Y137666I-3J-1803D01*
G01X485943Y137656D01*
X486024Y137670D01*
G37*
G36*
G01X502495Y84108D02*
Y84460D01*
X502467Y84529D01*
X502441Y84557D01*
G02X502035Y85584I1096J1027D01*
G02X505039I1502J0D01*
G02X504633Y84557I-1502J0D01*
G01X504607Y84529D01*
X504579Y84460D01*
Y84108D01*
X504607Y84039D01*
X504633Y84011D01*
G02Y81957I-1096J-1027D01*
G01X504607Y81929D01*
X504579Y81860D01*
Y81508D01*
X504607Y81439D01*
X504633Y81411D01*
G02Y79357I-1096J-1027D01*
G01X504607Y79329D01*
X504579Y79260D01*
Y78908D01*
X504607Y78839D01*
X504633Y78811D01*
G02Y76757I-1096J-1027D01*
G01X504607Y76729D01*
X504579Y76660D01*
Y76308D01*
X504607Y76239D01*
X504633Y76211D01*
G02X505039Y75184I-1096J-1027D01*
G02X502035I-1502J0D01*
G02X502441Y76211I1502J0D01*
G01X502467Y76239D01*
X502495Y76308D01*
Y76660D01*
X502467Y76729D01*
X502441Y76757D01*
G02Y78811I1096J1027D01*
G01X502467Y78839D01*
X502495Y78908D01*
Y79260D01*
X502467Y79329D01*
X502441Y79357D01*
G02Y81411I1096J1027D01*
G01X502467Y81439D01*
X502495Y81508D01*
Y81860D01*
X502467Y81929D01*
X502441Y81957D01*
G02Y84011I1096J1027D01*
G01X502467Y84039D01*
X502495Y84108D01*
G37*
G36*
G01X520830Y83717D02*
Y84069D01*
X520802Y84138D01*
X520776Y84166D01*
G02X520370Y85193I1096J1027D01*
G02X523374I1502J0D01*
G02X522968Y84166I-1502J0D01*
G01X522942Y84138D01*
X522914Y84069D01*
Y83717D01*
X522942Y83648D01*
X522968Y83620D01*
G02Y81566I-1096J-1027D01*
G01X522942Y81538D01*
X522914Y81469D01*
Y81117D01*
X522942Y81048D01*
X522968Y81020D01*
G02Y78966I-1096J-1027D01*
G01X522942Y78938D01*
X522914Y78869D01*
Y78517D01*
X522942Y78448D01*
X522968Y78420D01*
G02Y76366I-1096J-1027D01*
G01X522942Y76338D01*
X522914Y76269D01*
Y75917D01*
X522942Y75848D01*
X522968Y75820D01*
G02X523374Y74793I-1096J-1027D01*
G02X520370I-1502J0D01*
G02X520776Y75820I1502J0D01*
G01X520802Y75848D01*
X520830Y75917D01*
Y76269D01*
X520802Y76338D01*
X520776Y76366D01*
G02Y78420I1096J1027D01*
G01X520802Y78448D01*
X520830Y78517D01*
Y78869D01*
X520802Y78938D01*
X520776Y78966D01*
G02Y81020I1096J1027D01*
G01X520802Y81048D01*
X520830Y81117D01*
Y81469D01*
X520802Y81538D01*
X520776Y81566D01*
G02Y83620I1096J1027D01*
G01X520802Y83648D01*
X520830Y83717D01*
G37*
G36*
G01X545259Y75446D02*
X544887Y75386D01*
X544818Y75341D01*
X544794Y75306D01*
G02X543545Y74638I-1249J834D01*
G02Y77642I0J1502D01*
G02X544466Y77327I1J-1502D01*
G01X544499Y77301D01*
X544579Y77281D01*
X544951Y77341D01*
X545020Y77386D01*
X545044Y77421D01*
G02X546293Y78089I1249J-834D01*
G02Y75085I0J-1502D01*
G02X545372Y75400I-1J1502D01*
G01X545339Y75426D01*
X545259Y75446D01*
G37*
G36*
G01X477115Y236121D02*
G02X480119I1502J0D01*
G02X479469Y234884I-1502J0D01*
G03X479475Y234222I227J-329D01*
G02X480145Y232971I-833J-1251D01*
G02X477141I-1502J0D01*
G02X477791Y234208I1502J0D01*
G03X477785Y234870I-227J329D01*
G02X477115Y236121I833J1251D01*
G37*
G36*
G01X475157Y221970D02*
G02X478161I1502J0D01*
G02X477791Y220983I-1501J0D01*
G01X477767Y220955D01*
X477742Y220888D01*
Y220552D01*
X477767Y220485D01*
X477791Y220457D01*
G02Y218483I-1131J-987D01*
G01X477767Y218455D01*
X477742Y218388D01*
Y218052D01*
X477767Y217985D01*
X477791Y217957D01*
G02X478161Y216970I-1131J-987D01*
G02X476659Y215468I-1502J0D01*
G02X475804Y215735I0J1502D01*
G01X475770Y215759D01*
X475689Y215775D01*
X475322Y215696D01*
X475255Y215648D01*
X475234Y215612D01*
G02X473946Y214883I-1288J773D01*
G02Y217887I0J1502D01*
G02X474801Y217620I0J-1502D01*
G01X474835Y217596D01*
X474916Y217580D01*
X475283Y217659D01*
X475350Y217707D01*
X475371Y217743D01*
G02X475527Y217957I1287J-774D01*
G01X475551Y217985D01*
X475576Y218052D01*
Y218388D01*
X475551Y218455D01*
X475527Y218483D01*
G02Y220457I1131J987D01*
G01X475551Y220485D01*
X475576Y220552D01*
Y220888D01*
X475551Y220955D01*
X475527Y220983D01*
G02X475157Y221970I1131J987D01*
G37*
G36*
G01X532855Y223294D02*
Y223630D01*
X532830Y223697D01*
X532806Y223725D01*
G02X532436Y224712I1131J987D01*
G02X535440I1502J0D01*
G02X535070Y223725I-1501J0D01*
G01X535046Y223697D01*
X535021Y223630D01*
Y223294D01*
X535046Y223227D01*
X535070Y223199D01*
G02X535440Y222212I-1131J-987D01*
G02X532436I-1502J0D01*
G02X532806Y223199I1501J0D01*
G01X532830Y223227D01*
X532855Y223294D01*
G37*
G36*
G01X527530Y225189D02*
X527236D01*
G03X527089Y225124I1J-200D01*
G02X525983Y224639I-1105J1017D01*
G02Y227643I0J1502D01*
G02X527089Y227158I1J-1502D01*
G03X527236Y227093I148J135D01*
G01X527530D01*
G03X527677Y227158I-1J200D01*
G02X528783Y227643I1105J-1017D01*
G02Y224639I0J-1502D01*
G02X527677Y225124I-1J1502D01*
G03X527530Y225189I-148J-135D01*
G37*
G36*
G01X510737Y229808D02*
Y230144D01*
X510712Y230211D01*
X510688Y230239D01*
G02X510318Y231226I1131J987D01*
G02X513322I1502J0D01*
G02X512952Y230239I-1501J0D01*
G01X512928Y230211D01*
X512903Y230144D01*
Y229808D01*
X512928Y229741D01*
X512952Y229713D01*
G02Y227739I-1131J-987D01*
G01X512928Y227711D01*
X512903Y227644D01*
Y227308D01*
X512928Y227241D01*
X512952Y227213D01*
G02Y225239I-1131J-987D01*
G01X512928Y225211D01*
X512903Y225144D01*
Y224808D01*
X512928Y224741D01*
X512952Y224713D01*
G02X513322Y223726I-1131J-987D01*
G02X510318I-1502J0D01*
G02X510688Y224713I1501J0D01*
G01X510712Y224741D01*
X510737Y224808D01*
Y225144D01*
X510712Y225211D01*
X510688Y225239D01*
G02Y227213I1131J987D01*
G01X510712Y227241D01*
X510737Y227308D01*
Y227644D01*
X510712Y227711D01*
X510688Y227739D01*
G02Y229713I1131J987D01*
G01X510712Y229741D01*
X510737Y229808D01*
G37*
G36*
G01X521193Y230043D02*
Y230379D01*
X521168Y230446D01*
X521144Y230474D01*
G02X520774Y231461I1131J987D01*
G02X523778I1502J0D01*
G02X523408Y230474I-1501J0D01*
G01X523384Y230446D01*
X523359Y230379D01*
Y230043D01*
X523384Y229976D01*
X523408Y229948D01*
G02Y227974I-1131J-987D01*
G01X523384Y227946D01*
X523359Y227879D01*
Y227543D01*
X523384Y227476D01*
X523408Y227448D01*
G02X523778Y226461I-1131J-987D01*
G02X523293Y225355I-1502J-1D01*
G03X523228Y225208I135J-148D01*
G01Y224914D01*
G03X523293Y224767I200J1D01*
G02X523778Y223661I-1017J-1105D01*
G02X520774I-1502J0D01*
G02X521259Y224767I1502J1D01*
G03X521324Y224914I-135J148D01*
G01Y225208D01*
G03X521259Y225355I-200J-1D01*
G02X520774Y226461I1017J1105D01*
G02X521144Y227448I1501J0D01*
G01X521168Y227476D01*
X521193Y227543D01*
Y227879D01*
X521168Y227946D01*
X521144Y227974D01*
G02Y229948I1131J987D01*
G01X521168Y229976D01*
X521193Y230043D01*
G37*
G36*
G01X529162Y230368D02*
Y230704D01*
X529137Y230771D01*
X529113Y230799D01*
G02X528743Y231786I1131J987D01*
G02X531747I1502J0D01*
G02X531377Y230799I-1501J0D01*
G01X531353Y230771D01*
X531328Y230704D01*
Y230368D01*
X531353Y230301D01*
X531377Y230273D01*
G02X531747Y229286I-1131J-987D01*
G02X528743I-1502J0D01*
G02X529113Y230273I1501J0D01*
G01X529137Y230301D01*
X529162Y230368D01*
G37*
G36*
G01X527308Y237694D02*
X527644D01*
X527711Y237719D01*
X527739Y237743D01*
G02X529713I987J-1131D01*
G01X529741Y237719D01*
X529808Y237694D01*
X530144D01*
X530211Y237719D01*
X530239Y237743D01*
G02X531226Y238113I987J-1131D01*
G02Y235109I0J-1502D01*
G02X530239Y235479I0J1501D01*
G01X530211Y235503D01*
X530144Y235528D01*
X529808D01*
X529741Y235503D01*
X529713Y235479D01*
G02X527739I-987J1131D01*
G01X527711Y235503D01*
X527644Y235528D01*
X527308D01*
X527241Y235503D01*
X527213Y235479D01*
G02X526226Y235109I-987J1131D01*
G02Y238113I0J1502D01*
G02X527213Y237743I0J-1501D01*
G01X527241Y237719D01*
X527308Y237694D01*
G37*
G36*
G01X527010Y249974D02*
X527346D01*
X527413Y249999D01*
X527441Y250023D01*
G02X529415I987J-1131D01*
G01X529443Y249999D01*
X529510Y249974D01*
X529846D01*
X529913Y249999D01*
X529941Y250023D01*
G02X530928Y250393I987J-1131D01*
G02Y247389I0J-1502D01*
G02X529941Y247759I0J1501D01*
G01X529913Y247783D01*
X529846Y247808D01*
X529510D01*
X529443Y247783D01*
X529415Y247759D01*
G02X527441I-987J1131D01*
G01X527413Y247783D01*
X527346Y247808D01*
X527010D01*
X526943Y247783D01*
X526915Y247759D01*
G02X525928Y247389I-987J1131D01*
G02Y250393I0J1502D01*
G02X526915Y250023I0J-1501D01*
G01X526943Y249999D01*
X527010Y249974D01*
G37*
G36*
G01X531305Y190705D02*
G02X530657Y191941I855J1236D01*
G02X533661I1502J0D01*
G02X532908Y190639I-1502J0D01*
G03X532880Y189963I199J-347D01*
G02X533528Y188727I-855J-1236D01*
G02X530524I-1502J0D01*
G02X531277Y190029I1502J0D01*
G03X531305Y190705I-199J347D01*
G37*
G36*
G01X555348Y185330D02*
X555483Y185710D01*
X555473Y185800D01*
X555449Y185839D01*
G02X555224Y186629I1277J791D01*
G02X558228I1502J0D01*
G02X557225Y185212I-1502J0D01*
G01X557181Y185197D01*
X557118Y185133D01*
X556983Y184753D01*
X556993Y184663D01*
X557017Y184624D01*
G02X557242Y183834I-1277J-791D01*
G02X554238I-1502J0D01*
G02X555241Y185251I1502J0D01*
G01X555285Y185266D01*
X555348Y185330D01*
G37*
G36*
G01X581170Y147959D02*
X581149Y147998D01*
G02X580966Y148717I1319J719D01*
G02X583970I1502J0D01*
G02X582965Y147300I-1501J0D01*
G01X582923Y147285D01*
X582860Y147224D01*
X582719Y146857D01*
X582725Y146770D01*
X582746Y146731D01*
G02X582929Y146012I-1319J-719D01*
G02X582269Y144768I-1502J0D01*
G03X582181Y144603I112J-166D01*
G01Y144271D01*
G03X582269Y144106I200J1D01*
G02X582914Y143074I-842J-1244D01*
G01X582919Y143037D01*
X582953Y142974D01*
X583211Y142754D01*
X583277Y142729D01*
X583315Y142730D01*
X583333D01*
G02Y139726I0J-1502D01*
G02X581846Y141016I0J1502D01*
G01X581841Y141053D01*
X581807Y141116D01*
X581549Y141336D01*
X581483Y141361D01*
X581445Y141360D01*
X581427D01*
G02X579925Y142862I0J1502D01*
G02X580585Y144106I1502J0D01*
G03X580673Y144271I-112J166D01*
G01Y144603D01*
G03X580585Y144768I-200J-1D01*
G02X579925Y146012I842J1244D01*
G02X580930Y147429I1501J0D01*
G01X580972Y147444D01*
X581035Y147505D01*
X581176Y147872D01*
X581170Y147959D01*
G37*
G36*
G01X581028Y110018D02*
X581344D01*
G03X581501Y110095I-1J200D01*
G02X582686Y110674I1185J-923D01*
G02X584188Y109172I0J-1502D01*
G02X583224Y107770I-1502J0D01*
G01X583184Y107754D01*
X583124Y107693D01*
X582989Y107331D01*
X582995Y107245D01*
X583016Y107207D01*
G02X583195Y106495I-1323J-711D01*
G02X580191I-1502J0D01*
G02X580329Y107123I1502J-1D01*
G01X580352Y107173D01*
X580340Y107283D01*
X580063Y107653D01*
X579961Y107694D01*
X579907Y107686D01*
G02X579686Y107670I-219J1486D01*
G02Y110674I0J1502D01*
G02X580871Y110095I0J-1502D01*
G03X581028Y110018I158J123D01*
G37*
G36*
G01X593795Y105329D02*
X593755Y105360D01*
G02X593154Y106561I901J1202D01*
G02X596158I1502J0D01*
G02X595432Y105275I-1502J0D01*
G01X595389Y105249D01*
X595338Y105164D01*
X595316Y104732D01*
X595358Y104643D01*
X595398Y104612D01*
G02X595953Y103779I-901J-1202D01*
G01X595965Y103731D01*
X596031Y103658D01*
X596434Y103509D01*
X596530Y103522D01*
X596571Y103550D01*
G02X597437Y103825I866J-1226D01*
G02Y100821I0J-1502D01*
G02X595981Y101955I0J1502D01*
G01X595969Y102003D01*
X595903Y102076D01*
X595500Y102225D01*
X595404Y102212D01*
X595363Y102184D01*
G02X594497Y101909I-866J1226D01*
G02X592995Y103411I0J1502D01*
G02X593721Y104697I1502J0D01*
G01X593764Y104723D01*
X593815Y104808D01*
X593837Y105240D01*
X593795Y105329D01*
G37*
G36*
G01X650066Y102731D02*
G02X649774Y103621I1210J890D01*
G02X652778I1502J0D01*
G02X651553Y102145I-1502J0D01*
G03X651304Y101515I73J-393D01*
G02X651596Y100625I-1210J-890D01*
G02X648592I-1502J0D01*
G02X649817Y102101I1502J0D01*
G03X650066Y102731I-73J393D01*
G37*
G36*
G01X614494Y101849D02*
G02X613911Y103037I919J1188D01*
G02X616915I1502J0D01*
G02X616259Y101796I-1502J0D01*
G03X616239Y101149I225J-331D01*
G02X616822Y99961I-919J-1188D01*
G02X613818I-1502J0D01*
G02X614474Y101202I1502J0D01*
G03X614494Y101849I-225J331D01*
G37*
G36*
G01X609007Y91453D02*
G02X608453Y91347I-554J1395D01*
G02X609955Y92849I0J1502D01*
G02X609909Y92481I-1502J1D01*
G03X610445Y92011I388J-98D01*
G02X610999Y92117I554J-1395D01*
G02X609497Y90615I0J-1502D01*
G02X609543Y90983I1502J-1D01*
G03X609007Y91453I-388J98D01*
G37*
G36*
G01X659846Y90701D02*
G02X659176Y91951I831J1250D01*
G02X662180I1502J0D01*
G02X661530Y90714I-1502J0D01*
G03X661535Y90051I227J-330D01*
G02X662205Y88801I-831J-1250D01*
G02X659201I-1502J0D01*
G02X659851Y90038I1502J0D01*
G03X659846Y90701I-227J330D01*
G37*
G36*
G01X571255Y217133D02*
X570961D01*
G03X570814Y217068I1J-200D01*
G02X569708Y216583I-1105J1017D01*
G02Y219587I0J1502D01*
G02X570814Y219102I1J-1502D01*
G03X570961Y219037I148J135D01*
G01X571255D01*
G03X571402Y219102I-1J200D01*
G02X572508Y219587I1105J-1017D01*
G02Y216583I0J-1502D01*
G02X571402Y217068I-1J1502D01*
G03X571255Y217133I-148J-135D01*
G37*
G36*
G01X577435Y205755D02*
X577099D01*
X577032Y205730D01*
X577004Y205706D01*
G02X576017Y205336I-987J1131D01*
G02Y208340I0J1502D01*
G02X577004Y207970I0J-1501D01*
G01X577032Y207946D01*
X577099Y207921D01*
X577435D01*
X577502Y207946D01*
X577530Y207970D01*
G02X578517Y208340I987J-1131D01*
G02Y205336I0J-1502D01*
G02X577530Y205706I0J1501D01*
G01X577502Y205730D01*
X577435Y205755D01*
G37*
G36*
G01X571247Y202310D02*
X570911D01*
X570844Y202285D01*
X570816Y202261D01*
G02X569829Y201891I-987J1131D01*
G02Y204895I0J1502D01*
G02X570816Y204525I0J-1501D01*
G01X570844Y204501D01*
X570911Y204476D01*
X571247D01*
X571314Y204501D01*
X571342Y204525D01*
G02X572329Y204895I987J-1131D01*
G02X573826Y203517I0J-1502D01*
G01X573829Y203474D01*
X573870Y203400D01*
X574177Y203168D01*
X574258Y203149D01*
X574301Y203157D01*
G02X574588Y203185I289J-1474D01*
G02X576090Y201683I0J-1502D01*
G02X575605Y200577I-1502J-1D01*
G03X575540Y200430I135J-148D01*
G01Y200136D01*
G03X575605Y199989I200J1D01*
G02X576090Y198883I-1017J-1105D01*
G02X573086I-1502J0D01*
G02X573571Y199989I1502J1D01*
G03X573636Y200136I-135J148D01*
G01Y200430D01*
G03X573571Y200577I-200J-1D01*
G02X573091Y201559I1017J1105D01*
G01X573088Y201602D01*
X573047Y201676D01*
X572740Y201908D01*
X572659Y201927D01*
X572616Y201919D01*
G02X572329Y201891I-289J1474D01*
G02X571342Y202261I0J1501D01*
G01X571314Y202285D01*
X571247Y202310D01*
G37*
G36*
G01X573551Y196259D02*
X573887D01*
X573954Y196284D01*
X573982Y196308D01*
G02X574969Y196678I987J-1131D01*
G02X576075Y196193I1J-1502D01*
G03X576222Y196128I148J135D01*
G01X576516D01*
G03X576663Y196193I-1J200D01*
G02X577769Y196678I1105J-1017D01*
G02Y193674I0J-1502D01*
G02X576663Y194159I-1J1502D01*
G03X576516Y194224I-148J-135D01*
G01X576222D01*
G03X576075Y194159I1J-200D01*
G02X574969Y193674I-1105J1017D01*
G02X573982Y194044I0J1501D01*
G01X573954Y194068D01*
X573887Y194093D01*
X573551D01*
X573484Y194068D01*
X573456Y194044D01*
G02X571482I-987J1131D01*
G01X571454Y194068D01*
X571387Y194093D01*
X571051D01*
X570984Y194068D01*
X570956Y194044D01*
G02X569969Y193674I-987J1131D01*
G02Y196678I0J1502D01*
G02X570956Y196308I0J-1501D01*
G01X570984Y196284D01*
X571051Y196259D01*
X571387D01*
X571454Y196284D01*
X571482Y196308D01*
G02X573456I987J-1131D01*
G01X573484Y196284D01*
X573551Y196259D01*
G37*
G36*
G01X588386Y137670D02*
X588702Y137881D01*
X588747Y137950D01*
X588754Y137992D01*
G02X590237Y139259I1483J-234D01*
G02Y136255I0J-1502D01*
G02X589969Y136279I-1J1502D01*
G03X589803Y136234I-36J-197D01*
G01X589707Y136151D01*
G03X589638Y135991I131J-151D01*
G02X589640Y135915I-1801J-85D01*
G01Y132515D01*
G02X589638Y132436I-1803J6D01*
G03X589707Y132276I200J-9D01*
G01X589803Y132193D01*
G03X589969Y132148I130J152D01*
G02X590237Y132172I267J-1478D01*
G02X591224Y131802I0J-1501D01*
G01X591252Y131778D01*
X591319Y131753D01*
X591655D01*
X591722Y131778D01*
X591750Y131802D01*
G02X592737Y132172I987J-1131D01*
G02X594220Y130905I0J-1501D01*
G01X594227Y130863D01*
X594272Y130794D01*
X594588Y130583D01*
X594669Y130569D01*
X594710Y130579D01*
G02X595137Y130630I426J-1751D01*
G02X595485Y130597I5J-1802D01*
G01X595525Y130589D01*
X595603Y130605D01*
X595907Y130814D01*
X595949Y130881D01*
X595956Y130922D01*
G02X597437Y132172I1481J-252D01*
G02Y129168I0J-1502D01*
G02X597256Y129179I0J1502D01*
G03X597098Y129128I-23J-199D01*
G01X597004Y129043D01*
G03X596938Y128888I134J-149D01*
G02X596940Y128828I-1800J-90D01*
G01Y125428D01*
G02X596938Y125365I-1802J26D01*
G03X597004Y125210I200J-6D01*
G01X597098Y125125D01*
G03X597256Y125074I135J148D01*
G02X597437Y125085I181J-1491D01*
G02Y122081I0J-1502D01*
G02X595956Y123333I0J1502D01*
G01X595949Y123374D01*
X595906Y123441D01*
X595603Y123651D01*
X595525Y123667D01*
X595484Y123659D01*
G02X595137Y123626I-343J1769D01*
G02X594711Y123677I0J1802D01*
G01X594669Y123687D01*
X594588Y123672D01*
X594272Y123462D01*
X594227Y123392D01*
X594221Y123350D01*
G02X592737Y122081I-1484J233D01*
G02X591749Y122451I-1J1502D01*
G01X591722Y122476D01*
X591655Y122501D01*
X591318D01*
X591252Y122476D01*
X591224Y122452D01*
G02X590237Y122082I-987J1131D01*
G02X589969Y122106I-1J1502D01*
G03X589803Y122061I-36J-197D01*
G01X589707Y121978D01*
G03X589638Y121818I131J-151D01*
G02X589640Y121742I-1801J-85D01*
G01Y118342D01*
G02X589638Y118263I-1803J6D01*
G03X589707Y118103I200J-9D01*
G01X589803Y118020D01*
G03X589969Y117975I130J152D01*
G02X590237Y117999I267J-1478D01*
G02X591224Y117629I0J-1501D01*
G01X591252Y117605D01*
X591319Y117580D01*
X591655D01*
X591722Y117605D01*
X591750Y117629D01*
G02X592737Y117999I987J-1131D01*
G02X594220Y116732I0J-1501D01*
G01X594227Y116690D01*
X594272Y116621D01*
X594588Y116410D01*
X594669Y116396D01*
X594710Y116406D01*
G02X595137Y116458I430J-1751D01*
G02X595485Y116424I0J-1803D01*
G01X595525Y116416D01*
X595603Y116432D01*
X595907Y116641D01*
X595949Y116708D01*
X595956Y116749D01*
G02X597437Y117998I1481J-254D01*
G02Y114994I0J-1502D01*
G02X597256Y115005I0J1502D01*
G03X597098Y114954I-23J-199D01*
G01X597004Y114869D01*
G03X596939Y114714I135J-148D01*
G02X596940Y114655I-1802J-60D01*
G01Y111255D01*
G02X596938Y111192I-1802J26D01*
G03X597004Y111037I200J-6D01*
G01X597098Y110952D01*
G03X597256Y110901I135J148D01*
G02X597437Y110912I181J-1491D01*
G02Y107908I0J-1502D01*
G02X595956Y109160I0J1502D01*
G01X595949Y109201D01*
X595906Y109268D01*
X595603Y109478D01*
X595525Y109494D01*
X595484Y109486D01*
G02X595137Y109452I-348J1769D01*
G02X594711Y109504I4J1803D01*
G01X594669Y109514D01*
X594588Y109499D01*
X594272Y109289D01*
X594227Y109219D01*
X594221Y109177D01*
G02X592737Y107908I-1484J233D01*
G02Y110912I0J1502D01*
G02X593005Y110888I1J-1502D01*
G03X593171Y110933I36J197D01*
G01X593267Y111016D01*
G03X593336Y111176I-131J151D01*
G02X593334Y111255I1801J85D01*
G01Y114655D01*
G02X593336Y114731I1803J-9D01*
G03X593267Y114891I-200J9D01*
G01X593171Y114974D01*
G03X593005Y115019I-130J-152D01*
G02X592737Y114995I-267J1478D01*
G02X591750Y115365I0J1501D01*
G01X591722Y115389D01*
X591655Y115414D01*
X591319D01*
X591252Y115389D01*
X591224Y115365D01*
G02X590237Y114995I-987J1131D01*
G02X588753Y116264I0J1502D01*
G01X588747Y116306D01*
X588702Y116376D01*
X588386Y116586D01*
X588305Y116601D01*
X588263Y116591D01*
G02X587837Y116540I-426J1751D01*
G02X587411Y116591I0J1802D01*
G01X587369Y116601D01*
X587288Y116586D01*
X586972Y116376D01*
X586927Y116306D01*
X586921Y116264D01*
G02X585437Y114995I-1484J233D01*
G02Y117999I0J1502D01*
G02X585705Y117975I1J-1502D01*
G03X585871Y118020I36J197D01*
G01X585967Y118103D01*
G03X586036Y118263I-131J151D01*
G02X586034Y118342I1801J85D01*
G01Y121742D01*
G02X586036Y121818I1803J-9D01*
G03X585967Y121978I-200J9D01*
G01X585871Y122061D01*
G03X585705Y122106I-130J-152D01*
G02X585437Y122082I-267J1478D01*
G02Y125086I0J1502D01*
G02X586920Y123819I0J-1501D01*
G01X586927Y123777D01*
X586972Y123708D01*
X587288Y123497D01*
X587369Y123483D01*
X587410Y123493D01*
G02X587837Y123544I426J-1751D01*
G02X588264Y123493I1J-1802D01*
G01X588305Y123483D01*
X588386Y123497D01*
X588702Y123708D01*
X588747Y123777D01*
X588754Y123819D01*
G02X590237Y125086I1483J-234D01*
G02X591225Y124716I1J-1502D01*
G01X591252Y124691D01*
X591319Y124666D01*
X591656D01*
X591722Y124691D01*
X591750Y124715D01*
G02X592737Y125085I987J-1131D01*
G02X593005Y125061I1J-1502D01*
G03X593171Y125106I36J197D01*
G01X593267Y125189D01*
G03X593336Y125349I-131J151D01*
G02X593334Y125428I1801J85D01*
G01Y128828D01*
G02X593336Y128904I1803J-9D01*
G03X593267Y129064I-200J9D01*
G01X593171Y129147D01*
G03X593005Y129192I-130J-152D01*
G02X592737Y129168I-267J1478D01*
G02X591750Y129538I0J1501D01*
G01X591722Y129562D01*
X591655Y129587D01*
X591319D01*
X591252Y129562D01*
X591224Y129538D01*
G02X590237Y129168I-987J1131D01*
G02X588753Y130437I0J1502D01*
G01X588747Y130479D01*
X588702Y130549D01*
X588386Y130759D01*
X588305Y130774D01*
X588263Y130764D01*
G02X587837Y130712I-430J1751D01*
G02X587411Y130764I4J1803D01*
G01X587369Y130774D01*
X587288Y130759D01*
X586972Y130549D01*
X586927Y130479D01*
X586921Y130437D01*
G02X585437Y129168I-1484J233D01*
G02Y132172I0J1502D01*
G02X585705Y132148I1J-1502D01*
G03X585871Y132193I36J197D01*
G01X585967Y132276D01*
G03X586036Y132436I-131J151D01*
G02X586034Y132515I1801J85D01*
G01Y135915D01*
G02X586036Y135991I1803J-9D01*
G03X585967Y136151I-200J9D01*
G01X585871Y136234D01*
G03X585705Y136279I-130J-152D01*
G02X585437Y136255I-267J1478D01*
G02Y139259I0J1502D01*
G02X586920Y137992I0J-1501D01*
G01X586927Y137950D01*
X586972Y137881D01*
X587288Y137670D01*
X587369Y137656D01*
X587410Y137666D01*
G02X587837Y137718I430J-1751D01*
G02X588264Y137666I-3J-1803D01*
G01X588305Y137656D01*
X588386Y137670D01*
G37*
G36*
G01X604857Y84108D02*
Y84460D01*
X604829Y84529D01*
X604803Y84557D01*
G02X604397Y85584I1096J1027D01*
G02X607401I1502J0D01*
G02X606995Y84557I-1502J0D01*
G01X606969Y84529D01*
X606941Y84460D01*
Y84108D01*
X606969Y84039D01*
X606995Y84011D01*
G02Y81957I-1096J-1027D01*
G01X606969Y81929D01*
X606941Y81860D01*
Y81508D01*
X606969Y81439D01*
X606995Y81411D01*
G02Y79357I-1096J-1027D01*
G01X606969Y79329D01*
X606941Y79260D01*
Y78908D01*
X606969Y78839D01*
X606995Y78811D01*
G02Y76757I-1096J-1027D01*
G01X606969Y76729D01*
X606941Y76660D01*
Y76308D01*
X606969Y76239D01*
X606995Y76211D01*
G02X607401Y75184I-1096J-1027D01*
G02X604397I-1502J0D01*
G02X604803Y76211I1502J0D01*
G01X604829Y76239D01*
X604857Y76308D01*
Y76660D01*
X604829Y76729D01*
X604803Y76757D01*
G02Y78811I1096J1027D01*
G01X604829Y78839D01*
X604857Y78908D01*
Y79260D01*
X604829Y79329D01*
X604803Y79357D01*
G02Y81411I1096J1027D01*
G01X604829Y81439D01*
X604857Y81508D01*
Y81860D01*
X604829Y81929D01*
X604803Y81957D01*
G02Y84011I1096J1027D01*
G01X604829Y84039D01*
X604857Y84108D01*
G37*
G36*
G01X623192Y83717D02*
Y84069D01*
X623164Y84138D01*
X623138Y84166D01*
G02X622732Y85193I1096J1027D01*
G02X625736I1502J0D01*
G02X625330Y84166I-1502J0D01*
G01X625304Y84138D01*
X625276Y84069D01*
Y83717D01*
X625304Y83648D01*
X625330Y83620D01*
G02Y81566I-1096J-1027D01*
G01X625304Y81538D01*
X625276Y81469D01*
Y81117D01*
X625304Y81048D01*
X625330Y81020D01*
G02Y78966I-1096J-1027D01*
G01X625304Y78938D01*
X625276Y78869D01*
Y78517D01*
X625304Y78448D01*
X625330Y78420D01*
G02Y76366I-1096J-1027D01*
G01X625304Y76338D01*
X625276Y76269D01*
Y75917D01*
X625304Y75848D01*
X625330Y75820D01*
G02X625736Y74793I-1096J-1027D01*
G02X622732I-1502J0D01*
G02X623138Y75820I1502J0D01*
G01X623164Y75848D01*
X623192Y75917D01*
Y76269D01*
X623164Y76338D01*
X623138Y76366D01*
G02Y78420I1096J1027D01*
G01X623164Y78448D01*
X623192Y78517D01*
Y78869D01*
X623164Y78938D01*
X623138Y78966D01*
G02Y81020I1096J1027D01*
G01X623164Y81048D01*
X623192Y81117D01*
Y81469D01*
X623164Y81538D01*
X623138Y81566D01*
G02Y83620I1096J1027D01*
G01X623164Y83648D01*
X623192Y83717D01*
G37*
G36*
G01X647621Y75446D02*
X647249Y75386D01*
X647180Y75341D01*
X647156Y75306D01*
G02X645907Y74638I-1249J834D01*
G02Y77642I0J1502D01*
G02X646828Y77327I1J-1502D01*
G01X646861Y77301D01*
X646941Y77281D01*
X647313Y77341D01*
X647382Y77386D01*
X647406Y77421D01*
G02X648655Y78089I1249J-834D01*
G02Y75085I0J-1502D01*
G02X647734Y75400I-1J1502D01*
G01X647701Y75426D01*
X647621Y75446D01*
G37*
G36*
G01X579477Y236121D02*
G02X582481I1502J0D01*
G02X581831Y234884I-1502J0D01*
G03X581837Y234222I227J-329D01*
G02X582507Y232971I-833J-1251D01*
G02X579503I-1502J0D01*
G02X580153Y234208I1502J0D01*
G03X580147Y234870I-227J329D01*
G02X579477Y236121I833J1251D01*
G37*
G36*
G01X577519Y221970D02*
G02X580523I1502J0D01*
G02X580153Y220983I-1501J0D01*
G01X580129Y220955D01*
X580104Y220888D01*
Y220552D01*
X580129Y220485D01*
X580153Y220457D01*
G02Y218483I-1131J-987D01*
G01X580129Y218455D01*
X580104Y218388D01*
Y218052D01*
X580129Y217985D01*
X580153Y217957D01*
G02X580523Y216970I-1131J-987D01*
G02X579021Y215468I-1502J0D01*
G02X578166Y215735I0J1502D01*
G01X578132Y215759D01*
X578051Y215775D01*
X577684Y215696D01*
X577617Y215648D01*
X577596Y215612D01*
G02X576308Y214883I-1288J773D01*
G02Y217887I0J1502D01*
G02X577163Y217620I0J-1502D01*
G01X577197Y217596D01*
X577278Y217580D01*
X577645Y217659D01*
X577712Y217707D01*
X577733Y217743D01*
G02X577889Y217957I1287J-774D01*
G01X577913Y217985D01*
X577938Y218052D01*
Y218388D01*
X577913Y218455D01*
X577889Y218483D01*
G02Y220457I1131J987D01*
G01X577913Y220485D01*
X577938Y220552D01*
Y220888D01*
X577913Y220955D01*
X577889Y220983D01*
G02X577519Y221970I1131J987D01*
G37*
G36*
G01X634798Y224712D02*
G02X637802I1502J0D01*
G02X637432Y223725I-1501J0D01*
G01Y223724D01*
X637431D01*
G03X637383Y223594I152J-130D01*
G01Y223330D01*
G03X637431Y223200I200J0D01*
G01X637432Y223199D01*
G02X637802Y222212I-1131J-987D01*
G02X634798I-1502J0D01*
G02X635168Y223199I1501J0D01*
G01Y223200D01*
X635169D01*
G03X635217Y223330I-152J130D01*
G01Y223594D01*
G03X635169Y223724I-200J0D01*
G01X635168Y223725D01*
G02X634798Y224712I1131J987D01*
G37*
G36*
G01X629892Y225189D02*
X629598D01*
G03X629451Y225124I1J-200D01*
G02X628345Y224639I-1106J1019D01*
G02Y227643I0J1502D01*
G02X629451Y227158I0J-1504D01*
G03X629598Y227093I148J135D01*
G01X629892D01*
G03X630039Y227158I-1J200D01*
G02X631145Y227643I1106J-1019D01*
G02Y224639I0J-1502D01*
G02X630039Y225124I0J1504D01*
G03X629892Y225189I-148J-135D01*
G37*
G36*
G01X612680Y231226D02*
G02X615684I1502J0D01*
G02X615314Y230239I-1501J0D01*
G01Y230238D01*
X615313D01*
G03X615265Y230108I152J-130D01*
G01Y229844D01*
G03X615313Y229714I200J0D01*
G01X615314Y229713D01*
G02Y227739I-1131J-987D01*
G01Y227738D01*
X615313D01*
G03X615265Y227608I152J-130D01*
G01Y227344D01*
G03X615313Y227214I200J0D01*
G01X615314Y227213D01*
G02Y225239I-1131J-987D01*
G01Y225238D01*
X615313D01*
G03X615265Y225108I152J-130D01*
G01Y224844D01*
G03X615313Y224714I200J0D01*
G01X615314Y224713D01*
G02X615684Y223726I-1131J-987D01*
G02X612680I-1502J0D01*
G02X613050Y224713I1501J0D01*
G01Y224714D01*
X613051D01*
G03X613099Y224844I-152J130D01*
G01Y225108D01*
G03X613051Y225238I-200J0D01*
G01X613050Y225239D01*
G02Y227213I1131J987D01*
G01Y227214D01*
X613051D01*
G03X613099Y227344I-152J130D01*
G01Y227608D01*
G03X613051Y227738I-200J0D01*
G01X613050Y227739D01*
G02Y229713I1131J987D01*
G01Y229714D01*
X613051D01*
G03X613099Y229844I-152J130D01*
G01Y230108D01*
G03X613051Y230238I-200J0D01*
G01X613050Y230239D01*
G02X612680Y231226I1131J987D01*
G37*
G36*
G01X623136Y231461D02*
G02X626140I1502J0D01*
G02X625770Y230474I-1501J0D01*
G01Y230473D01*
X625769D01*
G03X625721Y230343I152J-130D01*
G01Y230079D01*
G03X625769Y229949I200J0D01*
G01X625770Y229948D01*
G02Y227974I-1131J-987D01*
G01Y227973D01*
X625769D01*
G03X625721Y227843I152J-130D01*
G01Y227579D01*
G03X625769Y227449I200J0D01*
G01X625770Y227448D01*
G02X626140Y226461I-1131J-987D01*
G02X625655Y225355I-1504J0D01*
G03X625590Y225208I135J-148D01*
G01Y224914D01*
G03X625655Y224767I200J1D01*
G02X626140Y223661I-1019J-1106D01*
G02X623136I-1502J0D01*
G02X623621Y224767I1504J0D01*
G03X623686Y224914I-135J148D01*
G01Y225208D01*
G03X623621Y225355I-200J-1D01*
G02X623136Y226461I1019J1106D01*
G02X623506Y227448I1501J0D01*
G01Y227449D01*
X623507D01*
G03X623555Y227579I-152J130D01*
G01Y227843D01*
G03X623507Y227973I-200J0D01*
G01X623506Y227974D01*
G02Y229948I1131J987D01*
G01Y229949D01*
X623507D01*
G03X623555Y230079I-152J130D01*
G01Y230343D01*
G03X623507Y230473I-200J0D01*
G01X623506Y230474D01*
G02X623136Y231461I1131J987D01*
G37*
G36*
G01X631105Y231786D02*
G02X634109I1502J0D01*
G02X633739Y230799I-1501J0D01*
G01Y230798D01*
X633738D01*
G03X633690Y230668I152J-130D01*
G01Y230404D01*
G03X633738Y230274I200J0D01*
G01X633739Y230273D01*
G02X634109Y229286I-1131J-987D01*
G02X631105I-1502J0D01*
G02X631475Y230273I1501J0D01*
G01Y230274D01*
X631476D01*
G03X631524Y230404I-152J130D01*
G01Y230668D01*
G03X631476Y230798I-200J0D01*
G01X631475Y230799D01*
G02X631105Y231786I1131J987D01*
G37*
G36*
G01X632075Y237743D02*
X632076Y237742D01*
G03X632206Y237694I130J152D01*
G01X632470D01*
G03X632600Y237742I0J200D01*
G01X632601Y237743D01*
G02X633588Y238113I987J-1131D01*
G02Y235109I0J-1502D01*
G02X632601Y235479I0J1501D01*
G01X632600D01*
Y235480D01*
G03X632470Y235528I-130J-152D01*
G01X632206D01*
G03X632076Y235480I0J-200D01*
G01X632075Y235479D01*
G02X630101I-987J1131D01*
G01X630100D01*
Y235480D01*
G03X629970Y235528I-130J-152D01*
G01X629706D01*
G03X629576Y235480I0J-200D01*
G01X629575Y235479D01*
G02X628588Y235109I-987J1131D01*
G02Y238113I0J1502D01*
G02X629575Y237743I0J-1501D01*
G01X629576D01*
Y237742D01*
G03X629706Y237694I130J152D01*
G01X629970D01*
G03X630100Y237742I0J200D01*
G01X630101Y237743D01*
G02X632075I987J-1131D01*
G37*
G36*
G01X631777Y250023D02*
X631778Y250022D01*
G03X631908Y249974I130J152D01*
G01X632172D01*
G03X632302Y250022I0J200D01*
G01X632303Y250023D01*
G02X633290Y250393I987J-1131D01*
G02Y247389I0J-1502D01*
G02X632303Y247759I0J1501D01*
G01X632302D01*
Y247760D01*
G03X632172Y247808I-130J-152D01*
G01X631908D01*
G03X631778Y247760I0J-200D01*
G01X631777Y247759D01*
G02X629803I-987J1131D01*
G01X629802D01*
Y247760D01*
G03X629672Y247808I-130J-152D01*
G01X629408D01*
G03X629278Y247760I0J-200D01*
G01X629277Y247759D01*
G02X628290Y247389I-987J1131D01*
G02Y250393I0J1502D01*
G02X629277Y250023I0J-1501D01*
G01X629278D01*
Y250022D01*
G03X629408Y249974I130J152D01*
G01X629672D01*
G03X629802Y250022I0J200D01*
G01X629803Y250023D01*
G02X631777I987J-1131D01*
G37*
G36*
G01X633667Y190705D02*
G02X633019Y191941I855J1236D01*
G02X636023I1502J0D01*
G02X635270Y190639I-1502J0D01*
G03X635242Y189963I199J-347D01*
G02X635890Y188727I-855J-1236D01*
G02X632886I-1502J0D01*
G02X633639Y190029I1502J0D01*
G03X633667Y190705I-199J347D01*
G37*
G36*
G01X726147Y1134362D02*
X725033D01*
G02X724710Y1134404I0J1265D01*
G03X724699Y1134406I-41J-196D01*
G03X724525Y1134062I-40J-196D01*
G02X724922Y1133169I-806J-893D01*
G02X722518I-1202J0D01*
G02X722915Y1134062I1203J0D01*
G03X722741Y1134406I-134J148D01*
G03X722730Y1134404I30J-198D01*
G02X722407Y1134362I-323J1223D01*
G01X721293D01*
G02X720970Y1134404I0J1265D01*
G03X720959Y1134406I-41J-196D01*
G03X720785Y1134062I-40J-196D01*
G02X721182Y1133169I-806J-893D01*
G02X718778I-1202J0D01*
G02X719175Y1134062I1203J0D01*
G03X719001Y1134406I-134J148D01*
G03X718990Y1134404I30J-198D01*
G02X718667Y1134362I-323J1223D01*
G01X717553D01*
G02X717230Y1134404I0J1265D01*
G03X717219Y1134406I-41J-196D01*
G03X717045Y1134062I-40J-196D01*
G02X717442Y1133169I-806J-893D01*
G02X715038I-1202J0D01*
G02X715435Y1134062I1203J0D01*
G03X715261Y1134406I-134J148D01*
G03X715250Y1134404I30J-198D01*
G02X714927Y1134362I-323J1223D01*
G01X713813D01*
G02X713490Y1134404I0J1265D01*
G03X713479Y1134406I-41J-196D01*
G03X713305Y1134062I-40J-196D01*
G02X713702Y1133169I-806J-893D01*
G02X711298I-1202J0D01*
G02X711695Y1134062I1203J0D01*
G03X711521Y1134406I-134J148D01*
G03X711510Y1134404I30J-198D01*
G02X711187Y1134362I-323J1223D01*
G01X710073D01*
G02X709750Y1134404I0J1265D01*
G03X709739Y1134406I-41J-196D01*
G03X709565Y1134062I-40J-196D01*
G02X709962Y1133169I-806J-893D01*
G02X707558I-1202J0D01*
G02X707955Y1134062I1203J0D01*
G03X707781Y1134406I-134J148D01*
G03X707770Y1134404I30J-198D01*
G02X707447Y1134362I-323J1223D01*
G01X706333D01*
G02X706010Y1134404I0J1265D01*
G03X705999Y1134406I-41J-196D01*
G03X705825Y1134062I-40J-196D01*
G02X706222Y1133169I-806J-893D01*
G02X703818I-1202J0D01*
G02X704215Y1134062I1203J0D01*
G03X704041Y1134406I-134J148D01*
G03X704030Y1134404I30J-198D01*
G02X703707Y1134362I-323J1223D01*
G01X702592D01*
G02X702269Y1134404I0J1265D01*
G03X702258Y1134406I-41J-196D01*
G03X702084Y1134062I-40J-196D01*
G02X702481Y1133169I-806J-893D01*
G02X700077I-1202J0D01*
G02X700474Y1134062I1203J0D01*
G03X700300Y1134406I-134J148D01*
G03X700289Y1134404I30J-198D01*
G02X699966Y1134362I-323J1223D01*
G01X698852D01*
G02X698529Y1134404I0J1265D01*
G03X698518Y1134406I-41J-196D01*
G03X698344Y1134062I-40J-196D01*
G02X698741Y1133169I-806J-893D01*
G02X696337I-1202J0D01*
G02X696734Y1134062I1203J0D01*
G03X696560Y1134406I-134J148D01*
G03X696549Y1134404I30J-198D01*
G02X696226Y1134362I-323J1223D01*
G01X695113D01*
G02X695027Y1134365I1J1265D01*
G03X694988Y1134364I-14J-200D01*
G03X694840Y1134065I25J-199D01*
G02X695001Y1133465I-1040J-601D01*
G01Y1133464D01*
G02X692597I-1202J0D01*
G01Y1133465D01*
G02X692758Y1134065I1201J-1D01*
G03X692610Y1134364I-173J100D01*
G03X692571Y1134365I-25J-199D01*
G02X692485Y1134362I-87J1262D01*
G01X687633D01*
G02X686635Y1134850I0J1265D01*
G03X686477Y1134927I-158J-123D01*
G01X686161D01*
G03X686003Y1134850I0J-200D01*
G02X685005Y1134362I-998J777D01*
G01X683892D01*
G02X683569Y1134404I0J1265D01*
G03X683558Y1134406I-41J-196D01*
G03X683384Y1134062I-40J-196D01*
G02X683781Y1133169I-806J-893D01*
G02X681377I-1202J0D01*
G02X681774Y1134062I1203J0D01*
G03X681600Y1134406I-134J148D01*
G03X681589Y1134404I30J-198D01*
G02X681266Y1134362I-323J1223D01*
G01X680151D01*
G02X679828Y1134404I0J1265D01*
G03X679817Y1134406I-41J-196D01*
G03X679643Y1134062I-40J-196D01*
G02X680040Y1133169I-806J-893D01*
G02X677636I-1202J0D01*
G02X678033Y1134062I1203J0D01*
G03X677859Y1134406I-134J148D01*
G03X677848Y1134404I30J-198D01*
G02X677525Y1134362I-323J1223D01*
G01X676411D01*
G02X676088Y1134404I0J1265D01*
G03X676077Y1134406I-41J-196D01*
G03X675903Y1134062I-40J-196D01*
G02X676300Y1133169I-806J-893D01*
G02X673896I-1202J0D01*
G02X674293Y1134062I1203J0D01*
G03X674119Y1134406I-134J148D01*
G03X674108Y1134404I30J-198D01*
G02X673785Y1134362I-323J1223D01*
G01X672671D01*
G02X672348Y1134404I0J1265D01*
G03X672337Y1134406I-41J-196D01*
G03X672163Y1134062I-40J-196D01*
G02X672560Y1133169I-806J-893D01*
G02X670156I-1202J0D01*
G02X670553Y1134062I1203J0D01*
G03X670379Y1134406I-134J148D01*
G03X670368Y1134404I30J-198D01*
G02X670045Y1134362I-323J1223D01*
G01X668931D01*
G02X668608Y1134404I0J1265D01*
G03X668597Y1134406I-41J-196D01*
G03X668423Y1134062I-40J-196D01*
G02X668820Y1133169I-806J-893D01*
G02X666416I-1202J0D01*
G02X666813Y1134062I1203J0D01*
G03X666639Y1134406I-134J148D01*
G03X666628Y1134404I30J-198D01*
G02X666305Y1134362I-323J1223D01*
G01X665191D01*
G02X664868Y1134404I0J1265D01*
G03X664857Y1134406I-41J-196D01*
G03X664683Y1134062I-40J-196D01*
G02X665080Y1133169I-806J-893D01*
G02X662676I-1202J0D01*
G02X663073Y1134062I1203J0D01*
G03X662899Y1134406I-134J148D01*
G03X662888Y1134404I30J-198D01*
G02X662565Y1134362I-323J1223D01*
G01X661451D01*
G02X661128Y1134404I0J1265D01*
G03X661117Y1134406I-41J-196D01*
G03X660943Y1134062I-40J-196D01*
G02X661340Y1133169I-806J-893D01*
G02X658936I-1202J0D01*
G02X659333Y1134062I1203J0D01*
G03X659159Y1134406I-134J148D01*
G03X659148Y1134404I30J-198D01*
G02X658825Y1134362I-323J1223D01*
G01X657711D01*
G02X657388Y1134404I0J1265D01*
G03X657377Y1134406I-41J-196D01*
G03X657203Y1134062I-40J-196D01*
G02X657600Y1133169I-806J-893D01*
G02X655196I-1202J0D01*
G02X655593Y1134062I1203J0D01*
G03X655419Y1134406I-134J148D01*
G03X655408Y1134404I30J-198D01*
G02X655085Y1134362I-323J1223D01*
G01X654262D01*
G02X653367Y1134733I0J1265D01*
G01X652693Y1135407D01*
G02X652635Y1135533I142J142D01*
G01Y1135541D01*
G03X652467Y1135723I-199J-16D01*
G02X651471Y1136719I190J1186D01*
G03X651289Y1136887I-198J-31D01*
G01X651281D01*
G02X651155Y1136945I16J200D01*
G01X649907Y1138193D01*
X649863Y1138208D01*
G02X649128Y1138850I400J1200D01*
G01X649096Y1138915D01*
G03X648917Y1139026I-179J-89D01*
G01X648860D01*
X648763Y1138966D01*
X648706Y1138850D01*
G02X647572Y1138142I-1136J558D01*
G01X646522D01*
G02X646084Y1138221I2J1266D01*
G03X645895Y1137873I-70J-187D01*
G02X646379Y1136909I-718J-964D01*
G02X643975I-1202J0D01*
G02X644459Y1137873I1202J0D01*
G03X644270Y1138221I-119J161D01*
G02X643832Y1138142I-440J1187D01*
G01X642782D01*
G02X642344Y1138221I2J1266D01*
G03X642155Y1137873I-70J-187D01*
G02X642639Y1136909I-718J-964D01*
G02X640235I-1202J0D01*
G02X640719Y1137873I1202J0D01*
G03X640530Y1138221I-119J161D01*
G02X640092Y1138142I-440J1187D01*
G01X639042D01*
G02X638604Y1138221I2J1266D01*
G03X638415Y1137873I-70J-187D01*
G02X638899Y1136909I-718J-964D01*
G02X636495I-1202J0D01*
G02X636979Y1137873I1202J0D01*
G03X636790Y1138221I-119J161D01*
G02X636352Y1138142I-440J1187D01*
G01X635302D01*
G02X634864Y1138221I2J1266D01*
G03X634675Y1137873I-70J-187D01*
G02X635159Y1136909I-718J-964D01*
G02X632755I-1202J0D01*
G02X633239Y1137873I1202J0D01*
G03X633050Y1138221I-119J161D01*
G02X632612Y1138142I-440J1187D01*
G01X631561D01*
G02X631123Y1138221I2J1266D01*
G03X630934Y1137873I-70J-187D01*
G02X631418Y1136909I-718J-964D01*
G02X629014I-1202J0D01*
G02X629498Y1137873I1202J0D01*
G03X629309Y1138221I-119J161D01*
G02X628871Y1138142I-440J1187D01*
G01X627844D01*
G03X627670Y1138040I0J-200D01*
G01X627499Y1137736D01*
G03X627503Y1137534I175J-98D01*
G02X627678Y1136909I-1029J-625D01*
G02X625274I-1202J0D01*
G02X626412Y1138109I1202J0D01*
G03X626554Y1138439I-10J200D01*
G03X626533Y1138459I-148J-134D01*
G02X626475Y1138514I841J945D01*
G01X626455Y1138534D01*
G02X626086Y1139384I896J894D01*
G03X625970Y1139558I-200J-7D01*
G02X625274Y1140649I507J1091D01*
G02X625735Y1141595I1201J0D01*
G03X625812Y1141752I-123J158D01*
G01Y1142265D01*
G03X625796Y1142343I-200J0D01*
G01X625768Y1142411D01*
G02X625752Y1142489I184J78D01*
G01Y1142988D01*
G02X625782Y1143261I1266J-1D01*
G03X625714Y1143459I-195J44D01*
G02Y1145319I762J930D01*
G03X625782Y1145517I-127J154D01*
G02X625752Y1145790I1236J274D01*
G01Y1146728D01*
G02X625782Y1147001I1266J-1D01*
G03X625714Y1147199I-195J44D01*
G02Y1149059I762J930D01*
G03X625782Y1149257I-127J154D01*
G02X625752Y1149530I1236J274D01*
G01Y1150469D01*
G02X625782Y1150742I1266J-1D01*
G03X625714Y1150940I-195J44D01*
G02Y1152800I762J930D01*
G03X625782Y1152998I-127J154D01*
G02X625752Y1153271I1236J274D01*
G01Y1154300D01*
G03X625667Y1154463I-200J-1D01*
G02Y1156757I809J1147D01*
G03X625752Y1156920I-115J164D01*
G01Y1157949D01*
G02X625782Y1158222I1266J-1D01*
G03X625714Y1158420I-195J44D01*
G02Y1160280I762J930D01*
G03X625782Y1160478I-127J154D01*
G02X625752Y1160751I1236J274D01*
G01Y1169097D01*
G02X626119Y1169987I1266J-1D01*
G01X627626Y1171494D01*
G02X628224Y1171830I896J-894D01*
G01X628485Y1171892D01*
G02X628580Y1171891I45J-195D01*
G01X629086Y1171763D01*
G02X629171Y1171718I-48J-194D01*
G01X629311Y1171592D01*
G03X629555Y1171574I134J149D01*
G02X630216Y1171772I661J-1004D01*
G02X630878Y1171573I0J-1202D01*
G03X631114Y1171584I110J167D01*
G02X631908Y1171866I796J-984D01*
G01X632464D01*
G02X632537Y1171852I0J-200D01*
G01X632904Y1171708D01*
G02X632964Y1171671I-73J-186D01*
G01X633054Y1171592D01*
G03X633296Y1171574I133J149D01*
G02X633956Y1171772I661J-1004D01*
G01X633957D01*
G02X634619Y1171573I0J-1202D01*
G03X634855Y1171584I110J167D01*
G02X635649Y1171866I796J-984D01*
G01X636204D01*
G02X636277Y1171852I-1J-200D01*
G01X636483Y1171771D01*
G03X636670Y1171792I74J186D01*
G01X636711Y1171820D01*
X636756Y1171906D01*
Y1173218D01*
G02X636800Y1173343I200J0D01*
G01X636809Y1173354D01*
X636808Y1173496D01*
X636764Y1173550D01*
G02X636495Y1174309I934J758D01*
G01Y1174311D01*
G02X636764Y1175069I1202J0D01*
G01X636809Y1175125D01*
X636810Y1175266D01*
X636801Y1175277D01*
G02X636756Y1175403I155J126D01*
G01Y1176959D01*
G02X636800Y1177084I200J0D01*
G01X636809Y1177095D01*
X636808Y1177237D01*
X636764Y1177291D01*
G02X636495Y1178050I934J758D01*
G01Y1178052D01*
G02X636764Y1178810I1202J0D01*
G01X636809Y1178866D01*
X636810Y1179007D01*
X636801Y1179018D01*
G02X636756Y1179144I155J126D01*
G01Y1180699D01*
G02X636800Y1180824I200J0D01*
G01X636809Y1180835D01*
X636808Y1180977D01*
X636764Y1181031D01*
G02X636495Y1181790I934J758D01*
G01Y1181792D01*
G02X636764Y1182550I1202J0D01*
G01X636809Y1182606D01*
X636810Y1182747D01*
X636801Y1182758D01*
G02X636756Y1182884I155J126D01*
G01Y1184439D01*
G02X636800Y1184564I200J0D01*
G01X636809Y1184575D01*
X636808Y1184717D01*
X636764Y1184771D01*
G02X636495Y1185530I934J758D01*
G01Y1185531D01*
G02X636516Y1185751I1202J-4D01*
G01Y1185753D01*
G03X636461Y1185930I-197J36D01*
G01X636226Y1186165D01*
G03X636049Y1186220I-141J-142D01*
G01X636048D01*
G02X635828Y1186199I-224J1181D01*
G01X635826D01*
G02X635607Y1186220I5J1202D01*
G01X635605D01*
G03X635428Y1186165I-36J-197D01*
G01X635193Y1185930D01*
G03X635138Y1185753I142J-141D01*
G01Y1185751D01*
G02X635159Y1185531I-1181J-224D01*
G02X632755I-1202J0D01*
G02X632776Y1185752I1202J-3D01*
G01Y1185754D01*
G03X632721Y1185931I-197J36D01*
G01X632486Y1186165D01*
G03X632309Y1186220I-141J-142D01*
G01X632308D01*
G02X632086Y1186199I-224J1181D01*
G02X633288Y1187401I0J1202D01*
G02X633267Y1187180I-1202J3D01*
G01Y1187178D01*
G03X633322Y1187001I197J-36D01*
G01X633557Y1186767D01*
G03X633734Y1186712I141J142D01*
G01X633735D01*
G02X633957Y1186733I224J-1181D01*
G02X634177Y1186712I-4J-1202D01*
G01X634179D01*
G03X634356Y1186767I36J197D01*
G01X634591Y1187002D01*
G03X634646Y1187179I-142J141D01*
G01Y1187181D01*
G02X634625Y1187401I1181J224D01*
G02X635827Y1188603I1202J0D01*
G02X636047Y1188582I-4J-1202D01*
G01X636049D01*
G03X636226Y1188637I36J197D01*
G01X636461Y1188872D01*
G03X636516Y1189049I-142J141D01*
G01Y1189051D01*
G02X636495Y1189270I1181J224D01*
G01Y1189272D01*
G02X636516Y1189491I1202J-5D01*
G01Y1189493D01*
G03X636461Y1189670I-197J36D01*
G01X636226Y1189905D01*
G03X636049Y1189960I-141J-142D01*
G01X636048D01*
G02X635827Y1189939I-224J1181D01*
G02Y1192343I0J1202D01*
G02X636047Y1192322I-4J-1202D01*
G01X636049D01*
G03X636226Y1192377I36J197D01*
G01X636461Y1192612D01*
G03X636516Y1192789I-142J141D01*
G01Y1192791D01*
G02X636495Y1193010I1181J224D01*
G01Y1193012D01*
G02X636516Y1193231I1202J-5D01*
G01Y1193233D01*
G03X636461Y1193410I-197J36D01*
G01X636226Y1193645D01*
G03X636049Y1193700I-141J-142D01*
G01X636048D01*
G02X635827Y1193679I-224J1181D01*
G02X637029Y1194881I0J1202D01*
G02X637008Y1194661I-1202J4D01*
G01Y1194659D01*
G03X637063Y1194482I197J-36D01*
G01X637298Y1194247D01*
G03X637475Y1194192I141J142D01*
G01X637476D01*
G02X637697Y1194213I224J-1181D01*
G02Y1191809I0J-1202D01*
G02X637477Y1191830I4J1202D01*
G01X637475D01*
G03X637298Y1191775I-36J-197D01*
G01X637063Y1191540D01*
G03X637008Y1191363I142J-141D01*
G01Y1191361D01*
G02X637029Y1191142I-1181J-224D01*
G01Y1191140D01*
G02X637008Y1190921I-1202J5D01*
G01Y1190919D01*
G03X637063Y1190742I197J-36D01*
G01X637298Y1190507D01*
G03X637475Y1190452I141J142D01*
G01X637476D01*
G02X637697Y1190473I224J-1181D01*
G01X637698D01*
G02X638282Y1190322I0J-1203D01*
G01X638340Y1190289D01*
X638472Y1190307D01*
X639234Y1191069D01*
G02X639242Y1191076I837J-949D01*
G03X639248Y1191082I-138J144D01*
G02X640130Y1191442I884J-906D01*
G01X640342D01*
G03X640528Y1191569I0J200D01*
G01X640664Y1191915D01*
G03X640615Y1192134I-186J73D01*
G02X640235Y1193011I822J877D01*
G02X642639I1202J0D01*
G02X642259Y1192134I-1202J0D01*
G03X642210Y1191915I137J-146D01*
G01X642346Y1191569D01*
G03X642532Y1191442I186J73D01*
G01X644082D01*
G03X644268Y1191569I0J200D01*
G01X644404Y1191915D01*
G03X644355Y1192134I-186J73D01*
G02X643975Y1193011I822J877D01*
G02X646379I1202J0D01*
G02X645999Y1192134I-1202J0D01*
G03X645950Y1191915I137J-146D01*
G01X646086Y1191569D01*
G03X646272Y1191442I186J73D01*
G01X649845D01*
G03X649987Y1191500I1J200D01*
G01X650574Y1192087D01*
G03X650604Y1192125I-141J142D01*
G01X650874Y1192569D01*
G02X650953Y1192643I171J-103D01*
G01X651320Y1192833D01*
G02X651344Y1192845I578J-1126D01*
G03X651455Y1193022I-89J179D01*
G02X651464Y1193152I1202J-18D01*
G01Y1193154D01*
G03X651376Y1193344I-199J23D01*
G01X651098Y1193528D01*
G02X650534Y1194581I702J1053D01*
G01Y1195181D01*
G02X651098Y1196234I1266J0D01*
G01X651376Y1196418D01*
G03X651464Y1196608I-111J167D01*
G01Y1196609D01*
G02X651455Y1196748I1193J147D01*
G01Y1196751D01*
G02X652657Y1197953I1202J0D01*
G01X652672D01*
G03X652846Y1198051I2J200D01*
G01X653062Y1198414D01*
G02X654150Y1199034I1089J-646D01*
G01X654905D01*
G02X655993Y1198414I-1J-1266D01*
G01X656209Y1198051D01*
G03X656383Y1197953I172J102D01*
G01X656413D01*
G03X656587Y1198051I2J200D01*
G01X656803Y1198414D01*
G02X657891Y1199034I1089J-646D01*
G01X658645D01*
G02X659733Y1198414I-1J-1266D01*
G01X659949Y1198051D01*
G03X660123Y1197953I172J102D01*
G01X660153D01*
G03X660327Y1198051I2J200D01*
G01X660543Y1198414D01*
G02X661631Y1199034I1089J-646D01*
G01X662385D01*
G02X663473Y1198414I-1J-1266D01*
G01X663689Y1198051D01*
G03X663863Y1197953I172J102D01*
G01X663893D01*
G03X664067Y1198051I2J200D01*
G01X664283Y1198414D01*
G02X665371Y1199034I1089J-646D01*
G01X666125D01*
G02X667213Y1198414I-1J-1266D01*
G01X667429Y1198051D01*
G03X667603Y1197953I172J102D01*
G01X667633D01*
G03X667807Y1198051I2J200D01*
G01X668023Y1198414D01*
G02X669111Y1199034I1089J-646D01*
G01X669865D01*
G02X670953Y1198414I-1J-1266D01*
G01X671169Y1198051D01*
G03X671343Y1197953I172J102D01*
G01X671373D01*
G03X671547Y1198051I2J200D01*
G01X671763Y1198414D01*
G02X672851Y1199034I1089J-646D01*
G01X673605D01*
G02X674693Y1198414I-1J-1266D01*
G01X674909Y1198051D01*
G03X675083Y1197953I172J102D01*
G01X675113D01*
G03X675287Y1198051I2J200D01*
G01X675503Y1198414D01*
G02X676591Y1199034I1089J-646D01*
G01X677345D01*
G02X678433Y1198414I-1J-1266D01*
G01X678649Y1198051D01*
G03X678823Y1197953I172J102D01*
G01X678853D01*
G03X679027Y1198051I2J200D01*
G01X679243Y1198414D01*
G02X680331Y1199034I1089J-646D01*
G01X681086D01*
G02X682174Y1198414I-1J-1266D01*
G01X682390Y1198051D01*
G03X682564Y1197953I172J102D01*
G01X682594D01*
G03X682768Y1198051I2J200D01*
G01X682984Y1198414D01*
G02X684072Y1199034I1089J-646D01*
G01X684826D01*
G02X685914Y1198414I-1J-1266D01*
G01X686130Y1198051D01*
G03X686304Y1197953I172J102D01*
G01X686334D01*
G03X686508Y1198051I2J200D01*
G01X686724Y1198414D01*
G02X687812Y1199034I1089J-646D01*
G01X692306D01*
G02X693394Y1198414I-1J-1266D01*
G01X693610Y1198051D01*
G03X693784Y1197953I172J102D01*
G01X693814D01*
G03X693988Y1198051I2J200D01*
G01X694204Y1198414D01*
G02X695292Y1199034I1089J-646D01*
G01X696046D01*
G02X697134Y1198414I-1J-1266D01*
G01X697350Y1198051D01*
G03X697524Y1197953I172J102D01*
G01X697554D01*
G03X697728Y1198051I2J200D01*
G01X697944Y1198414D01*
G02X699032Y1199034I1089J-646D01*
G01X699786D01*
G02X700874Y1198414I-1J-1266D01*
G01X701090Y1198051D01*
G03X701264Y1197953I172J102D01*
G01X701294D01*
G03X701468Y1198051I2J200D01*
G01X701684Y1198414D01*
G02X702772Y1199034I1089J-646D01*
G01X703527D01*
G02X704615Y1198414I-1J-1266D01*
G01X704831Y1198051D01*
G03X705005Y1197953I172J102D01*
G01X705035D01*
G03X705209Y1198051I2J200D01*
G01X705425Y1198414D01*
G02X706513Y1199034I1089J-646D01*
G01X707267D01*
G02X708355Y1198414I-1J-1266D01*
G01X708571Y1198051D01*
G03X708745Y1197953I172J102D01*
G01X708775D01*
G03X708949Y1198051I2J200D01*
G01X709165Y1198414D01*
G02X710253Y1199034I1089J-646D01*
G01X711007D01*
G02X712095Y1198414I-1J-1266D01*
G01X712311Y1198051D01*
G03X712485Y1197953I172J102D01*
G01X712515D01*
G03X712689Y1198051I2J200D01*
G01X712905Y1198414D01*
G02X713993Y1199034I1089J-646D01*
G01X714747D01*
G02X715835Y1198414I-1J-1266D01*
G01X716051Y1198051D01*
G03X716225Y1197953I172J102D01*
G01X716255D01*
G03X716429Y1198051I2J200D01*
G01X716645Y1198414D01*
G02X717733Y1199034I1089J-646D01*
G01X718487D01*
G02X719575Y1198414I-1J-1266D01*
G01X719791Y1198051D01*
G03X719965Y1197953I172J102D01*
G01X719995D01*
G03X720169Y1198051I2J200D01*
G01X720385Y1198414D01*
G02X721473Y1199034I1089J-646D01*
G01X722227D01*
G02X723315Y1198414I-1J-1266D01*
G01X723531Y1198051D01*
G03X723705Y1197953I172J102D01*
G01X723735D01*
G03X723909Y1198051I2J200D01*
G01X724125Y1198414D01*
G02X725213Y1199034I1089J-646D01*
G01X725999D01*
G02X727090Y1198407I-2J-1266D01*
G01X727308Y1198035D01*
G03X727481Y1197936I173J101D01*
G01X727533D01*
X727625Y1197989D01*
X727870Y1198407D01*
G02X728961Y1199034I1093J-639D01*
G01X729708D01*
G02X730796Y1198414I-1J-1266D01*
G01X731012Y1198051D01*
G03X731186Y1197953I172J102D01*
G01X731201D01*
G02X732379Y1196994I0J-1203D01*
G01X732389Y1196947D01*
X732447Y1196873D01*
X733033Y1196602D01*
G02X733192Y1196515I-527J-1151D01*
G01X733237Y1196485D01*
X733346Y1196481D01*
X733634Y1196633D01*
G03X733740Y1196801I-94J177D01*
G01Y1196802D01*
G02X734941Y1197953I1201J-51D01*
G02Y1195549I0J-1202D01*
G02X734075Y1195917I0J1203D01*
G03X733731Y1195785I-144J-139D01*
G03X733736Y1195733I200J-7D01*
G02X733768Y1195454I-1234J-283D01*
G01Y1194341D01*
G03X733870Y1194167I200J0D01*
G01X734110Y1194032D01*
G03X734313Y1194036I98J174D01*
G02X734941Y1194213I628J-1026D01*
G02Y1191809I0J-1202D01*
G02X734313Y1191986I0J1203D01*
G03X734110Y1191990I-105J-170D01*
G01X733870Y1191855D01*
G03X733768Y1191681I98J-174D01*
G01Y1190601D01*
G03X733870Y1190427I200J0D01*
G01X734110Y1190292D01*
G03X734313Y1190296I98J174D01*
G02X734941Y1190473I628J-1026D01*
G02Y1188069I0J-1202D01*
G02X734313Y1188246I0J1203D01*
G03X734110Y1188250I-105J-170D01*
G01X733870Y1188115D01*
G03X733768Y1187941I98J-174D01*
G01Y1186861D01*
G03X733870Y1186687I200J0D01*
G01X734110Y1186552D01*
G03X734313Y1186556I98J174D01*
G02X734941Y1186733I628J-1026D01*
G02Y1184329I0J-1202D01*
G02X734199Y1184586I1J1202D01*
G01X734198D01*
G03X734030Y1184623I-123J-158D01*
G01X733803Y1184570D01*
G03X733665Y1184454I46J-195D01*
G02X733396Y1184057I-1163J499D01*
G01X732163Y1182824D01*
G03X732104Y1182689I141J-142D01*
G01X732102Y1182627D01*
X732124Y1182561D01*
X732146Y1182533D01*
G02X732403Y1181791I-945J-743D01*
G02X729999I-1202J0D01*
G01Y1181793D01*
G02X730018Y1182005I1202J-1D01*
G01X730026Y1182049D01*
X730003Y1182134D01*
X729830Y1182341D01*
G03X729677Y1182412I-153J-129D01*
G01X727014D01*
G03X726814Y1182212I0J-200D01*
G01Y1179571D01*
G03X726886Y1179417I200J0D01*
G01X727061Y1179272D01*
G03X727227Y1179230I127J154D01*
G01X727228D01*
G02X727460Y1179253I234J-1179D01*
G02Y1176849I0J-1202D01*
G02X727229Y1176872I3J1202D01*
G01X727227D01*
G03X727061Y1176830I-39J-196D01*
G01X726886Y1176685D01*
G03X726814Y1176531I128J-154D01*
G01Y1175830D01*
G03X726886Y1175676I200J0D01*
G01X727061Y1175531D01*
G03X727227Y1175489I127J154D01*
G01X727228D01*
G02X727460Y1175512I234J-1179D01*
G02Y1173108I0J-1202D01*
G02X727229Y1173131I3J1202D01*
G01X727227D01*
G03X727061Y1173089I-39J-196D01*
G01X726886Y1172944D01*
G03X726814Y1172790I128J-154D01*
G01Y1172090D01*
G03X726886Y1171936I200J0D01*
G01X727061Y1171791D01*
G03X727227Y1171749I127J154D01*
G01X727228D01*
G02X727460Y1171772I234J-1179D01*
G02X728232Y1171491I0J-1201D01*
G03X728361Y1171444I129J153D01*
G01X730112D01*
G02X730234Y1171403I1J-200D01*
G01X730333Y1171407D01*
X730408Y1171472D01*
G02X731201Y1171772I794J-902D01*
G02X731973Y1171491I0J-1201D01*
G03X732102Y1171444I129J153D01*
G01X733852D01*
G02X733974Y1171403I1J-200D01*
G01X734073Y1171407D01*
X734148Y1171472D01*
G02X734941Y1171772I794J-902D01*
G02X736143Y1170570I0J-1202D01*
G02X735932Y1169891I-1203J1D01*
G03X735947Y1169645I165J-113D01*
G01X735974Y1169616D01*
G02X736024Y1169483I-150J-132D01*
G01Y1167917D01*
G02X735974Y1167784I-200J-1D01*
G01X735947Y1167755D01*
G03X735932Y1167509I150J-133D01*
G02Y1166151I-992J-679D01*
G03X735947Y1165905I165J-113D01*
G01X735974Y1165876D01*
G02X736024Y1165743I-150J-132D01*
G01Y1160437D01*
G02X735974Y1160304I-200J-1D01*
G01X735947Y1160275D01*
G03X735932Y1160029I150J-133D01*
G02Y1158671I-992J-679D01*
G03X735947Y1158425I165J-113D01*
G01X735974Y1158396D01*
G02X736024Y1158263I-150J-132D01*
G01Y1156697D01*
G02X735974Y1156564I-200J-1D01*
G01X735947Y1156535D01*
G03X735932Y1156289I150J-133D01*
G02Y1154931I-992J-679D01*
G03X735947Y1154685I165J-113D01*
G01X735974Y1154656D01*
G02X736024Y1154523I-150J-132D01*
G01Y1152957D01*
G02X735974Y1152824I-200J-1D01*
G01X735947Y1152795D01*
G03X735932Y1152549I150J-133D01*
G02Y1151191I-992J-679D01*
G03X735947Y1150945I165J-113D01*
G01X735974Y1150916D01*
G02X736024Y1150783I-150J-132D01*
G01Y1149216D01*
G02X735974Y1149083I-200J-1D01*
G01X735947Y1149054D01*
G03X735932Y1148808I150J-133D01*
G02Y1147450I-992J-679D01*
G03X735947Y1147204I165J-113D01*
G01X735974Y1147175D01*
G02X736024Y1147042I-150J-132D01*
G01Y1145476D01*
G02X735974Y1145343I-200J-1D01*
G01X735947Y1145314D01*
G03X735932Y1145068I150J-133D01*
G02Y1143710I-992J-679D01*
G03X735947Y1143464I165J-113D01*
G01X735974Y1143435D01*
G02X736024Y1143302I-150J-132D01*
G01Y1141736D01*
G02X735974Y1141603I-200J-1D01*
G01X735947Y1141574D01*
G03X735932Y1141328I150J-133D01*
G02Y1139970I-992J-679D01*
G03X735947Y1139724I165J-113D01*
G01X735974Y1139695D01*
G02X736024Y1139562I-150J-132D01*
G01Y1137996D01*
G02X735974Y1137863I-200J-1D01*
G01X735947Y1137834D01*
G03X735932Y1137588I150J-133D01*
G02X736143Y1136909I-992J-680D01*
G02X734941Y1135707I-1202J0D01*
G01X734940D01*
G02X734672Y1135737I-1J1202D01*
G03X734474Y1135670I-44J-195D01*
G02X734397Y1135586I-970J812D01*
G01X733551Y1134740D01*
G03X733549Y1134738I140J-142D01*
G01X733402Y1134585D01*
G02X733332Y1134538I-144J139D01*
G01X732932Y1134377D01*
G02X732857Y1134362I-76J185D01*
G01X728773D01*
G02X728450Y1134404I0J1265D01*
G03X728265Y1134062I-51J-193D01*
G02X728662Y1133169I-806J-893D01*
G02X726258I-1202J0D01*
G02X726655Y1134062I1203J0D01*
G03X726470Y1134404I-134J149D01*
G02X726147Y1134362I-323J1223D01*
G37*
G36*
G01X612184Y1179921D02*
G02X614588I1202J0D01*
G02X614581Y1179796I-1202J5D01*
G01Y1179794D01*
X614577Y1179753D01*
X614603Y1179673D01*
X614830Y1179420D01*
G03X614979Y1179354I149J134D01*
G01X615256D01*
G02Y1176748I0J-1303D01*
G01X611516D01*
G02Y1179354I0J1303D01*
G01X611793D01*
G03X611942Y1179420I0J200D01*
G01X612169Y1179673D01*
X612195Y1179753D01*
X612191Y1179795D01*
G02X612184Y1179921I1195J130D01*
G37*
G36*
G01X628568Y1182480D02*
G02X628346Y1182459I-224J1181D01*
G02X629548Y1183661I0J1202D01*
G02X629527Y1183439I-1202J2D01*
G03X629994Y1182972I393J-74D01*
G02X630216Y1182993I224J-1181D01*
G02X629014Y1181791I0J-1202D01*
G02X629035Y1182013I1202J-2D01*
G03X628568Y1182480I-393J74D01*
G37*
G36*
G01X753642Y1188069D02*
G02X754844Y1189271I0J1202D01*
G02X754823Y1189049I-1202J2D01*
G01X754814Y1189000D01*
X754843Y1188907D01*
X755148Y1188602D01*
X755241Y1188573D01*
X755290Y1188582D01*
G02X755512Y1188603I224J-1181D01*
G02X756714Y1187401I0J-1202D01*
G02X756693Y1187179I-1202J2D01*
G01X756684Y1187130D01*
X756713Y1187037D01*
X757018Y1186732D01*
X757111Y1186703D01*
X757160Y1186712D01*
G02X757382Y1186733I224J-1181D01*
G02X756180Y1185531I0J-1202D01*
G02X756201Y1185753I1202J-2D01*
G01X756210Y1185802D01*
X756181Y1185895D01*
X755876Y1186200D01*
X755783Y1186229D01*
X755734Y1186220D01*
G02X755512Y1186199I-224J1181D01*
G02X754310Y1187401I0J1202D01*
G02X754331Y1187623I1202J-2D01*
G01X754340Y1187672D01*
X754311Y1187765D01*
X754006Y1188070D01*
X753913Y1188099D01*
X753864Y1188090D01*
G02X753642Y1188069I-224J1181D01*
G37*
G36*
G01X746850Y1190919D02*
G02X746829Y1191141I1181J224D01*
G02X748031Y1189939I1202J0D01*
G02X747809Y1189960I2J1202D01*
G03X747342Y1189493I-74J-393D01*
G02X747363Y1189271I-1181J-224D01*
G02X746161Y1190473I-1202J0D01*
G02X746383Y1190452I-2J-1202D01*
G03X746850Y1190919I74J393D01*
G37*
G36*
G01X698207Y1217322D02*
G02X700611I1202J0D01*
G02X700590Y1217100I-1202J2D01*
G01X700581Y1217051D01*
X700610Y1216958D01*
X700915Y1216653D01*
X701008Y1216624D01*
X701057Y1216633D01*
G02X701279Y1216654I224J-1181D01*
G02X700077Y1215452I0J-1202D01*
G02X700098Y1215674I1202J-2D01*
G01X700107Y1215723D01*
X700078Y1215816D01*
X699773Y1216121D01*
X699680Y1216150D01*
X699631Y1216141D01*
G02X699409Y1216120I-224J1181D01*
G02X699187Y1216141I2J1202D01*
G01X699138Y1216150D01*
X699045Y1216121D01*
X698740Y1215816D01*
X698711Y1215723D01*
X698720Y1215674D01*
G02X698741Y1215452I-1181J-224D01*
G02X696337I-1202J0D01*
G02X696358Y1215674I1202J-2D01*
G01X696367Y1215723D01*
X696338Y1215816D01*
X696033Y1216121D01*
X695940Y1216150D01*
X695891Y1216141D01*
G02X695669Y1216120I-224J1181D01*
G02X695447Y1216141I2J1202D01*
G01X695398Y1216150D01*
X695305Y1216121D01*
X695000Y1215816D01*
X694971Y1215723D01*
X694980Y1215674D01*
G02X695001Y1215452I-1181J-224D01*
G02X693799Y1216654I-1202J0D01*
G02X694021Y1216633I-2J-1202D01*
G01X694070Y1216624D01*
X694163Y1216653D01*
X694468Y1216958D01*
X694497Y1217051D01*
X694488Y1217100D01*
G02X694467Y1217322I1181J224D01*
G02X696871I1202J0D01*
G02X696850Y1217100I-1202J2D01*
G01X696841Y1217051D01*
X696870Y1216958D01*
X697175Y1216653D01*
X697268Y1216624D01*
X697317Y1216633D01*
G02X697539Y1216654I224J-1181D01*
G02X697761Y1216633I-2J-1202D01*
G01X697810Y1216624D01*
X697903Y1216653D01*
X698208Y1216958D01*
X698237Y1217051D01*
X698228Y1217100D01*
G02X698207Y1217322I1181J224D01*
G37*
G36*
G01X642105Y1221062D02*
G02X643307Y1219860I1202J0D01*
G02X643085Y1219881I2J1202D01*
G01X643036Y1219890D01*
X642943Y1219861D01*
X642638Y1219556D01*
X642609Y1219463D01*
X642618Y1219414D01*
G02X642639Y1219192I-1181J-224D01*
G02X640235I-1202J0D01*
G02X640256Y1219414I1202J-2D01*
G01X640265Y1219463D01*
X640236Y1219556D01*
X639931Y1219861D01*
X639838Y1219890D01*
X639789Y1219881D01*
G02X639567Y1219860I-224J1181D01*
G02X640769Y1221062I0J1202D01*
G02X640748Y1220840I-1202J2D01*
G01X640739Y1220791D01*
X640768Y1220698D01*
X641073Y1220393D01*
X641166Y1220364D01*
X641215Y1220373D01*
G02X641437Y1220394I224J-1181D01*
G02X641659Y1220373I-2J-1202D01*
G01X641708Y1220364D01*
X641801Y1220393D01*
X642106Y1220698D01*
X642135Y1220791D01*
X642126Y1220840D01*
G02X642105Y1221062I1181J224D01*
G37*
G36*
G01X653325D02*
G02X654527Y1219860I1202J0D01*
G02X654305Y1219881I2J1202D01*
G01X654256Y1219890D01*
X654163Y1219861D01*
X653858Y1219556D01*
X653829Y1219463D01*
X653838Y1219414D01*
G02X653859Y1219192I-1181J-224D01*
G02X651455I-1202J0D01*
G02X651476Y1219414I1202J-2D01*
G01X651485Y1219463D01*
X651456Y1219556D01*
X651151Y1219861D01*
X651058Y1219890D01*
X651009Y1219881D01*
G02X650787Y1219860I-224J1181D01*
G02X650565Y1219881I2J1202D01*
G01X650516Y1219890D01*
X650423Y1219861D01*
X650118Y1219556D01*
X650089Y1219463D01*
X650098Y1219414D01*
G02X650119Y1219192I-1181J-224D01*
G02X647715I-1202J0D01*
G02X647736Y1219414I1202J-2D01*
G01X647745Y1219463D01*
X647716Y1219556D01*
X647411Y1219861D01*
X647318Y1219890D01*
X647269Y1219881D01*
G02X647047Y1219860I-224J1181D01*
G02X648249Y1221062I0J1202D01*
G02X648228Y1220840I-1202J2D01*
G01X648219Y1220791D01*
X648248Y1220698D01*
X648553Y1220393D01*
X648646Y1220364D01*
X648695Y1220373D01*
G02X648917Y1220394I224J-1181D01*
G02X649139Y1220373I-2J-1202D01*
G01X649188Y1220364D01*
X649281Y1220393D01*
X649586Y1220698D01*
X649615Y1220791D01*
X649606Y1220840D01*
G02X649585Y1221062I1181J224D01*
G02X651989I1202J0D01*
G02X651968Y1220840I-1202J2D01*
G01X651959Y1220791D01*
X651988Y1220698D01*
X652293Y1220393D01*
X652386Y1220364D01*
X652435Y1220373D01*
G02X652657Y1220394I224J-1181D01*
G02X652879Y1220373I-2J-1202D01*
G01X652928Y1220364D01*
X653021Y1220393D01*
X653326Y1220698D01*
X653355Y1220791D01*
X653346Y1220840D01*
G02X653325Y1221062I1181J224D01*
G37*
G36*
G01X679507D02*
G02X680709Y1219860I1202J0D01*
G02X680486Y1219881I1J1202D01*
G01X680437Y1219890D01*
X680344Y1219861D01*
X680074Y1219592D01*
G03X680019Y1219415I142J-141D01*
G01Y1219414D01*
G02X680040Y1219192I-1181J-224D01*
G02X677636I-1202J0D01*
G02X677657Y1219414I1202J-2D01*
G01X677666Y1219463D01*
X677637Y1219556D01*
X677332Y1219861D01*
X677239Y1219890D01*
X677190Y1219881D01*
G02X676968Y1219860I-224J1181D01*
G02X678170Y1221062I0J1202D01*
G02X678149Y1220840I-1202J2D01*
G01X678140Y1220791D01*
X678169Y1220698D01*
X678474Y1220393D01*
X678567Y1220364D01*
X678616Y1220373D01*
G02X678838Y1220394I224J-1181D01*
G02X679061Y1220373I-1J-1202D01*
G01X679110Y1220364D01*
X679203Y1220393D01*
X679473Y1220662D01*
G03X679528Y1220839I-142J141D01*
G01Y1220840D01*
G02X679507Y1221062I1181J224D01*
G37*
G36*
G01X657710Y185330D02*
X657845Y185710D01*
X657835Y185800D01*
X657811Y185839D01*
G02X657586Y186629I1277J791D01*
G02X660590I1502J0D01*
G02X659587Y185212I-1502J0D01*
G01X659543Y185197D01*
X659480Y185133D01*
X659345Y184753D01*
X659355Y184663D01*
X659379Y184624D01*
G02X659604Y183834I-1277J-791D01*
G02X656600I-1502J0D01*
G02X657603Y185251I1502J0D01*
G01X657647Y185266D01*
X657710Y185330D01*
G37*
G36*
G01X711968Y1409998D02*
X715368D01*
G02Y1406992I0J-1503D01*
G01X711968D01*
G02Y1409998I0J1503D01*
G37*
G36*
G01Y1398086D02*
X715368D01*
G02Y1395080I0J-1503D01*
G01X711968D01*
G02Y1398086I0J1503D01*
G37*
G36*
G01X724208Y1409904D02*
X727608D01*
G02Y1406898I0J-1503D01*
G01X724208D01*
G02Y1409904I0J1503D01*
G37*
G36*
G01Y1397992D02*
X727608D01*
G02Y1394986I0J-1503D01*
G01X724208D01*
G02Y1397992I0J1503D01*
G37*
G36*
G01X736448Y1409904D02*
X739848D01*
G02Y1406898I0J-1503D01*
G01X736448D01*
G02Y1409904I0J1503D01*
G37*
G36*
G01Y1397992D02*
X739848D01*
G02Y1394986I0J-1503D01*
G01X736448D01*
G02Y1397992I0J1503D01*
G37*
G36*
G01X760928Y1385800D02*
X764328D01*
G02Y1382794I0J-1503D01*
G01X760928D01*
G02Y1385800I0J1503D01*
G37*
G36*
G01Y1373888D02*
X764328D01*
G02Y1370882I0J-1503D01*
G01X760928D01*
G02Y1373888I0J1503D01*
G37*
G36*
G01X748688D02*
X752088D01*
G02Y1370882I0J-1503D01*
G01X748688D01*
G02Y1373888I0J1503D01*
G37*
G36*
G01Y1385800D02*
X752088D01*
G02Y1382794I0J-1503D01*
G01X748688D01*
G02Y1385800I0J1503D01*
G37*
G36*
G01X736448D02*
X739848D01*
G02Y1382794I0J-1503D01*
G01X736448D01*
G02Y1385800I0J1503D01*
G37*
G36*
G01Y1373888D02*
X739848D01*
G02Y1370882I0J-1503D01*
G01X736448D01*
G02Y1373888I0J1503D01*
G37*
G36*
G01X724208D02*
X727608D01*
G02Y1370882I0J-1503D01*
G01X724208D01*
G02Y1373888I0J1503D01*
G37*
G36*
G01Y1385800D02*
X727608D01*
G02Y1382794I0J-1503D01*
G01X724208D01*
G02Y1385800I0J1503D01*
G37*
G36*
G01X711968D02*
X715368D01*
G02Y1382794I0J-1503D01*
G01X711968D01*
G02Y1385800I0J1503D01*
G37*
G36*
G01Y1373888D02*
X715368D01*
G02Y1370882I0J-1503D01*
G01X711968D01*
G02Y1373888I0J1503D01*
G37*
G36*
G01X699728Y1349690D02*
X703128D01*
G02Y1346684I0J-1503D01*
G01X699728D01*
G02Y1349690I0J1503D01*
G37*
G36*
G01Y1361602D02*
X703128D01*
G02Y1358596I0J-1503D01*
G01X699728D01*
G02Y1361602I0J1503D01*
G37*
G36*
G01X711968D02*
X715368D01*
G02Y1358596I0J-1503D01*
G01X711968D01*
G02Y1361602I0J1503D01*
G37*
G36*
G01Y1349690D02*
X715368D01*
G02Y1346684I0J-1503D01*
G01X711968D01*
G02Y1349690I0J1503D01*
G37*
G36*
G01X724208D02*
X727608D01*
G02Y1346684I0J-1503D01*
G01X724208D01*
G02Y1349690I0J1503D01*
G37*
G36*
G01Y1361602D02*
X727608D01*
G02Y1358596I0J-1503D01*
G01X724208D01*
G02Y1361602I0J1503D01*
G37*
G36*
G01X736448D02*
X739848D01*
G02Y1358596I0J-1503D01*
G01X736448D01*
G02Y1361602I0J1503D01*
G37*
G36*
G01Y1349690D02*
X739848D01*
G02Y1346684I0J-1503D01*
G01X736448D01*
G02Y1349690I0J1503D01*
G37*
G36*
G01X748688Y1361602D02*
X752088D01*
G02Y1358596I0J-1503D01*
G01X748688D01*
G02Y1361602I0J1503D01*
G37*
G36*
G01Y1349690D02*
X752088D01*
G02Y1346684I0J-1503D01*
G01X748688D01*
G02Y1349690I0J1503D01*
G37*
G36*
G01X760928D02*
X764328D01*
G02Y1346684I0J-1503D01*
G01X760928D01*
G02Y1349690I0J1503D01*
G37*
G36*
G01Y1361602D02*
X764328D01*
G02Y1358596I0J-1503D01*
G01X760928D01*
G02Y1361602I0J1503D01*
G37*
G36*
G01X773168D02*
X776568D01*
G02Y1358596I0J-1503D01*
G01X773168D01*
G02Y1361602I0J1503D01*
G37*
G36*
G01Y1349690D02*
X776568D01*
G02Y1346684I0J-1503D01*
G01X773168D01*
G02Y1349690I0J1503D01*
G37*
G36*
G01X807525Y1219895D02*
G02X809027Y1218393I1502J0D01*
G02X808942Y1218395I-7J1502D01*
G03X808790Y1218337I-11J-200D01*
G01X808579Y1218127D01*
G03X808520Y1217977I141J-142D01*
G01Y1217976D01*
G02X808522Y1217900I-1500J-77D01*
G02X807020Y1219402I-1502J0D01*
G02X807105Y1219400I7J-1502D01*
G03X807257Y1219458I11J200D01*
G01X807468Y1219668D01*
G03X807527Y1219818I-141J142D01*
G01Y1219819D01*
G02X807525Y1219895I1500J77D01*
G37*
G36*
G01X871098Y1300833D02*
G02X874102I1502J0D01*
G02X873732Y1299846I-1501J0D01*
G01Y1299845D01*
X873731D01*
G03X873683Y1299715I152J-130D01*
G01Y1299451D01*
G03X873731Y1299321I200J0D01*
G01X873732Y1299320D01*
G02X874102Y1298333I-1131J-987D01*
G02X871098I-1502J0D01*
G02X871468Y1299320I1501J0D01*
G01Y1299321D01*
X871469D01*
G03X871517Y1299451I-152J130D01*
G01Y1299715D01*
G03X871469Y1299845I-200J0D01*
G01X871468Y1299846D01*
G02X871098Y1300833I1131J987D01*
G37*
G36*
G01X794031Y1332483D02*
Y1332777D01*
G03X793966Y1332924I-200J-1D01*
G02X793481Y1334030I1019J1106D01*
G02X796485I1502J0D01*
G02X796000Y1332924I-1504J0D01*
G03X795935Y1332777I135J-148D01*
G01Y1332483D01*
G03X796000Y1332336I200J1D01*
G02X796485Y1331230I-1019J-1106D01*
G02X793481I-1502J0D01*
G02X793966Y1332336I1504J0D01*
G03X794031Y1332483I-135J148D01*
G37*
G36*
G01X950489Y1370808D02*
X950175D01*
G03X950017Y1370731I0J-200D01*
G02X948832Y1370152I-1185J923D01*
G02Y1373156I0J1502D01*
G02X950017Y1372577I0J-1502D01*
G03X950175Y1372500I158J123D01*
G01X950489D01*
G03X950647Y1372577I0J200D01*
G02X951832Y1373156I1185J-923D01*
G02Y1370152I0J-1502D01*
G02X950647Y1370731I0J1502D01*
G03X950489Y1370808I-158J-123D01*
G37*
G36*
G01X951042Y1374745D02*
X950728D01*
G03X950570Y1374668I0J-200D01*
G02X949385Y1374089I-1185J923D01*
G02Y1377093I0J1502D01*
G02X950570Y1376514I0J-1502D01*
G03X950728Y1376437I158J123D01*
G01X951042D01*
G03X951200Y1376514I0J200D01*
G02X952385Y1377093I1185J-923D01*
G02Y1374089I0J-1502D01*
G02X951200Y1374668I0J1502D01*
G03X951042Y1374745I-158J-123D01*
G37*
G36*
G01X951098Y1378652D02*
X950788D01*
G03X950633Y1378578I0J-200D01*
G02X949469Y1378026I-1163J950D01*
G02Y1381030I0J1502D01*
G02X950633Y1380478I1J-1502D01*
G03X950788Y1380404I155J126D01*
G01X951098D01*
G03X951253Y1380478I0J200D01*
G02X952417Y1381030I1163J-950D01*
G02Y1378026I0J-1502D01*
G02X951253Y1378578I-1J1502D01*
G03X951098Y1378652I-155J-126D01*
G37*
G36*
G01X985793Y1400790D02*
X985479D01*
G03X985321Y1400713I0J-200D01*
G02X984136Y1400134I-1185J923D01*
G02Y1403138I0J1502D01*
G02X985321Y1402559I0J-1502D01*
G03X985479Y1402482I158J123D01*
G01X985793D01*
G03X985951Y1402559I0J200D01*
G02X987136Y1403138I1185J-923D01*
G02Y1400134I0J-1502D01*
G02X985951Y1400713I0J1502D01*
G03X985793Y1400790I-158J-123D01*
G37*
G36*
G01X806004Y1201265D02*
G02X807489Y1202545I1485J-221D01*
G02Y1199541I0J-1502D01*
G02X806576Y1199850I0J1503D01*
G03X805937Y1199592I-243J-317D01*
G02X804452Y1198312I-1485J221D01*
G02Y1201316I0J1502D01*
G02X805365Y1201007I0J-1503D01*
G03X806004Y1201265I243J317D01*
G37*
G36*
G01X817917Y1230265D02*
G02X819419Y1228763I1502J0D01*
G02X819291Y1228768I-5J1502D01*
G01X819247Y1228772D01*
X819165Y1228742D01*
X818885Y1228466D01*
X818855Y1228384D01*
X818858Y1228340D01*
G02X818862Y1228226I-1498J-110D01*
G02X817360Y1226724I-1502J0D01*
G01X817359D01*
G02X817092Y1226748I0J1502D01*
G01X817043Y1226757D01*
X816950Y1226728D01*
X816647Y1226425D01*
X816618Y1226332D01*
X816627Y1226283D01*
G02X816651Y1226016I-1478J-267D01*
G02X815149Y1227518I-1502J0D01*
G01X815150D01*
G02X815417Y1227494I0J-1502D01*
G01X815466Y1227485D01*
X815559Y1227514D01*
X815862Y1227817D01*
X815891Y1227910D01*
X815882Y1227959D01*
G02X815858Y1228226I1478J267D01*
G02X817360Y1229728I1502J0D01*
G02X817488Y1229723I5J-1502D01*
G01X817532Y1229719D01*
X817614Y1229749D01*
X817894Y1230025D01*
X817924Y1230107D01*
X817921Y1230151D01*
G02X817917Y1230265I1498J110D01*
G37*
G36*
G01X979288Y1388101D02*
G02X978590Y1389370I805J1269D01*
G02X981594I1502J0D01*
G02X980820Y1388056I-1502J0D01*
G03X980800Y1387369I194J-349D01*
G02X981498Y1386100I-805J-1269D01*
G02X978494I-1502J0D01*
G02X979268Y1387414I1502J0D01*
G03X979288Y1388101I-194J349D01*
G37*
G36*
G01X950339Y1408056D02*
G02X950239Y1408053I-95J1499D01*
G02X951741Y1409555I0J1502D01*
G02X951672Y1409105I-1502J0D01*
G03X952080Y1408586I381J-120D01*
G02X952180Y1408589I95J-1499D01*
G02X950678Y1407087I0J-1502D01*
G02X950747Y1407537I1502J0D01*
G03X950339Y1408056I-381J120D01*
G37*
G36*
G01X683532Y147959D02*
X683511Y147998D01*
G02X683328Y148717I1319J719D01*
G02X686332I1502J0D01*
G02X685327Y147300I-1501J0D01*
G01X685285Y147285D01*
X685222Y147224D01*
X685081Y146857D01*
X685087Y146770D01*
X685108Y146731D01*
G02X685291Y146012I-1319J-719D01*
G02X684631Y144768I-1502J0D01*
G03X684543Y144603I112J-166D01*
G01Y144271D01*
G03X684631Y144106I200J1D01*
G02X685276Y143074I-842J-1244D01*
G01X685281Y143037D01*
X685315Y142974D01*
X685573Y142754D01*
X685639Y142729D01*
X685677Y142730D01*
X685695D01*
G02Y139726I0J-1502D01*
G02X684208Y141016I0J1502D01*
G01X684203Y141053D01*
X684169Y141116D01*
X683911Y141336D01*
X683845Y141361D01*
X683807Y141360D01*
X683789D01*
G02X682287Y142862I0J1502D01*
G02X682947Y144106I1502J0D01*
G03X683035Y144271I-112J166D01*
G01Y144603D01*
G03X682947Y144768I-200J-1D01*
G02X682287Y146012I842J1244D01*
G02X683292Y147429I1501J0D01*
G01X683334Y147444D01*
X683397Y147505D01*
X683538Y147872D01*
X683532Y147959D01*
G37*
G36*
G01X683390Y110018D02*
X683706D01*
G03X683863Y110095I-1J200D01*
G02X685048Y110674I1185J-923D01*
G02X686550Y109172I0J-1502D01*
G02X685586Y107770I-1502J0D01*
G01X685546Y107754D01*
X685486Y107693D01*
X685351Y107331D01*
X685357Y107245D01*
X685378Y107207D01*
G02X685557Y106495I-1323J-711D01*
G02X682553I-1502J0D01*
G02X682691Y107123I1502J-1D01*
G01X682714Y107173D01*
X682702Y107283D01*
X682425Y107653D01*
X682323Y107694D01*
X682269Y107686D01*
G02X682048Y107670I-219J1486D01*
G02Y110674I0J1502D01*
G02X683233Y110095I0J-1502D01*
G03X683390Y110018I158J123D01*
G37*
G36*
G01X696157Y105329D02*
X696117Y105360D01*
G02X695516Y106561I901J1202D01*
G02X698520I1502J0D01*
G02X697794Y105275I-1502J0D01*
G01X697751Y105249D01*
X697700Y105164D01*
X697678Y104732D01*
X697720Y104643D01*
X697760Y104612D01*
G02X698315Y103779I-901J-1202D01*
G01X698327Y103731D01*
X698393Y103658D01*
X698796Y103509D01*
X698892Y103522D01*
X698933Y103550D01*
G02X699799Y103825I866J-1226D01*
G02Y100821I0J-1502D01*
G02X698343Y101955I0J1502D01*
G01X698331Y102003D01*
X698265Y102076D01*
X697862Y102225D01*
X697766Y102212D01*
X697725Y102184D01*
G02X696859Y101909I-866J1226D01*
G02X695357Y103411I0J1502D01*
G02X696083Y104697I1502J0D01*
G01X696126Y104723D01*
X696177Y104808D01*
X696199Y105240D01*
X696157Y105329D01*
G37*
G36*
G01X752428Y102731D02*
G02X752136Y103621I1210J890D01*
G02X755140I1502J0D01*
G02X753915Y102145I-1502J0D01*
G03X753666Y101515I73J-393D01*
G02X753958Y100625I-1210J-890D01*
G02X750954I-1502J0D01*
G02X752179Y102101I1502J0D01*
G03X752428Y102731I-73J393D01*
G37*
G36*
G01X716856Y101849D02*
G02X716273Y103037I919J1188D01*
G02X719277I1502J0D01*
G02X718621Y101796I-1502J0D01*
G03X718601Y101149I225J-331D01*
G02X719184Y99961I-919J-1188D01*
G02X716180I-1502J0D01*
G02X716836Y101202I1502J0D01*
G03X716856Y101849I-225J331D01*
G37*
G36*
G01X711369Y91453D02*
G02X710815Y91347I-554J1395D01*
G02X712317Y92849I0J1502D01*
G02X712271Y92481I-1502J1D01*
G03X712807Y92011I388J-98D01*
G02X713361Y92117I554J-1395D01*
G02X711859Y90615I0J-1502D01*
G02X711905Y90983I1502J-1D01*
G03X711369Y91453I-388J98D01*
G37*
G36*
G01X762208Y90701D02*
G02X761538Y91951I831J1250D01*
G02X764542I1502J0D01*
G02X763892Y90714I-1502J0D01*
G03X763897Y90051I227J-330D01*
G02X764567Y88801I-831J-1250D01*
G02X761563I-1502J0D01*
G02X762213Y90038I1502J0D01*
G03X762208Y90701I-227J330D01*
G37*
G36*
G01X673617Y217133D02*
X673323D01*
G03X673176Y217068I1J-200D01*
G02X672070Y216583I-1105J1017D01*
G02Y219587I0J1502D01*
G02X673176Y219102I1J-1502D01*
G03X673323Y219037I148J135D01*
G01X673617D01*
G03X673764Y219102I-1J200D01*
G02X674870Y219587I1105J-1017D01*
G02Y216583I0J-1502D01*
G02X673764Y217068I-1J1502D01*
G03X673617Y217133I-148J-135D01*
G37*
G36*
G01X679797Y205755D02*
X679461D01*
X679394Y205730D01*
X679366Y205706D01*
G02X678379Y205336I-987J1131D01*
G02Y208340I0J1502D01*
G02X679366Y207970I0J-1501D01*
G01X679394Y207946D01*
X679461Y207921D01*
X679797D01*
X679864Y207946D01*
X679892Y207970D01*
G02X680879Y208340I987J-1131D01*
G02Y205336I0J-1502D01*
G02X679892Y205706I0J1501D01*
G01X679864Y205730D01*
X679797Y205755D01*
G37*
G36*
G01X673609Y202310D02*
X673273D01*
X673206Y202285D01*
X673178Y202261D01*
G02X672191Y201891I-987J1131D01*
G02Y204895I0J1502D01*
G02X673178Y204525I0J-1501D01*
G01X673206Y204501D01*
X673273Y204476D01*
X673609D01*
X673676Y204501D01*
X673704Y204525D01*
G02X674691Y204895I987J-1131D01*
G02X676188Y203517I0J-1502D01*
G01X676191Y203474D01*
X676232Y203400D01*
X676539Y203168D01*
X676620Y203149D01*
X676663Y203157D01*
G02X676950Y203185I289J-1474D01*
G02X678452Y201683I0J-1502D01*
G02X677967Y200577I-1502J-1D01*
G03X677902Y200430I135J-148D01*
G01Y200136D01*
G03X677967Y199989I200J1D01*
G02X678452Y198883I-1017J-1105D01*
G02X675448I-1502J0D01*
G02X675933Y199989I1502J1D01*
G03X675998Y200136I-135J148D01*
G01Y200430D01*
G03X675933Y200577I-200J-1D01*
G02X675453Y201559I1017J1105D01*
G01X675450Y201602D01*
X675409Y201676D01*
X675102Y201908D01*
X675021Y201927D01*
X674978Y201919D01*
G02X674691Y201891I-289J1474D01*
G02X673704Y202261I0J1501D01*
G01X673676Y202285D01*
X673609Y202310D01*
G37*
G36*
G01X675913Y196259D02*
X676249D01*
X676316Y196284D01*
X676344Y196308D01*
G02X677331Y196678I987J-1131D01*
G02X678437Y196193I1J-1502D01*
G03X678584Y196128I148J135D01*
G01X678878D01*
G03X679025Y196193I-1J200D01*
G02X680131Y196678I1105J-1017D01*
G02Y193674I0J-1502D01*
G02X679025Y194159I-1J1502D01*
G03X678878Y194224I-148J-135D01*
G01X678584D01*
G03X678437Y194159I1J-200D01*
G02X677331Y193674I-1105J1017D01*
G02X676344Y194044I0J1501D01*
G01X676316Y194068D01*
X676249Y194093D01*
X675913D01*
X675846Y194068D01*
X675818Y194044D01*
G02X673844I-987J1131D01*
G01X673816Y194068D01*
X673749Y194093D01*
X673413D01*
X673346Y194068D01*
X673318Y194044D01*
G02X672331Y193674I-987J1131D01*
G02Y196678I0J1502D01*
G02X673318Y196308I0J-1501D01*
G01X673346Y196284D01*
X673413Y196259D01*
X673749D01*
X673816Y196284D01*
X673844Y196308D01*
G02X675818I987J-1131D01*
G01X675846Y196284D01*
X675913Y196259D01*
G37*
G36*
G01X690748Y137670D02*
X691064Y137881D01*
X691109Y137950D01*
X691116Y137992D01*
G02X692599Y139259I1483J-234D01*
G02Y136255I0J-1502D01*
G02X692331Y136279I-1J1502D01*
G03X692165Y136234I-36J-197D01*
G01X692069Y136151D01*
G03X692000Y135991I131J-151D01*
G02X692002Y135915I-1801J-85D01*
G01Y132515D01*
G02X692000Y132436I-1803J6D01*
G03X692069Y132276I200J-9D01*
G01X692165Y132193D01*
G03X692331Y132148I130J152D01*
G02X692599Y132172I267J-1478D01*
G02X693586Y131802I0J-1501D01*
G01X693614Y131778D01*
X693681Y131753D01*
X694017D01*
X694084Y131778D01*
X694112Y131802D01*
G02X695099Y132172I987J-1131D01*
G02X696582Y130905I0J-1501D01*
G01X696589Y130863D01*
X696634Y130794D01*
X696950Y130583D01*
X697031Y130569D01*
X697072Y130579D01*
G02X697499Y130630I426J-1751D01*
G02X697847Y130597I5J-1802D01*
G01X697887Y130589D01*
X697965Y130605D01*
X698269Y130814D01*
X698311Y130881D01*
X698318Y130922D01*
G02X699799Y132172I1481J-252D01*
G02Y129168I0J-1502D01*
G02X699618Y129179I0J1502D01*
G03X699460Y129128I-23J-199D01*
G01X699366Y129043D01*
G03X699300Y128888I134J-149D01*
G02X699302Y128828I-1800J-90D01*
G01Y125428D01*
G02X699300Y125365I-1802J26D01*
G03X699366Y125210I200J-6D01*
G01X699460Y125125D01*
G03X699618Y125074I135J148D01*
G02X699799Y125085I181J-1491D01*
G02Y122081I0J-1502D01*
G02X698318Y123333I0J1502D01*
G01X698311Y123374D01*
X698268Y123441D01*
X697965Y123651D01*
X697887Y123667D01*
X697846Y123659D01*
G02X697499Y123626I-343J1769D01*
G02X697073Y123677I0J1802D01*
G01X697031Y123687D01*
X696950Y123672D01*
X696634Y123462D01*
X696589Y123392D01*
X696583Y123350D01*
G02X695099Y122081I-1484J233D01*
G02X694111Y122451I-1J1502D01*
G01X694084Y122476D01*
X694017Y122501D01*
X693680D01*
X693614Y122476D01*
X693586Y122452D01*
G02X692599Y122082I-987J1131D01*
G02X692331Y122106I-1J1502D01*
G03X692165Y122061I-36J-197D01*
G01X692069Y121978D01*
G03X692000Y121818I131J-151D01*
G02X692002Y121742I-1801J-85D01*
G01Y118342D01*
G02X692000Y118263I-1803J6D01*
G03X692069Y118103I200J-9D01*
G01X692165Y118020D01*
G03X692331Y117975I130J152D01*
G02X692599Y117999I267J-1478D01*
G02X693586Y117629I0J-1501D01*
G01X693614Y117605D01*
X693681Y117580D01*
X694017D01*
X694084Y117605D01*
X694112Y117629D01*
G02X695099Y117999I987J-1131D01*
G02X696582Y116732I0J-1501D01*
G01X696589Y116690D01*
X696634Y116621D01*
X696950Y116410D01*
X697031Y116396D01*
X697072Y116406D01*
G02X697499Y116458I430J-1751D01*
G02X697847Y116424I0J-1803D01*
G01X697887Y116416D01*
X697965Y116432D01*
X698269Y116641D01*
X698311Y116708D01*
X698318Y116749D01*
G02X699799Y117998I1481J-254D01*
G02Y114994I0J-1502D01*
G02X699618Y115005I0J1502D01*
G03X699460Y114954I-23J-199D01*
G01X699366Y114869D01*
G03X699301Y114714I135J-148D01*
G02X699302Y114655I-1802J-60D01*
G01Y111255D01*
G02X699300Y111192I-1802J26D01*
G03X699366Y111037I200J-6D01*
G01X699460Y110952D01*
G03X699618Y110901I135J148D01*
G02X699799Y110912I181J-1491D01*
G02Y107908I0J-1502D01*
G02X698318Y109160I0J1502D01*
G01X698311Y109201D01*
X698268Y109268D01*
X697965Y109478D01*
X697887Y109494D01*
X697846Y109486D01*
G02X697499Y109452I-348J1769D01*
G02X697073Y109504I4J1803D01*
G01X697031Y109514D01*
X696950Y109499D01*
X696634Y109289D01*
X696589Y109219D01*
X696583Y109177D01*
G02X695099Y107908I-1484J233D01*
G02Y110912I0J1502D01*
G02X695367Y110888I1J-1502D01*
G03X695533Y110933I36J197D01*
G01X695629Y111016D01*
G03X695698Y111176I-131J151D01*
G02X695696Y111255I1801J85D01*
G01Y114655D01*
G02X695698Y114731I1803J-9D01*
G03X695629Y114891I-200J9D01*
G01X695533Y114974D01*
G03X695367Y115019I-130J-152D01*
G02X695099Y114995I-267J1478D01*
G02X694112Y115365I0J1501D01*
G01X694084Y115389D01*
X694017Y115414D01*
X693681D01*
X693614Y115389D01*
X693586Y115365D01*
G02X692599Y114995I-987J1131D01*
G02X691115Y116264I0J1502D01*
G01X691109Y116306D01*
X691064Y116376D01*
X690748Y116586D01*
X690667Y116601D01*
X690625Y116591D01*
G02X690199Y116540I-426J1751D01*
G02X689773Y116591I0J1802D01*
G01X689731Y116601D01*
X689650Y116586D01*
X689334Y116376D01*
X689289Y116306D01*
X689283Y116264D01*
G02X687799Y114995I-1484J233D01*
G02Y117999I0J1502D01*
G02X688067Y117975I1J-1502D01*
G03X688233Y118020I36J197D01*
G01X688329Y118103D01*
G03X688398Y118263I-131J151D01*
G02X688396Y118342I1801J85D01*
G01Y121742D01*
G02X688398Y121818I1803J-9D01*
G03X688329Y121978I-200J9D01*
G01X688233Y122061D01*
G03X688067Y122106I-130J-152D01*
G02X687799Y122082I-267J1478D01*
G02Y125086I0J1502D01*
G02X689282Y123819I0J-1501D01*
G01X689289Y123777D01*
X689334Y123708D01*
X689650Y123497D01*
X689731Y123483D01*
X689772Y123493D01*
G02X690199Y123544I426J-1751D01*
G02X690626Y123493I1J-1802D01*
G01X690667Y123483D01*
X690748Y123497D01*
X691064Y123708D01*
X691109Y123777D01*
X691116Y123819D01*
G02X692599Y125086I1483J-234D01*
G02X693587Y124716I1J-1502D01*
G01X693614Y124691D01*
X693681Y124666D01*
X694018D01*
X694084Y124691D01*
X694112Y124715D01*
G02X695099Y125085I987J-1131D01*
G02X695367Y125061I1J-1502D01*
G03X695533Y125106I36J197D01*
G01X695629Y125189D01*
G03X695698Y125349I-131J151D01*
G02X695696Y125428I1801J85D01*
G01Y128828D01*
G02X695698Y128904I1803J-9D01*
G03X695629Y129064I-200J9D01*
G01X695533Y129147D01*
G03X695367Y129192I-130J-152D01*
G02X695099Y129168I-267J1478D01*
G02X694112Y129538I0J1501D01*
G01X694084Y129562D01*
X694017Y129587D01*
X693681D01*
X693614Y129562D01*
X693586Y129538D01*
G02X692599Y129168I-987J1131D01*
G02X691115Y130437I0J1502D01*
G01X691109Y130479D01*
X691064Y130549D01*
X690748Y130759D01*
X690667Y130774D01*
X690625Y130764D01*
G02X690199Y130712I-430J1751D01*
G02X689773Y130764I4J1803D01*
G01X689731Y130774D01*
X689650Y130759D01*
X689334Y130549D01*
X689289Y130479D01*
X689283Y130437D01*
G02X687799Y129168I-1484J233D01*
G02Y132172I0J1502D01*
G02X688067Y132148I1J-1502D01*
G03X688233Y132193I36J197D01*
G01X688329Y132276D01*
G03X688398Y132436I-131J151D01*
G02X688396Y132515I1801J85D01*
G01Y135915D01*
G02X688398Y135991I1803J-9D01*
G03X688329Y136151I-200J9D01*
G01X688233Y136234D01*
G03X688067Y136279I-130J-152D01*
G02X687799Y136255I-267J1478D01*
G02Y139259I0J1502D01*
G02X689282Y137992I0J-1501D01*
G01X689289Y137950D01*
X689334Y137881D01*
X689650Y137670D01*
X689731Y137656D01*
X689772Y137666D01*
G02X690199Y137718I430J-1751D01*
G02X690626Y137666I-3J-1803D01*
G01X690667Y137656D01*
X690748Y137670D01*
G37*
G36*
G01X707219Y84108D02*
Y84460D01*
X707191Y84529D01*
X707165Y84557D01*
G02X706759Y85584I1096J1027D01*
G02X709763I1502J0D01*
G02X709357Y84557I-1502J0D01*
G01X709331Y84529D01*
X709303Y84460D01*
Y84108D01*
X709331Y84039D01*
X709357Y84011D01*
G02Y81957I-1096J-1027D01*
G01X709331Y81929D01*
X709303Y81860D01*
Y81508D01*
X709331Y81439D01*
X709357Y81411D01*
G02Y79357I-1096J-1027D01*
G01X709331Y79329D01*
X709303Y79260D01*
Y78908D01*
X709331Y78839D01*
X709357Y78811D01*
G02Y76757I-1096J-1027D01*
G01X709331Y76729D01*
X709303Y76660D01*
Y76308D01*
X709331Y76239D01*
X709357Y76211D01*
G02X709763Y75184I-1096J-1027D01*
G02X706759I-1502J0D01*
G02X707165Y76211I1502J0D01*
G01X707191Y76239D01*
X707219Y76308D01*
Y76660D01*
X707191Y76729D01*
X707165Y76757D01*
G02Y78811I1096J1027D01*
G01X707191Y78839D01*
X707219Y78908D01*
Y79260D01*
X707191Y79329D01*
X707165Y79357D01*
G02Y81411I1096J1027D01*
G01X707191Y81439D01*
X707219Y81508D01*
Y81860D01*
X707191Y81929D01*
X707165Y81957D01*
G02Y84011I1096J1027D01*
G01X707191Y84039D01*
X707219Y84108D01*
G37*
G36*
G01X725554Y83717D02*
Y84069D01*
X725526Y84138D01*
X725500Y84166D01*
G02X725094Y85193I1096J1027D01*
G02X728098I1502J0D01*
G02X727692Y84166I-1502J0D01*
G01X727666Y84138D01*
X727638Y84069D01*
Y83717D01*
X727666Y83648D01*
X727692Y83620D01*
G02Y81566I-1096J-1027D01*
G01X727666Y81538D01*
X727638Y81469D01*
Y81117D01*
X727666Y81048D01*
X727692Y81020D01*
G02Y78966I-1096J-1027D01*
G01X727666Y78938D01*
X727638Y78869D01*
Y78517D01*
X727666Y78448D01*
X727692Y78420D01*
G02Y76366I-1096J-1027D01*
G01X727666Y76338D01*
X727638Y76269D01*
Y75917D01*
X727666Y75848D01*
X727692Y75820D01*
G02X728098Y74793I-1096J-1027D01*
G02X725094I-1502J0D01*
G02X725500Y75820I1502J0D01*
G01X725526Y75848D01*
X725554Y75917D01*
Y76269D01*
X725526Y76338D01*
X725500Y76366D01*
G02Y78420I1096J1027D01*
G01X725526Y78448D01*
X725554Y78517D01*
Y78869D01*
X725526Y78938D01*
X725500Y78966D01*
G02Y81020I1096J1027D01*
G01X725526Y81048D01*
X725554Y81117D01*
Y81469D01*
X725526Y81538D01*
X725500Y81566D01*
G02Y83620I1096J1027D01*
G01X725526Y83648D01*
X725554Y83717D01*
G37*
G36*
G01X749983Y75446D02*
X749611Y75386D01*
X749542Y75341D01*
X749518Y75306D01*
G02X748269Y74638I-1249J834D01*
G02Y77642I0J1502D01*
G02X749190Y77327I1J-1502D01*
G01X749223Y77301D01*
X749303Y77281D01*
X749675Y77341D01*
X749744Y77386D01*
X749768Y77421D01*
G02X751017Y78089I1249J-834D01*
G02Y75085I0J-1502D01*
G02X750096Y75400I-1J1502D01*
G01X750063Y75426D01*
X749983Y75446D01*
G37*
G36*
G01X681839Y236121D02*
G02X684843I1502J0D01*
G02X684193Y234884I-1502J0D01*
G03X684199Y234222I227J-329D01*
G02X684869Y232971I-833J-1251D01*
G02X681865I-1502J0D01*
G02X682515Y234208I1502J0D01*
G03X682509Y234870I-227J329D01*
G02X681839Y236121I833J1251D01*
G37*
G36*
G01X679881Y221970D02*
G02X682885I1502J0D01*
G02X682515Y220983I-1501J0D01*
G01X682491Y220955D01*
X682466Y220888D01*
Y220552D01*
X682491Y220485D01*
X682515Y220457D01*
G02Y218483I-1131J-987D01*
G01X682491Y218455D01*
X682466Y218388D01*
Y218052D01*
X682491Y217985D01*
X682515Y217957D01*
G02X682885Y216970I-1131J-987D01*
G02X681383Y215468I-1502J0D01*
G02X680528Y215735I0J1502D01*
G01X680494Y215759D01*
X680413Y215775D01*
X680046Y215696D01*
X679979Y215648D01*
X679958Y215612D01*
G02X678670Y214883I-1288J773D01*
G02Y217887I0J1502D01*
G02X679525Y217620I0J-1502D01*
G01X679559Y217596D01*
X679640Y217580D01*
X680007Y217659D01*
X680074Y217707D01*
X680095Y217743D01*
G02X680251Y217957I1287J-774D01*
G01X680275Y217985D01*
X680300Y218052D01*
Y218388D01*
X680275Y218455D01*
X680251Y218483D01*
G02Y220457I1131J987D01*
G01X680275Y220485D01*
X680300Y220552D01*
Y220888D01*
X680275Y220955D01*
X680251Y220983D01*
G02X679881Y221970I1131J987D01*
G37*
G36*
G01X737579Y223294D02*
Y223630D01*
X737554Y223697D01*
X737530Y223725D01*
G02X737160Y224712I1131J987D01*
G02X740164I1502J0D01*
G02X739794Y223725I-1501J0D01*
G01X739770Y223697D01*
X739745Y223630D01*
Y223294D01*
X739770Y223227D01*
X739794Y223199D01*
G02X740164Y222212I-1131J-987D01*
G02X737160I-1502J0D01*
G02X737530Y223199I1501J0D01*
G01X737554Y223227D01*
X737579Y223294D01*
G37*
G36*
G01X732254Y225189D02*
X731960D01*
G03X731813Y225124I1J-200D01*
G02X730707Y224639I-1105J1017D01*
G02Y227643I0J1502D01*
G02X731813Y227158I1J-1502D01*
G03X731960Y227093I148J135D01*
G01X732254D01*
G03X732401Y227158I-1J200D01*
G02X733507Y227643I1105J-1017D01*
G02Y224639I0J-1502D01*
G02X732401Y225124I-1J1502D01*
G03X732254Y225189I-148J-135D01*
G37*
G36*
G01X715461Y229808D02*
Y230144D01*
X715436Y230211D01*
X715412Y230239D01*
G02X715042Y231226I1131J987D01*
G02X718046I1502J0D01*
G02X717676Y230239I-1501J0D01*
G01X717652Y230211D01*
X717627Y230144D01*
Y229808D01*
X717652Y229741D01*
X717676Y229713D01*
G02Y227739I-1131J-987D01*
G01X717652Y227711D01*
X717627Y227644D01*
Y227308D01*
X717652Y227241D01*
X717676Y227213D01*
G02Y225239I-1131J-987D01*
G01X717652Y225211D01*
X717627Y225144D01*
Y224808D01*
X717652Y224741D01*
X717676Y224713D01*
G02X718046Y223726I-1131J-987D01*
G02X715042I-1502J0D01*
G02X715412Y224713I1501J0D01*
G01X715436Y224741D01*
X715461Y224808D01*
Y225144D01*
X715436Y225211D01*
X715412Y225239D01*
G02Y227213I1131J987D01*
G01X715436Y227241D01*
X715461Y227308D01*
Y227644D01*
X715436Y227711D01*
X715412Y227739D01*
G02Y229713I1131J987D01*
G01X715436Y229741D01*
X715461Y229808D01*
G37*
G36*
G01X725917Y230043D02*
Y230379D01*
X725892Y230446D01*
X725868Y230474D01*
G02X725498Y231461I1131J987D01*
G02X728502I1502J0D01*
G02X728132Y230474I-1501J0D01*
G01X728108Y230446D01*
X728083Y230379D01*
Y230043D01*
X728108Y229976D01*
X728132Y229948D01*
G02Y227974I-1131J-987D01*
G01X728108Y227946D01*
X728083Y227879D01*
Y227543D01*
X728108Y227476D01*
X728132Y227448D01*
G02X728502Y226461I-1131J-987D01*
G02X728017Y225355I-1502J-1D01*
G03X727952Y225208I135J-148D01*
G01Y224914D01*
G03X728017Y224767I200J1D01*
G02X728502Y223661I-1017J-1105D01*
G02X725498I-1502J0D01*
G02X725983Y224767I1502J1D01*
G03X726048Y224914I-135J148D01*
G01Y225208D01*
G03X725983Y225355I-200J-1D01*
G02X725498Y226461I1017J1105D01*
G02X725868Y227448I1501J0D01*
G01X725892Y227476D01*
X725917Y227543D01*
Y227879D01*
X725892Y227946D01*
X725868Y227974D01*
G02Y229948I1131J987D01*
G01X725892Y229976D01*
X725917Y230043D01*
G37*
G36*
G01X733886Y230368D02*
Y230704D01*
X733861Y230771D01*
X733837Y230799D01*
G02X733467Y231786I1131J987D01*
G02X736471I1502J0D01*
G02X736101Y230799I-1501J0D01*
G01X736077Y230771D01*
X736052Y230704D01*
Y230368D01*
X736077Y230301D01*
X736101Y230273D01*
G02X736471Y229286I-1131J-987D01*
G02X733467I-1502J0D01*
G02X733837Y230273I1501J0D01*
G01X733861Y230301D01*
X733886Y230368D01*
G37*
G36*
G01X732032Y237694D02*
X732368D01*
X732435Y237719D01*
X732463Y237743D01*
G02X734437I987J-1131D01*
G01X734465Y237719D01*
X734532Y237694D01*
X734868D01*
X734935Y237719D01*
X734963Y237743D01*
G02X735950Y238113I987J-1131D01*
G02Y235109I0J-1502D01*
G02X734963Y235479I0J1501D01*
G01X734935Y235503D01*
X734868Y235528D01*
X734532D01*
X734465Y235503D01*
X734437Y235479D01*
G02X732463I-987J1131D01*
G01X732435Y235503D01*
X732368Y235528D01*
X732032D01*
X731965Y235503D01*
X731937Y235479D01*
G02X730950Y235109I-987J1131D01*
G02Y238113I0J1502D01*
G02X731937Y237743I0J-1501D01*
G01X731965Y237719D01*
X732032Y237694D01*
G37*
G36*
G01X731734Y249974D02*
X732070D01*
X732137Y249999D01*
X732165Y250023D01*
G02X734139I987J-1131D01*
G01X734167Y249999D01*
X734234Y249974D01*
X734570D01*
X734637Y249999D01*
X734665Y250023D01*
G02X735652Y250393I987J-1131D01*
G02Y247389I0J-1502D01*
G02X734665Y247759I0J1501D01*
G01X734637Y247783D01*
X734570Y247808D01*
X734234D01*
X734167Y247783D01*
X734139Y247759D01*
G02X732165I-987J1131D01*
G01X732137Y247783D01*
X732070Y247808D01*
X731734D01*
X731667Y247783D01*
X731639Y247759D01*
G02X730652Y247389I-987J1131D01*
G02Y250393I0J1502D01*
G02X731639Y250023I0J-1501D01*
G01X731667Y249999D01*
X731734Y249974D01*
G37*
G36*
G01X736029Y190705D02*
G02X735381Y191941I855J1236D01*
G02X738385I1502J0D01*
G02X737632Y190639I-1502J0D01*
G03X737604Y189963I199J-347D01*
G02X738252Y188727I-855J-1236D01*
G02X735248I-1502J0D01*
G02X736001Y190029I1502J0D01*
G03X736029Y190705I-199J347D01*
G37*
G36*
G01X759948Y186629D02*
G02X762952I1502J0D01*
G02X761949Y185212I-1502J0D01*
G01X761948D01*
G03X761826Y185090I67J-189D01*
G01X761723Y184796D01*
G03X761740Y184625I188J-68D01*
G01X761741Y184624D01*
G02X761966Y183834I-1277J-791D01*
G02X758962I-1502J0D01*
G02X759965Y185251I1502J0D01*
G01X759966D01*
G03X760088Y185373I-67J189D01*
G01X760191Y185667D01*
G03X760174Y185838I-188J68D01*
G01X760173Y185839D01*
G02X759948Y186629I1277J791D01*
G37*
G36*
G01X755516Y1615011D02*
G03X755544Y1615652I-224J331D01*
G03X755528Y1615664I-128J-154D01*
G02X754855Y1616917I830J1253D01*
G02X757861I1503J0D01*
G02X757188Y1615664I-1503J0D01*
G03X757172Y1615652I112J-166D01*
G03X757200Y1615011I252J-310D01*
G02X757860Y1613767I-842J-1244D01*
G02X754856I-1502J0D01*
G02X755516Y1615011I1502J0D01*
G37*
G36*
G01X768910Y1439243D02*
G02Y1436239I0J-1502D01*
G02X767741Y1436798I0J1502D01*
G03X767069Y1436719I-311J-251D01*
G02X765713Y1435863I-1356J646D01*
G02Y1438867I0J1502D01*
G02X766882Y1438308I0J-1502D01*
G03X767554Y1438387I311J251D01*
G02X768910Y1439243I1356J-646D01*
G37*
G36*
G01X775612Y1442270D02*
G02X778616I1502J0D01*
G02X778310Y1441361I-1503J0D01*
G01X778283Y1441325D01*
X778264Y1441240D01*
X778340Y1440898D01*
G03X778443Y1440764I195J44D01*
G02X779251Y1439432I-694J-1332D01*
G02X776247I-1502J0D01*
G02X776553Y1440341I1503J0D01*
G01X776580Y1440377D01*
X776599Y1440462D01*
X776523Y1440804D01*
G03X776420Y1440938I-195J-44D01*
G02X775612Y1442270I694J1332D01*
G37*
G36*
G01X788815Y1441586D02*
G03X788613Y1441561I-80J-183D01*
G02X787694Y1441247I-919J1188D01*
G02Y1444251I0J1502D01*
G02X789191Y1442872I0J-1502D01*
G01Y1442871D01*
X789196Y1442817D01*
X789226Y1442773D01*
G03X789257Y1442738I164J114D01*
G01X789283Y1442714D01*
X789633Y1442562D01*
G03X789835Y1442587I80J183D01*
G02X790754Y1442901I919J-1188D01*
G02X792009Y1442224I0J-1502D01*
G03X792183Y1442134I167J110D01*
G01X792575Y1442146D01*
X792664Y1442199D01*
X792690Y1442245D01*
G02X793994Y1443001I1304J-747D01*
G02Y1439997I0J-1502D01*
G02X792739Y1440674I0J1502D01*
G03X792565Y1440764I-167J-110D01*
G01X792173Y1440752D01*
X792084Y1440699D01*
X792058Y1440653D01*
G02X790754Y1439897I-1304J747D01*
G02X789257Y1441276I0J1502D01*
G01Y1441277D01*
X789252Y1441331D01*
X789208Y1441394D01*
X789189Y1441412D01*
G03X789135Y1441447I-134J-148D01*
G01X788815Y1441586D01*
G37*
G36*
G01X796478Y1469259D02*
G03X796527Y1469965I-161J366D01*
G02X795816Y1471242I791J1277D01*
G02X798820I1502J0D01*
G02X797923Y1469867I-1502J0D01*
G03X797874Y1469161I161J-366D01*
G02X798586Y1467883I-791J-1278D01*
G02X795580I-1503J0D01*
G02X796478Y1469259I1503J0D01*
G37*
G36*
G01X785894Y147959D02*
X785873Y147998D01*
G02X785690Y148717I1319J719D01*
G02X788694I1502J0D01*
G02X787689Y147300I-1501J0D01*
G01X787647Y147285D01*
X787584Y147224D01*
X787443Y146857D01*
X787449Y146770D01*
X787470Y146731D01*
G02X787653Y146012I-1319J-719D01*
G02X786993Y144768I-1502J0D01*
G03X786905Y144603I112J-166D01*
G01Y144271D01*
G03X786993Y144106I200J1D01*
G02X787638Y143074I-842J-1244D01*
G01X787643Y143037D01*
X787677Y142974D01*
X787935Y142754D01*
X788001Y142729D01*
X788039Y142730D01*
X788057D01*
G02Y139726I0J-1502D01*
G02X786570Y141016I0J1502D01*
G01X786565Y141053D01*
X786531Y141116D01*
X786273Y141336D01*
X786207Y141361D01*
X786169Y141360D01*
X786151D01*
G02X784649Y142862I0J1502D01*
G02X785309Y144106I1502J0D01*
G03X785397Y144271I-112J166D01*
G01Y144603D01*
G03X785309Y144768I-200J-1D01*
G02X784649Y146012I842J1244D01*
G02X785654Y147429I1501J0D01*
G01X785696Y147444D01*
X785759Y147505D01*
X785900Y147872D01*
X785894Y147959D01*
G37*
G36*
G01X793229Y138793D02*
X793180Y138795D01*
G02X791719Y140296I41J1501D01*
G02X794723I1502J0D01*
G02X794636Y139792I-1503J0D01*
G01X794620Y139746D01*
X794632Y139653D01*
X794870Y139305D01*
X794953Y139260D01*
X795002Y139258D01*
G02X796463Y137757I-41J-1501D01*
G02X794961Y136255I-1502J0D01*
G02X794693Y136279I-1J1502D01*
G03X794527Y136234I-36J-197D01*
G01X794431Y136151D01*
G03X794362Y135991I131J-151D01*
G02X794364Y135915I-1801J-85D01*
G01Y132515D01*
G02X794362Y132436I-1803J6D01*
G03X794431Y132276I200J-9D01*
G01X794527Y132193D01*
G03X794693Y132148I130J152D01*
G02X794961Y132172I267J-1478D01*
G02X795948Y131802I0J-1501D01*
G01X795976Y131778D01*
X796043Y131753D01*
X796379D01*
X796446Y131778D01*
X796474Y131802D01*
G02X797461Y132172I987J-1131D01*
G02X798944Y130905I0J-1501D01*
G01X798951Y130863D01*
X798996Y130794D01*
X799312Y130583D01*
X799393Y130569D01*
X799434Y130579D01*
G02X799861Y130630I426J-1751D01*
G02X800209Y130597I5J-1802D01*
G01X800249Y130589D01*
X800327Y130605D01*
X800631Y130814D01*
X800673Y130881D01*
X800680Y130922D01*
G02X802161Y132172I1481J-252D01*
G02Y129168I0J-1502D01*
G02X801980Y129179I0J1502D01*
G03X801822Y129128I-23J-199D01*
G01X801728Y129043D01*
G03X801662Y128888I134J-149D01*
G02X801664Y128828I-1800J-90D01*
G01Y125428D01*
G02X801662Y125365I-1802J26D01*
G03X801728Y125210I200J-6D01*
G01X801822Y125125D01*
G03X801980Y125074I135J148D01*
G02X802161Y125085I181J-1491D01*
G02Y122081I0J-1502D01*
G02X800680Y123333I0J1502D01*
G01X800673Y123374D01*
X800630Y123441D01*
X800327Y123651D01*
X800249Y123667D01*
X800208Y123659D01*
G02X799861Y123626I-343J1769D01*
G02X799435Y123677I0J1802D01*
G01X799393Y123687D01*
X799312Y123672D01*
X798996Y123462D01*
X798951Y123392D01*
X798945Y123350D01*
G02X797461Y122081I-1484J233D01*
G02X796473Y122451I-1J1502D01*
G01X796446Y122476D01*
X796379Y122501D01*
X796042D01*
X795976Y122476D01*
X795948Y122452D01*
G02X794961Y122082I-987J1131D01*
G02X794693Y122106I-1J1502D01*
G03X794527Y122061I-36J-197D01*
G01X794431Y121978D01*
G03X794362Y121818I131J-151D01*
G02X794364Y121742I-1801J-85D01*
G01Y118342D01*
G02X794362Y118263I-1803J6D01*
G03X794431Y118103I200J-9D01*
G01X794527Y118020D01*
G03X794693Y117975I130J152D01*
G02X794961Y117999I267J-1478D01*
G02X795948Y117629I0J-1501D01*
G01X795976Y117605D01*
X796043Y117580D01*
X796379D01*
X796446Y117605D01*
X796474Y117629D01*
G02X797461Y117999I987J-1131D01*
G02X798944Y116732I0J-1501D01*
G01X798951Y116690D01*
X798996Y116621D01*
X799312Y116410D01*
X799393Y116396D01*
X799434Y116406D01*
G02X799861Y116458I430J-1751D01*
G02X800209Y116424I0J-1803D01*
G01X800249Y116416D01*
X800327Y116432D01*
X800631Y116641D01*
X800673Y116708D01*
X800680Y116749D01*
G02X802161Y117998I1481J-254D01*
G02Y114994I0J-1502D01*
G02X801980Y115005I0J1502D01*
G03X801822Y114954I-23J-199D01*
G01X801728Y114869D01*
G03X801663Y114714I135J-148D01*
G02X801664Y114655I-1802J-60D01*
G01Y111255D01*
G02X801662Y111192I-1802J26D01*
G03X801728Y111037I200J-6D01*
G01X801822Y110952D01*
G03X801980Y110901I135J148D01*
G02X802161Y110912I181J-1491D01*
G02Y107908I0J-1502D01*
G02X800680Y109160I0J1502D01*
G01X800673Y109201D01*
X800630Y109268D01*
X800327Y109478D01*
X800249Y109494D01*
X800208Y109486D01*
G02X799861Y109452I-348J1769D01*
G02X799435Y109504I4J1803D01*
G01X799393Y109514D01*
X799312Y109499D01*
X798996Y109289D01*
X798951Y109219D01*
X798945Y109177D01*
G02X797461Y107908I-1484J233D01*
G02Y110912I0J1502D01*
G02X797729Y110888I1J-1502D01*
G03X797895Y110933I36J197D01*
G01X797991Y111016D01*
G03X798060Y111176I-131J151D01*
G02X798058Y111255I1801J85D01*
G01Y114655D01*
G02X798060Y114731I1803J-9D01*
G03X797991Y114891I-200J9D01*
G01X797895Y114974D01*
G03X797729Y115019I-130J-152D01*
G02X797461Y114995I-267J1478D01*
G02X796474Y115365I0J1501D01*
G01X796446Y115389D01*
X796379Y115414D01*
X796043D01*
X795976Y115389D01*
X795948Y115365D01*
G02X794961Y114995I-987J1131D01*
G02X793477Y116264I0J1502D01*
G01X793471Y116306D01*
X793426Y116376D01*
X793110Y116586D01*
X793029Y116601D01*
X792987Y116591D01*
G02X792561Y116540I-426J1751D01*
G02X792135Y116591I0J1802D01*
G01X792093Y116601D01*
X792012Y116586D01*
X791696Y116376D01*
X791651Y116306D01*
X791645Y116264D01*
G02X790161Y114995I-1484J233D01*
G02Y117999I0J1502D01*
G02X790429Y117975I1J-1502D01*
G03X790595Y118020I36J197D01*
G01X790691Y118103D01*
G03X790760Y118263I-131J151D01*
G02X790758Y118342I1801J85D01*
G01Y121742D01*
G02X790760Y121818I1803J-9D01*
G03X790691Y121978I-200J9D01*
G01X790595Y122061D01*
G03X790429Y122106I-130J-152D01*
G02X790161Y122082I-267J1478D01*
G02Y125086I0J1502D01*
G02X791644Y123819I0J-1501D01*
G01X791651Y123777D01*
X791696Y123708D01*
X792012Y123497D01*
X792093Y123483D01*
X792134Y123493D01*
G02X792561Y123544I426J-1751D01*
G02X792988Y123493I1J-1802D01*
G01X793029Y123483D01*
X793110Y123497D01*
X793426Y123708D01*
X793471Y123777D01*
X793478Y123819D01*
G02X794961Y125086I1483J-234D01*
G02X795949Y124716I1J-1502D01*
G01X795976Y124691D01*
X796043Y124666D01*
X796380D01*
X796446Y124691D01*
X796474Y124715D01*
G02X797461Y125085I987J-1131D01*
G02X797729Y125061I1J-1502D01*
G03X797895Y125106I36J197D01*
G01X797991Y125189D01*
G03X798060Y125349I-131J151D01*
G02X798058Y125428I1801J85D01*
G01Y128828D01*
G02X798060Y128904I1803J-9D01*
G03X797991Y129064I-200J9D01*
G01X797895Y129147D01*
G03X797729Y129192I-130J-152D01*
G02X797461Y129168I-267J1478D01*
G02X796474Y129538I0J1501D01*
G01X796446Y129562D01*
X796379Y129587D01*
X796043D01*
X795976Y129562D01*
X795948Y129538D01*
G02X794961Y129168I-987J1131D01*
G02X793477Y130437I0J1502D01*
G01X793471Y130479D01*
X793426Y130549D01*
X793110Y130759D01*
X793029Y130774D01*
X792987Y130764D01*
G02X792561Y130712I-430J1751D01*
G02X792135Y130764I4J1803D01*
G01X792093Y130774D01*
X792012Y130759D01*
X791696Y130549D01*
X791651Y130479D01*
X791645Y130437D01*
G02X790161Y129168I-1484J233D01*
G02Y132172I0J1502D01*
G02X790429Y132148I1J-1502D01*
G03X790595Y132193I36J197D01*
G01X790691Y132276D01*
G03X790760Y132436I-131J151D01*
G02X790758Y132515I1801J85D01*
G01Y135915D01*
G02X790760Y135991I1803J-9D01*
G03X790691Y136151I-200J9D01*
G01X790595Y136234D01*
G03X790429Y136279I-130J-152D01*
G02X790161Y136255I-267J1478D01*
G02Y139259I0J1502D01*
G02X791644Y137992I0J-1501D01*
G01X791651Y137950D01*
X791696Y137881D01*
X792012Y137670D01*
X792093Y137656D01*
X792134Y137666D01*
G02X792561Y137718I430J-1751D01*
G02X792988Y137666I-3J-1803D01*
G01X793029Y137656D01*
X793110Y137670D01*
X793426Y137881D01*
X793471Y137950D01*
X793478Y137992D01*
G02X793546Y138261I1484J-232D01*
G01X793562Y138307D01*
X793550Y138400D01*
X793312Y138748D01*
X793229Y138793D01*
G37*
G36*
G01X785752Y110018D02*
X786068D01*
G03X786225Y110095I-1J200D01*
G02X787410Y110674I1185J-923D01*
G02X788912Y109172I0J-1502D01*
G02X787948Y107770I-1502J0D01*
G01X787908Y107754D01*
X787848Y107693D01*
X787713Y107331D01*
X787719Y107245D01*
X787740Y107207D01*
G02X787919Y106495I-1323J-711D01*
G02X784915I-1502J0D01*
G02X785053Y107123I1502J-1D01*
G01X785076Y107173D01*
X785064Y107283D01*
X784787Y107653D01*
X784685Y107694D01*
X784631Y107686D01*
G02X784410Y107670I-219J1486D01*
G02Y110674I0J1502D01*
G02X785595Y110095I0J-1502D01*
G03X785752Y110018I158J123D01*
G37*
G36*
G01X798519Y105329D02*
X798479Y105360D01*
G02X797878Y106561I901J1202D01*
G02X800882I1502J0D01*
G02X800156Y105275I-1502J0D01*
G01X800113Y105249D01*
X800062Y105164D01*
X800040Y104732D01*
X800082Y104643D01*
X800122Y104612D01*
G02X800677Y103779I-901J-1202D01*
G01X800689Y103731D01*
X800755Y103658D01*
X801158Y103509D01*
X801254Y103522D01*
X801295Y103550D01*
G02X802161Y103825I866J-1226D01*
G02Y100821I0J-1502D01*
G02X800705Y101955I0J1502D01*
G01X800693Y102003D01*
X800627Y102076D01*
X800224Y102225D01*
X800128Y102212D01*
X800087Y102184D01*
G02X799221Y101909I-866J1226D01*
G02X797719Y103411I0J1502D01*
G02X798445Y104697I1502J0D01*
G01X798488Y104723D01*
X798539Y104808D01*
X798561Y105240D01*
X798519Y105329D01*
G37*
G36*
G01X854790Y102731D02*
G02X854498Y103621I1210J890D01*
G02X857502I1502J0D01*
G02X856277Y102145I-1502J0D01*
G03X856028Y101515I73J-393D01*
G02X856320Y100625I-1210J-890D01*
G02X853316I-1502J0D01*
G02X854541Y102101I1502J0D01*
G03X854790Y102731I-73J393D01*
G37*
G36*
G01X819218Y101849D02*
G02X818635Y103037I919J1188D01*
G02X821639I1502J0D01*
G02X820983Y101796I-1502J0D01*
G03X820963Y101149I225J-331D01*
G02X821546Y99961I-919J-1188D01*
G02X818542I-1502J0D01*
G02X819198Y101202I1502J0D01*
G03X819218Y101849I-225J331D01*
G37*
G36*
G01X813731Y91453D02*
G02X813177Y91347I-554J1395D01*
G02X814679Y92849I0J1502D01*
G02X814633Y92481I-1502J1D01*
G03X815169Y92011I388J-98D01*
G02X815723Y92117I554J-1395D01*
G02X814221Y90615I0J-1502D01*
G02X814267Y90983I1502J-1D01*
G03X813731Y91453I-388J98D01*
G37*
G36*
G01X864570Y90701D02*
G02X863900Y91951I831J1250D01*
G02X866904I1502J0D01*
G02X866254Y90714I-1502J0D01*
G03X866259Y90051I227J-330D01*
G02X866929Y88801I-831J-1250D01*
G02X863925I-1502J0D01*
G02X864575Y90038I1502J0D01*
G03X864570Y90701I-227J330D01*
G37*
G36*
G01X775979Y217133D02*
X775685D01*
G03X775538Y217068I1J-200D01*
G02X774432Y216583I-1105J1017D01*
G02Y219587I0J1502D01*
G02X775538Y219102I1J-1502D01*
G03X775685Y219037I148J135D01*
G01X775979D01*
G03X776126Y219102I-1J200D01*
G02X777232Y219587I1105J-1017D01*
G02Y216583I0J-1502D01*
G02X776126Y217068I-1J1502D01*
G03X775979Y217133I-148J-135D01*
G37*
G36*
G01X782159Y205755D02*
X781823D01*
X781756Y205730D01*
X781728Y205706D01*
G02X780741Y205336I-987J1131D01*
G02Y208340I0J1502D01*
G02X781728Y207970I0J-1501D01*
G01X781756Y207946D01*
X781823Y207921D01*
X782159D01*
X782226Y207946D01*
X782254Y207970D01*
G02X783241Y208340I987J-1131D01*
G02Y205336I0J-1502D01*
G02X782254Y205706I0J1501D01*
G01X782226Y205730D01*
X782159Y205755D01*
G37*
G36*
G01X775971Y202310D02*
X775635D01*
X775568Y202285D01*
X775540Y202261D01*
G02X774553Y201891I-987J1131D01*
G02Y204895I0J1502D01*
G02X775540Y204525I0J-1501D01*
G01X775568Y204501D01*
X775635Y204476D01*
X775971D01*
X776038Y204501D01*
X776066Y204525D01*
G02X777053Y204895I987J-1131D01*
G02X778550Y203517I0J-1502D01*
G01X778553Y203474D01*
X778594Y203400D01*
X778901Y203168D01*
X778982Y203149D01*
X779025Y203157D01*
G02X779312Y203185I289J-1474D01*
G02X780814Y201683I0J-1502D01*
G02X780329Y200577I-1502J-1D01*
G03X780264Y200430I135J-148D01*
G01Y200136D01*
G03X780329Y199989I200J1D01*
G02X780814Y198883I-1017J-1105D01*
G02X777810I-1502J0D01*
G02X778295Y199989I1502J1D01*
G03X778360Y200136I-135J148D01*
G01Y200430D01*
G03X778295Y200577I-200J-1D01*
G02X777815Y201559I1017J1105D01*
G01X777812Y201602D01*
X777771Y201676D01*
X777464Y201908D01*
X777383Y201927D01*
X777340Y201919D01*
G02X777053Y201891I-289J1474D01*
G02X776066Y202261I0J1501D01*
G01X776038Y202285D01*
X775971Y202310D01*
G37*
G36*
G01X778275Y196259D02*
X778611D01*
X778678Y196284D01*
X778706Y196308D01*
G02X779693Y196678I987J-1131D01*
G02X780799Y196193I1J-1502D01*
G03X780946Y196128I148J135D01*
G01X781240D01*
G03X781387Y196193I-1J200D01*
G02X782493Y196678I1105J-1017D01*
G02Y193674I0J-1502D01*
G02X781387Y194159I-1J1502D01*
G03X781240Y194224I-148J-135D01*
G01X780946D01*
G03X780799Y194159I1J-200D01*
G02X779693Y193674I-1105J1017D01*
G02X778706Y194044I0J1501D01*
G01X778678Y194068D01*
X778611Y194093D01*
X778275D01*
X778208Y194068D01*
X778180Y194044D01*
G02X776206I-987J1131D01*
G01X776178Y194068D01*
X776111Y194093D01*
X775775D01*
X775708Y194068D01*
X775680Y194044D01*
G02X774693Y193674I-987J1131D01*
G02Y196678I0J1502D01*
G02X775680Y196308I0J-1501D01*
G01X775708Y196284D01*
X775775Y196259D01*
X776111D01*
X776178Y196284D01*
X776206Y196308D01*
G02X778180I987J-1131D01*
G01X778208Y196284D01*
X778275Y196259D01*
G37*
G36*
G01X809581Y84108D02*
Y84460D01*
X809553Y84529D01*
X809527Y84557D01*
G02X809121Y85584I1096J1027D01*
G02X812125I1502J0D01*
G02X811719Y84557I-1502J0D01*
G01X811693Y84529D01*
X811665Y84460D01*
Y84108D01*
X811693Y84039D01*
X811719Y84011D01*
G02Y81957I-1096J-1027D01*
G01X811693Y81929D01*
X811665Y81860D01*
Y81508D01*
X811693Y81439D01*
X811719Y81411D01*
G02Y79357I-1096J-1027D01*
G01X811693Y79329D01*
X811665Y79260D01*
Y78908D01*
X811693Y78839D01*
X811719Y78811D01*
G02Y76757I-1096J-1027D01*
G01X811693Y76729D01*
X811665Y76660D01*
Y76308D01*
X811693Y76239D01*
X811719Y76211D01*
G02X812125Y75184I-1096J-1027D01*
G02X809121I-1502J0D01*
G02X809527Y76211I1502J0D01*
G01X809553Y76239D01*
X809581Y76308D01*
Y76660D01*
X809553Y76729D01*
X809527Y76757D01*
G02Y78811I1096J1027D01*
G01X809553Y78839D01*
X809581Y78908D01*
Y79260D01*
X809553Y79329D01*
X809527Y79357D01*
G02Y81411I1096J1027D01*
G01X809553Y81439D01*
X809581Y81508D01*
Y81860D01*
X809553Y81929D01*
X809527Y81957D01*
G02Y84011I1096J1027D01*
G01X809553Y84039D01*
X809581Y84108D01*
G37*
G36*
G01X827916Y83717D02*
Y84069D01*
X827888Y84138D01*
X827862Y84166D01*
G02X827456Y85193I1096J1027D01*
G02X830460I1502J0D01*
G02X830054Y84166I-1502J0D01*
G01X830028Y84138D01*
X830000Y84069D01*
Y83717D01*
X830028Y83648D01*
X830054Y83620D01*
G02Y81566I-1096J-1027D01*
G01X830028Y81538D01*
X830000Y81469D01*
Y81117D01*
X830028Y81048D01*
X830054Y81020D01*
G02Y78966I-1096J-1027D01*
G01X830028Y78938D01*
X830000Y78869D01*
Y78517D01*
X830028Y78448D01*
X830054Y78420D01*
G02Y76366I-1096J-1027D01*
G01X830028Y76338D01*
X830000Y76269D01*
Y75917D01*
X830028Y75848D01*
X830054Y75820D01*
G02X830460Y74793I-1096J-1027D01*
G02X827456I-1502J0D01*
G02X827862Y75820I1502J0D01*
G01X827888Y75848D01*
X827916Y75917D01*
Y76269D01*
X827888Y76338D01*
X827862Y76366D01*
G02Y78420I1096J1027D01*
G01X827888Y78448D01*
X827916Y78517D01*
Y78869D01*
X827888Y78938D01*
X827862Y78966D01*
G02Y81020I1096J1027D01*
G01X827888Y81048D01*
X827916Y81117D01*
Y81469D01*
X827888Y81538D01*
X827862Y81566D01*
G02Y83620I1096J1027D01*
G01X827888Y83648D01*
X827916Y83717D01*
G37*
G36*
G01X852345Y75446D02*
X851973Y75386D01*
X851904Y75341D01*
X851880Y75306D01*
G02X850631Y74638I-1249J834D01*
G02Y77642I0J1502D01*
G02X851552Y77327I1J-1502D01*
G01X851585Y77301D01*
X851665Y77281D01*
X852037Y77341D01*
X852106Y77386D01*
X852130Y77421D01*
G02X853379Y78089I1249J-834D01*
G02Y75085I0J-1502D01*
G02X852458Y75400I-1J1502D01*
G01X852425Y75426D01*
X852345Y75446D01*
G37*
G36*
G01X784201Y236121D02*
G02X787205I1502J0D01*
G02X786555Y234884I-1502J0D01*
G03X786561Y234222I227J-329D01*
G02X787231Y232971I-833J-1251D01*
G02X784227I-1502J0D01*
G02X784877Y234208I1502J0D01*
G03X784871Y234870I-227J329D01*
G02X784201Y236121I833J1251D01*
G37*
G36*
G01X782243Y221970D02*
G02X785247I1502J0D01*
G02X784877Y220983I-1501J0D01*
G01X784853Y220955D01*
X784828Y220888D01*
Y220552D01*
X784853Y220485D01*
X784877Y220457D01*
G02Y218483I-1131J-987D01*
G01X784853Y218455D01*
X784828Y218388D01*
Y218052D01*
X784853Y217985D01*
X784877Y217957D01*
G02X785247Y216970I-1131J-987D01*
G02X783745Y215468I-1502J0D01*
G02X782890Y215735I0J1502D01*
G01X782856Y215759D01*
X782775Y215775D01*
X782408Y215696D01*
X782341Y215648D01*
X782320Y215612D01*
G02X781032Y214883I-1288J773D01*
G02Y217887I0J1502D01*
G02X781887Y217620I0J-1502D01*
G01X781921Y217596D01*
X782002Y217580D01*
X782369Y217659D01*
X782436Y217707D01*
X782457Y217743D01*
G02X782613Y217957I1287J-774D01*
G01X782637Y217985D01*
X782662Y218052D01*
Y218388D01*
X782637Y218455D01*
X782613Y218483D01*
G02Y220457I1131J987D01*
G01X782637Y220485D01*
X782662Y220552D01*
Y220888D01*
X782637Y220955D01*
X782613Y220983D01*
G02X782243Y221970I1131J987D01*
G37*
G36*
G01X839941Y223294D02*
Y223630D01*
X839916Y223697D01*
X839892Y223725D01*
G02X839522Y224712I1131J987D01*
G02X842526I1502J0D01*
G02X842156Y223725I-1501J0D01*
G01X842132Y223697D01*
X842107Y223630D01*
Y223294D01*
X842132Y223227D01*
X842156Y223199D01*
G02X842526Y222212I-1131J-987D01*
G02X839522I-1502J0D01*
G02X839892Y223199I1501J0D01*
G01X839916Y223227D01*
X839941Y223294D01*
G37*
G36*
G01X834616Y225189D02*
X834322D01*
G03X834175Y225124I1J-200D01*
G02X833069Y224639I-1105J1017D01*
G02Y227643I0J1502D01*
G02X834175Y227158I1J-1502D01*
G03X834322Y227093I148J135D01*
G01X834616D01*
G03X834763Y227158I-1J200D01*
G02X835869Y227643I1105J-1017D01*
G02Y224639I0J-1502D01*
G02X834763Y225124I-1J1502D01*
G03X834616Y225189I-148J-135D01*
G37*
G36*
G01X817823Y229808D02*
Y230144D01*
X817798Y230211D01*
X817774Y230239D01*
G02X817404Y231226I1131J987D01*
G02X820408I1502J0D01*
G02X820038Y230239I-1501J0D01*
G01X820014Y230211D01*
X819989Y230144D01*
Y229808D01*
X820014Y229741D01*
X820038Y229713D01*
G02Y227739I-1131J-987D01*
G01X820014Y227711D01*
X819989Y227644D01*
Y227308D01*
X820014Y227241D01*
X820038Y227213D01*
G02Y225239I-1131J-987D01*
G01X820014Y225211D01*
X819989Y225144D01*
Y224808D01*
X820014Y224741D01*
X820038Y224713D01*
G02X820408Y223726I-1131J-987D01*
G02X817404I-1502J0D01*
G02X817774Y224713I1501J0D01*
G01X817798Y224741D01*
X817823Y224808D01*
Y225144D01*
X817798Y225211D01*
X817774Y225239D01*
G02Y227213I1131J987D01*
G01X817798Y227241D01*
X817823Y227308D01*
Y227644D01*
X817798Y227711D01*
X817774Y227739D01*
G02Y229713I1131J987D01*
G01X817798Y229741D01*
X817823Y229808D01*
G37*
G36*
G01X828279Y230043D02*
Y230379D01*
X828254Y230446D01*
X828230Y230474D01*
G02X827860Y231461I1131J987D01*
G02X830864I1502J0D01*
G02X830494Y230474I-1501J0D01*
G01X830470Y230446D01*
X830445Y230379D01*
Y230043D01*
X830470Y229976D01*
X830494Y229948D01*
G02Y227974I-1131J-987D01*
G01X830470Y227946D01*
X830445Y227879D01*
Y227543D01*
X830470Y227476D01*
X830494Y227448D01*
G02X830864Y226461I-1131J-987D01*
G02X830379Y225355I-1502J-1D01*
G03X830314Y225208I135J-148D01*
G01Y224914D01*
G03X830379Y224767I200J1D01*
G02X830864Y223661I-1017J-1105D01*
G02X827860I-1502J0D01*
G02X828345Y224767I1502J1D01*
G03X828410Y224914I-135J148D01*
G01Y225208D01*
G03X828345Y225355I-200J-1D01*
G02X827860Y226461I1017J1105D01*
G02X828230Y227448I1501J0D01*
G01X828254Y227476D01*
X828279Y227543D01*
Y227879D01*
X828254Y227946D01*
X828230Y227974D01*
G02Y229948I1131J987D01*
G01X828254Y229976D01*
X828279Y230043D01*
G37*
G36*
G01X836248Y230368D02*
Y230704D01*
X836223Y230771D01*
X836199Y230799D01*
G02X835829Y231786I1131J987D01*
G02X838833I1502J0D01*
G02X838463Y230799I-1501J0D01*
G01X838439Y230771D01*
X838414Y230704D01*
Y230368D01*
X838439Y230301D01*
X838463Y230273D01*
G02X838833Y229286I-1131J-987D01*
G02X835829I-1502J0D01*
G02X836199Y230273I1501J0D01*
G01X836223Y230301D01*
X836248Y230368D01*
G37*
G36*
G01X834394Y237694D02*
X834730D01*
X834797Y237719D01*
X834825Y237743D01*
G02X836799I987J-1131D01*
G01X836827Y237719D01*
X836894Y237694D01*
X837230D01*
X837297Y237719D01*
X837325Y237743D01*
G02X838312Y238113I987J-1131D01*
G02Y235109I0J-1502D01*
G02X837325Y235479I0J1501D01*
G01X837297Y235503D01*
X837230Y235528D01*
X836894D01*
X836827Y235503D01*
X836799Y235479D01*
G02X834825I-987J1131D01*
G01X834797Y235503D01*
X834730Y235528D01*
X834394D01*
X834327Y235503D01*
X834299Y235479D01*
G02X833312Y235109I-987J1131D01*
G02Y238113I0J1502D01*
G02X834299Y237743I0J-1501D01*
G01X834327Y237719D01*
X834394Y237694D01*
G37*
G36*
G01X834096Y249974D02*
X834432D01*
X834499Y249999D01*
X834527Y250023D01*
G02X836501I987J-1131D01*
G01X836529Y249999D01*
X836596Y249974D01*
X836932D01*
X836999Y249999D01*
X837027Y250023D01*
G02X838014Y250393I987J-1131D01*
G02Y247389I0J-1502D01*
G02X837027Y247759I0J1501D01*
G01X836999Y247783D01*
X836932Y247808D01*
X836596D01*
X836529Y247783D01*
X836501Y247759D01*
G02X834527I-987J1131D01*
G01X834499Y247783D01*
X834432Y247808D01*
X834096D01*
X834029Y247783D01*
X834001Y247759D01*
G02X833014Y247389I-987J1131D01*
G02Y250393I0J1502D01*
G02X834001Y250023I0J-1501D01*
G01X834029Y249999D01*
X834096Y249974D01*
G37*
G36*
G01X838391Y190705D02*
G02X837743Y191941I855J1236D01*
G02X840747I1502J0D01*
G02X839994Y190639I-1502J0D01*
G03X839966Y189963I199J-347D01*
G02X840614Y188727I-855J-1236D01*
G02X837610I-1502J0D01*
G02X838363Y190029I1502J0D01*
G03X838391Y190705I-199J347D01*
G37*
G36*
G01X862434Y185330D02*
X862569Y185710D01*
X862559Y185800D01*
X862535Y185839D01*
G02X862310Y186629I1277J791D01*
G02X865314I1502J0D01*
G02X864311Y185212I-1502J0D01*
G01X864267Y185197D01*
X864204Y185133D01*
X864069Y184753D01*
X864079Y184663D01*
X864103Y184624D01*
G02X864328Y183834I-1277J-791D01*
G02X861324I-1502J0D01*
G02X862327Y185251I1502J0D01*
G01X862371Y185266D01*
X862434Y185330D01*
G37*
G36*
G01X819575Y778732D02*
X819582Y779113D01*
X819549Y779191D01*
X819518Y779220D01*
G02X819045Y780314I1029J1094D01*
G02X822049I1502J0D01*
G02X821539Y779186I-1502J0D01*
G01X821507Y779158D01*
X821472Y779082D01*
X821465Y778701D01*
X821498Y778623D01*
X821529Y778594D01*
G02X822002Y777500I-1029J-1094D01*
G02X818998I-1502J0D01*
G02X819508Y778628I1502J0D01*
G01X819540Y778656D01*
X819575Y778732D01*
G37*
G36*
G01X926783Y815977D02*
X926421Y815966D01*
X926349Y815933D01*
X926321Y815904D01*
G02X925228Y815432I-1093J1030D01*
G02Y818436I0J1502D01*
G02X926257Y818028I0J-1502D01*
G01X926286Y818001D01*
X926361Y817972D01*
X926723Y817983D01*
X926795Y818016D01*
X926823Y818045D01*
G02X927916Y818517I1093J-1030D01*
G02Y815513I0J-1502D01*
G02X926887Y815921I0J1502D01*
G01X926858Y815948D01*
X926783Y815977D01*
G37*
G36*
G01X944482Y818498D02*
X944091Y818503D01*
X944013Y818468D01*
X943983Y818435D01*
G02X942858Y817928I-1125J995D01*
G02Y820932I0J1502D01*
G02X944006Y820399I0J-1503D01*
G01X944034Y820365D01*
X944112Y820329D01*
X944503Y820324D01*
X944581Y820359D01*
X944611Y820392D01*
G02X945736Y820899I1125J-995D01*
G02Y817895I0J-1502D01*
G02X944588Y818428I0J1503D01*
G01X944560Y818462D01*
X944482Y818498D01*
G37*
G36*
G01X933990Y824205D02*
X933690D01*
G03X933541Y824138I0J-200D01*
G02X932418Y823633I-1123J996D01*
G02Y826637I0J1502D01*
G02X933541Y826132I0J-1501D01*
G03X933690Y826065I149J133D01*
G01X933990D01*
G03X934139Y826132I0J200D01*
G02X935262Y826637I1123J-996D01*
G02Y823633I0J-1502D01*
G02X934139Y824138I0J1501D01*
G03X933990Y824205I-149J-133D01*
G37*
G36*
G01X967038Y827052D02*
X966905Y827419D01*
X966844Y827482D01*
X966803Y827497D01*
G02X965835Y828901I534J1404D01*
G02X968839I1502J0D01*
G02X968646Y828165I-1502J1D01*
G01X968625Y828127D01*
X968618Y828040D01*
X968751Y827673D01*
X968812Y827610D01*
X968853Y827595D01*
G02X969821Y826191I-534J-1404D01*
G02X966817I-1502J0D01*
G02X967010Y826927I1502J-1D01*
G01X967031Y826965D01*
X967038Y827052D01*
G37*
G36*
G01X876009Y828642D02*
X875883Y828959D01*
X875834Y829013D01*
X875801Y829030D01*
G02X874973Y830372I674J1342D01*
G02X877977I1502J0D01*
G02X877885Y829855I-1502J1D01*
G01X877872Y829820D01*
X877873Y829747D01*
X877999Y829430D01*
X878048Y829376D01*
X878081Y829359D01*
G02X878909Y828017I-674J-1342D01*
G02X875905I-1502J0D01*
G02X875997Y828534I1502J-1D01*
G01X876010Y828569D01*
X876009Y828642D01*
G37*
G36*
G01X863774Y829880D02*
X863847Y830256D01*
X863828Y830338D01*
X863802Y830372D01*
G02X863502Y831273I1203J901D01*
G02X866506I1502J0D01*
G02X865779Y829987I-1501J0D01*
G01X865743Y829964D01*
X865694Y829896D01*
X865621Y829520D01*
X865640Y829438D01*
X865666Y829404D01*
G02X865966Y828503I-1203J-901D01*
G02X862962I-1502J0D01*
G02X863689Y829789I1501J0D01*
G01X863725Y829812D01*
X863774Y829880D01*
G37*
G36*
G01X836907Y832830D02*
X837156Y833057D01*
X837188Y833120D01*
X837193Y833157D01*
G02X838685Y834489I1492J-170D01*
G02X840187Y832987I0J-1502D01*
G02X840176Y832803I-1502J-3D01*
G01X840171Y832766D01*
X840189Y832695D01*
X840384Y832414D01*
X840444Y832373D01*
X840481Y832365D01*
G02X841638Y830903I-345J-1462D01*
G02X840136Y829401I-1502J0D01*
G02X838746Y830333I0J1503D01*
G01X838726Y830383D01*
X838639Y830449D01*
X838185Y830504D01*
X838085Y830461D01*
X838053Y830417D01*
G02X836839Y829799I-1214J883D01*
G02X835337Y831301I0J1502D01*
G02X836804Y832803I1502J0D01*
G01X836841D01*
X836907Y832830D01*
G37*
G36*
G01X849931Y834507D02*
X849637D01*
G03X849490Y834442I1J-200D01*
G02X848384Y833957I-1105J1017D01*
G02Y836961I0J1502D01*
G02X849490Y836476I1J-1502D01*
G03X849637Y836411I148J135D01*
G01X849931D01*
G03X850078Y836476I-1J200D01*
G02X851184Y836961I1105J-1017D01*
G02Y833957I0J-1502D01*
G02X850078Y834442I-1J1502D01*
G03X849931Y834507I-148J-135D01*
G37*
G36*
G01Y838507D02*
X849637D01*
G03X849490Y838442I1J-200D01*
G02X848384Y837957I-1105J1017D01*
G02Y840961I0J1502D01*
G02X849490Y840476I1J-1502D01*
G03X849637Y840411I148J135D01*
G01X849931D01*
G03X850078Y840476I-1J200D01*
G02X851184Y840961I1105J-1017D01*
G02Y837957I0J-1502D01*
G02X850078Y838442I-1J1502D01*
G03X849931Y838507I-148J-135D01*
G37*
G36*
G01Y842507D02*
X849637D01*
G03X849490Y842442I1J-200D01*
G02X848384Y841957I-1105J1017D01*
G02Y844961I0J1502D01*
G02X849490Y844476I1J-1502D01*
G03X849637Y844411I148J135D01*
G01X849931D01*
G03X850078Y844476I-1J200D01*
G02X851184Y844961I1105J-1017D01*
G02Y841957I0J-1502D01*
G02X850078Y842442I-1J1502D01*
G03X849931Y842507I-148J-135D01*
G37*
G36*
G01X837010Y842480D02*
X836665Y842502D01*
X836594Y842480D01*
X836565Y842456D01*
G02X835626Y842127I-938J1173D01*
G02Y845131I0J1502D01*
G02X836711Y844667I-1J-1502D01*
G01X836737Y844640D01*
X836805Y844608D01*
X837150Y844586D01*
X837221Y844608D01*
X837250Y844632D01*
G02X838189Y844961I938J-1173D01*
G02Y841957I0J-1502D01*
G02X837104Y842421I1J1502D01*
G01X837078Y842448D01*
X837010Y842480D01*
G37*
G36*
G01X932140Y842160D02*
X932144Y842557D01*
X932108Y842636D01*
X932074Y842666D01*
G02X931552Y843804I979J1138D01*
G02X934556I1502J0D01*
G02X934008Y842644I-1502J0D01*
G01X933973Y842615D01*
X933935Y842537D01*
X933931Y842140D01*
X933967Y842061D01*
X934001Y842031D01*
G02X934523Y840893I-979J-1138D01*
G02X931519I-1502J0D01*
G02X932067Y842053I1502J0D01*
G01X932102Y842082D01*
X932140Y842160D01*
G37*
G36*
G01X847644Y846390D02*
X847307Y846394D01*
X847240Y846370D01*
X847212Y846346D01*
G02X846239Y845988I-973J1143D01*
G02Y848992I0J1502D01*
G02X847240Y848610I0J-1503D01*
G01X847268Y848585D01*
X847334Y848559D01*
X847671Y848555D01*
X847738Y848579D01*
X847766Y848603D01*
G02X848739Y848961I973J-1143D01*
G02X849726Y848591I0J-1501D01*
G01X849754Y848567D01*
X849821Y848542D01*
X850157D01*
X850224Y848567D01*
X850252Y848591D01*
G02X851239Y848961I987J-1131D01*
G02Y845957I0J-1502D01*
G02X850252Y846327I0J1501D01*
G01X850224Y846351D01*
X850157Y846376D01*
X849821D01*
X849754Y846351D01*
X849726Y846327D01*
G02X848739Y845957I-987J1131D01*
G02X847738Y846339I0J1503D01*
G01X847710Y846364D01*
X847644Y846390D01*
G37*
G36*
G01X849931Y850507D02*
X849637D01*
G03X849490Y850442I1J-200D01*
G02X848384Y849957I-1105J1017D01*
G02Y852961I0J1502D01*
G02X849490Y852476I1J-1502D01*
G03X849637Y852411I148J135D01*
G01X849931D01*
G03X850078Y852476I-1J200D01*
G02X851184Y852961I1105J-1017D01*
G02Y849957I0J-1502D01*
G02X850078Y850442I-1J1502D01*
G03X849931Y850507I-148J-135D01*
G37*
G36*
G01X831580Y854992D02*
X831815Y855276D01*
X831839Y855354D01*
X831834Y855394D01*
G02X831825Y855560I1493J164D01*
G02X834829I1502J0D01*
G02X833443Y854062I-1503J0D01*
G01X833402Y854059D01*
X833330Y854022D01*
X833095Y853738D01*
X833071Y853660D01*
X833076Y853620D01*
G02X833085Y853454I-1493J-164D01*
G02X831583Y851952I-1502J0D01*
G02X831025Y852060I1J1502D01*
G01X830982Y852077D01*
X830892Y852071D01*
X830541Y851873D01*
X830489Y851799D01*
X830482Y851754D01*
G02X829000Y850498I-1482J246D01*
G02Y853502I0J1502D01*
G02X829558Y853394I-1J-1502D01*
G01X829601Y853377D01*
X829691Y853383D01*
X830042Y853581D01*
X830094Y853655D01*
X830101Y853700D01*
G02X831467Y854952I1482J-246D01*
G01X831508Y854955D01*
X831580Y854992D01*
G37*
G36*
G01X981827Y854303D02*
G03X981497Y854812I-384J113D01*
G02X980198Y856300I203J1488D01*
G02X983202I1502J0D01*
G02X983142Y855880I-1502J0D01*
G03X983472Y855371I384J-113D01*
G02X984771Y853883I-203J-1488D01*
G02X981767I-1502J0D01*
G02X981827Y854303I1502J0D01*
G37*
G36*
G01X860974Y858451D02*
X860616Y858448D01*
X860545Y858418D01*
X860517Y858391D01*
G02X859461Y857957I-1056J1068D01*
G02Y860961I0J1502D01*
G02X860500Y860543I-1J-1502D01*
G01X860529Y860516D01*
X860601Y860487D01*
X860959Y860490D01*
X861030Y860520D01*
X861058Y860547D01*
G02X862114Y860981I1056J-1068D01*
G02Y857977I0J-1502D01*
G02X861075Y858395I1J1502D01*
G01X861046Y858422D01*
X860974Y858451D01*
G37*
G36*
G01X936017Y859801D02*
X936166Y860136D01*
X936167Y860215D01*
X936153Y860253D01*
G02X936049Y860801I1398J549D01*
G02X939053I1502J0D01*
G02X938080Y859395I-1502J0D01*
G01X938042Y859381D01*
X937984Y859327D01*
X937835Y858992D01*
X937834Y858913D01*
X937848Y858875D01*
G02X937952Y858327I-1398J-549D01*
G02X934948I-1502J0D01*
G02X935921Y859733I1502J0D01*
G01X935959Y859747D01*
X936017Y859801D01*
G37*
G36*
G01X953946Y862805D02*
X954306Y863005D01*
X954358Y863080D01*
X954365Y863127D01*
G02X955850Y864404I1485J-225D01*
G02X957352Y862902I0J-1502D01*
G02X957017Y861957I-1502J1D01*
G01X956994Y861928D01*
X956971Y861858D01*
X956987Y861519D01*
X957016Y861452D01*
X957042Y861425D01*
G02X957469Y860376I-1075J-1049D01*
G02X955967Y858874I-1502J0D01*
G02X954539Y859911I0J1502D01*
G01X954525Y859955D01*
X954464Y860019D01*
X954089Y860164D01*
X954000Y860158D01*
X953960Y860135D01*
G02X953217Y859938I-744J1305D01*
G02Y862942I0J1502D01*
G02X953811Y862819I-1J-1502D01*
G01X953855Y862801D01*
X953946Y862805D01*
G37*
G36*
G01X933839Y870646D02*
X933488Y870633D01*
X933418Y870602D01*
X933391Y870574D01*
G02X932319Y870124I-1072J1052D01*
G02Y873128I0J1502D01*
G02X933307Y872757I0J-1501D01*
G01X933336Y872732D01*
X933408Y872707D01*
X933759Y872720D01*
X933829Y872751D01*
X933856Y872779D01*
G02X934928Y873229I1072J-1052D01*
G02Y870225I0J-1502D01*
G02X933940Y870596I0J1501D01*
G01X933911Y870621D01*
X933839Y870646D01*
G37*
G36*
G01X849931Y874507D02*
X849637D01*
G03X849490Y874442I1J-200D01*
G02X848384Y873957I-1105J1017D01*
G02Y876961I0J1502D01*
G02X849490Y876476I1J-1502D01*
G03X849637Y876411I148J135D01*
G01X849931D01*
G03X850078Y876476I-1J200D01*
G02X851184Y876961I1105J-1017D01*
G02Y873957I0J-1502D01*
G02X850078Y874442I-1J1502D01*
G03X849931Y874507I-148J-135D01*
G37*
G36*
G01X952143Y875400D02*
X952155Y875750D01*
X952131Y875821D01*
X952105Y875850D01*
G02X951738Y876834I1136J984D01*
G02X954742I1502J0D01*
G02X954300Y875770I-1502J0D01*
G01X954272Y875742D01*
X954242Y875674D01*
X954230Y875324D01*
X954254Y875253D01*
X954280Y875224D01*
G02X954647Y874240I-1136J-984D01*
G02X953145Y872738I-1502J0D01*
G02X951993Y873276I0J1502D01*
G01X951964Y873310D01*
X951886Y873348D01*
X951493Y873351D01*
X951413Y873316D01*
X951384Y873282D01*
G02X950251Y872766I-1133J986D01*
G02Y875770I0J1502D01*
G02X951403Y875232I0J-1502D01*
G01X951432Y875198D01*
X951510Y875160D01*
X951903Y875157D01*
X951983Y875192D01*
X952012Y875226D01*
G02X952085Y875304I1132J-987D01*
G01X952113Y875332D01*
X952143Y875400D01*
G37*
G36*
G01X934495Y877432D02*
X934087Y877421D01*
X934006Y877379D01*
X933979Y877341D01*
G02X932770Y876731I-1209J893D01*
G02Y879735I0J1502D01*
G02X933927Y879191I0J-1502D01*
G01X933956Y879155D01*
X934040Y879118D01*
X934448Y879129D01*
X934529Y879171D01*
X934556Y879209D01*
G02X935765Y879819I1209J-893D01*
G02Y876815I0J-1502D01*
G02X934608Y877359I0J1502D01*
G01X934579Y877395D01*
X934495Y877432D01*
G37*
G36*
G01X978380Y816240D02*
G02X977476Y817618I598J1378D01*
G02X980480I1502J0D01*
G02X979840Y816388I-1502J0D01*
G03X979911Y815694I230J-327D01*
G02X980815Y814316I-598J-1378D01*
G02X977811I-1502J0D01*
G02X978451Y815546I1502J0D01*
G03X978380Y816240I-230J327D01*
G37*
G36*
G01X954963Y828783D02*
X954937Y828828D01*
G02X954737Y829577I1303J749D01*
G02X957741I1502J0D01*
G02X957447Y828685I-1502J1D01*
G01X957417Y828644D01*
X957403Y828543D01*
X957560Y828133D01*
X957637Y828067D01*
X957687Y828056D01*
G02X958881Y826586I-308J-1470D01*
G02X957379Y825084I-1502J0D01*
G02X956284Y825558I0J1502D01*
G01X956257Y825587D01*
X956188Y825619D01*
X955835Y825639D01*
X955762Y825615D01*
X955733Y825590D01*
G02X954760Y825232I-973J1143D01*
G02X953258Y826734I0J1502D01*
G02X954626Y828230I1502J0D01*
G01X954677Y828235D01*
X954762Y828291D01*
X954965Y828682D01*
X954963Y828783D01*
G37*
G36*
G01X930558Y830578D02*
G02X930498Y831000I1442J420D01*
G02X932000Y829498I1502J0D01*
G02X931696Y829529I0J1502D01*
G03X931232Y829025I-80J-392D01*
G02X931292Y828603I-1442J-420D01*
G02X929790Y830105I-1502J0D01*
G02X930094Y830074I0J-1502D01*
G03X930558Y830578I80J392D01*
G37*
G36*
G01X829212Y831776D02*
G02X828512Y833046I802J1270D01*
G02X831516I1502J0D01*
G02X830762Y831743I-1503J0D01*
G03X830748Y831058I199J-347D01*
G02X831448Y829788I-802J-1270D01*
G02X828444I-1502J0D01*
G02X829198Y831091I1503J0D01*
G03X829212Y831776I-199J347D01*
G37*
G36*
G01X836694Y836890D02*
G02X836692Y836962I1500J78D01*
G02X838194Y835460I1502J0D01*
G02X837609Y835579I1J1502D01*
G03X837053Y835191I-156J-368D01*
G02X837055Y835119I-1500J-78D01*
G02X835553Y836621I-1502J0D01*
G02X836138Y836502I-1J-1502D01*
G03X836694Y836890I156J368D01*
G37*
G36*
G01X975372Y839087D02*
X975710D01*
X975778Y839113D01*
X975806Y839137D01*
G02X976800Y839513I994J-1126D01*
G02X978121Y838725I0J-1501D01*
G01X978139Y838692D01*
X978195Y838644D01*
X978519Y838530D01*
X978592Y838531D01*
X978627Y838546D01*
G02X979203Y838661I576J-1387D01*
G02Y835657I0J-1502D01*
G02X978648Y835763I-1J1502D01*
G01X978597Y835784D01*
X978488Y835766D01*
X978133Y835471D01*
X978097Y835367D01*
X978108Y835313D01*
G02X978137Y835018I-1473J-294D01*
G02X976635Y833516I-1502J0D01*
G02X975408Y834151I0J1503D01*
G01X975380Y834192D01*
X975293Y834236D01*
X974865Y834232D01*
X974779Y834186D01*
X974751Y834145D01*
G02X973510Y833489I-1241J846D01*
G02X972008Y834991I0J1502D01*
G02X972981Y836397I1502J0D01*
G01X973027Y836414D01*
X973092Y836487D01*
X973197Y836899D01*
X973175Y836994D01*
X973143Y837032D01*
G02X972780Y838011I1139J979D01*
G02X974282Y839513I1502J0D01*
G02X975276Y839137I0J-1502D01*
G01X975304Y839113D01*
X975372Y839087D01*
G37*
G36*
G01X824879Y838572D02*
G02X824219Y839816I842J1244D01*
G02X827223I1502J0D01*
G02X826563Y838572I-1502J0D01*
G03Y837910I224J-331D01*
G02X827223Y836666I-842J-1244D01*
G02X824219I-1502J0D01*
G02X824879Y837910I1502J0D01*
G03Y838572I-224J331D01*
G37*
G36*
G01X970124Y852280D02*
X970079Y852287D01*
G02X968797Y853773I220J1486D01*
G02X971801I1502J0D01*
G02X971711Y853260I-1502J-1D01*
G01X971695Y853217D01*
X971703Y853129D01*
X971909Y852784D01*
X971983Y852735D01*
X972028Y852728D01*
G02X973310Y851242I-220J-1486D01*
G02X973283Y850958I-1502J0D01*
G01X973272Y850904D01*
X973311Y850799D01*
X973674Y850509D01*
X973785Y850494D01*
X973836Y850516D01*
G02X974437Y850642I602J-1376D01*
G02X975939Y849140I0J-1502D01*
G02X975931Y848989I-1502J4D01*
G01X975926Y848938D01*
X975965Y848846D01*
X976303Y848571D01*
X976401Y848552D01*
X976450Y848567D01*
G02X976902Y848637I453J-1432D01*
G02X975400Y847135I0J-1502D01*
G02X975408Y847286I1502J-4D01*
G01X975413Y847337D01*
X975374Y847429D01*
X975036Y847704D01*
X974938Y847723D01*
X974889Y847708D01*
G02X974437Y847638I-453J1432D01*
G02X972935Y849140I0J1502D01*
G02X972962Y849424I1502J0D01*
G01X972973Y849478D01*
X972934Y849583D01*
X972571Y849873D01*
X972460Y849888D01*
X972409Y849866D01*
G02X971808Y849740I-602J1376D01*
G02X970306Y851242I0J1502D01*
G02X970396Y851755I1502J1D01*
G01X970412Y851798D01*
X970404Y851886D01*
X970198Y852231D01*
X970124Y852280D01*
G37*
G36*
G01X822392Y869586D02*
G02X821732Y870830I842J1244D01*
G02X823234Y872332I1502J0D01*
G02X824690Y871200I0J-1502D01*
G01X824700Y871159D01*
X824751Y871093D01*
X825083Y870913D01*
X825165Y870905D01*
X825205Y870919D01*
G02X825686Y870998I481J-1423D01*
G02Y867994I0J-1502D01*
G02X825252Y868058I0J1502D01*
G01X825206Y868072D01*
X825113Y868056D01*
X824779Y867808D01*
X824736Y867724D01*
Y867676D01*
G02X824735Y867634I-1502J15D01*
G01X824734Y867577D01*
X824789Y867480D01*
X825202Y867254D01*
X825314Y867260D01*
X825361Y867292D01*
G02X826209Y867554I848J-1241D01*
G02X827711Y866052I0J-1502D01*
G02X827088Y864834I-1502J0D01*
G01X827049Y864806D01*
X827006Y864722D01*
X827000Y864306D01*
X827041Y864221D01*
X827079Y864192D01*
G02X827667Y863000I-914J-1192D01*
G02X826165Y861498I-1502J0D01*
G02X824818Y862334I0J1503D01*
G01X824795Y862382D01*
X824710Y862440D01*
X824266Y862481D01*
X824172Y862439D01*
X824140Y862397D01*
G02X822938Y861796I-1202J902D01*
G02Y864800I0J1502D01*
G02X824285Y863964I0J-1503D01*
G01X824308Y863916D01*
X824393Y863858D01*
X824837Y863817D01*
X824931Y863859D01*
X824963Y863901D01*
G02X825286Y864218I1202J-901D01*
G01X825325Y864246D01*
X825368Y864330D01*
X825374Y864746D01*
X825333Y864831D01*
X825295Y864860D01*
G02X824707Y866052I914J1192D01*
G02X824708Y866098I1502J-10D01*
G01X824709Y866155D01*
X824654Y866252D01*
X824241Y866478D01*
X824129Y866472D01*
X824082Y866440D01*
G02X823234Y866178I-848J1241D01*
G02X821732Y867680I0J1502D01*
G02X822392Y868924I1502J0D01*
G03X822480Y869089I-112J166D01*
G01Y869421D01*
G03X822392Y869586I-200J-1D01*
G37*
G36*
G01X918507Y850369D02*
G02X917776Y851592I656J1222D01*
G02X920550I1387J0D01*
G02X919819Y850369I-1387J-1D01*
G03Y849665I189J-352D01*
G02X920550Y848442I-656J-1222D01*
G02X917776I-1387J0D01*
G02X918507Y849665I1387J1D01*
G03Y850369I-189J352D01*
G37*
G36*
G01X880115Y1083164D02*
G02Y1086168I0J1502D01*
G02X881102Y1085798I0J-1501D01*
G01X881103D01*
Y1085797D01*
G03X881233Y1085749I130J152D01*
G01X881497D01*
G03X881627Y1085797I0J200D01*
G01X881628Y1085798D01*
G02X882615Y1086168I987J-1131D01*
G02Y1083164I0J-1502D01*
G02X881628Y1083534I0J1501D01*
G01X881627D01*
Y1083535D01*
G03X881497Y1083583I-130J-152D01*
G01X881233D01*
G03X881103Y1083535I0J-200D01*
G01X881102Y1083534D01*
G02X880115Y1083164I-987J1131D01*
G37*
G36*
G01X872676Y1111677D02*
G02X873742Y1111233I0J-1502D01*
G03X873884Y1111174I142J141D01*
G01X874168D01*
G03X874310Y1111233I0J200D01*
G02X875376Y1111677I1066J-1058D01*
G02X876878Y1110175I0J-1502D01*
G02X876498Y1109176I-1503J0D01*
G01X876474Y1109150D01*
X876447Y1109080D01*
Y1108778D01*
G03X876498Y1108645I200J0D01*
G02X876877Y1107648I-1123J-998D01*
G01Y1107647D01*
G02X875375Y1106145I-1502J0D01*
G02X874309Y1106589I0J1502D01*
G03X874167Y1106648I-142J-141D01*
G01X873883D01*
G03X873741Y1106589I0J-200D01*
G02X872675Y1106145I-1066J1058D01*
G02X871648Y1106551I0J1502D01*
G01X871621Y1106577D01*
X871550Y1106605D01*
X871200D01*
X871129Y1106577D01*
X871102Y1106551D01*
G02X869048I-1027J1096D01*
G01X869021Y1106577D01*
X868950Y1106605D01*
X868600D01*
X868529Y1106577D01*
X868502Y1106551D01*
G02X867475Y1106145I-1027J1096D01*
G02X865973Y1107647I0J1502D01*
G02X866353Y1108646I1503J0D01*
G01X866377Y1108672D01*
X866404Y1108742D01*
Y1109044D01*
G03X866353Y1109177I-200J0D01*
G02X865974Y1110174I1123J998D01*
G01Y1110175D01*
G02X867476Y1111677I1502J0D01*
G02X868503Y1111271I0J-1502D01*
G01X868530Y1111245D01*
X868601Y1111217D01*
X868951D01*
X869022Y1111245D01*
X869049Y1111271D01*
G02X871103I1027J-1096D01*
G01X871130Y1111245D01*
X871201Y1111217D01*
X871551D01*
X871622Y1111245D01*
X871649Y1111271D01*
G02X872676Y1111677I1027J-1096D01*
G37*
G36*
G01X891549Y1115605D02*
G02X892615Y1115161I0J-1502D01*
G03X892757Y1115102I142J141D01*
G01X893041D01*
G03X893183Y1115161I0J200D01*
G02X894249Y1115605I1066J-1058D01*
G02Y1112601I0J-1502D01*
G02X893183Y1113045I0J1502D01*
G03X893041Y1113104I-142J-141D01*
G01X892757D01*
G03X892615Y1113045I0J-200D01*
G02X891549Y1112601I-1066J1058D01*
G02X890522Y1113007I0J1502D01*
G01X890495Y1113033D01*
X890424Y1113061D01*
X890074D01*
X890003Y1113033D01*
X889976Y1113007D01*
G02X887922I-1027J1096D01*
G01X887895Y1113033D01*
X887824Y1113061D01*
X887474D01*
X887403Y1113033D01*
X887376Y1113007D01*
G02X886349Y1112601I-1027J1096D01*
G02Y1115605I0J1502D01*
G02X887376Y1115199I0J-1502D01*
G01X887403Y1115173D01*
X887474Y1115145D01*
X887824D01*
X887895Y1115173D01*
X887922Y1115199D01*
G02X889976I1027J-1096D01*
G01X890003Y1115173D01*
X890074Y1115145D01*
X890424D01*
X890495Y1115173D01*
X890522Y1115199D01*
G02X891549Y1115605I1027J-1096D01*
G37*
G36*
G01X876564Y1122138D02*
G02X877630Y1121694I0J-1502D01*
G03X877772Y1121635I142J141D01*
G01X878056D01*
G03X878198Y1121694I0J200D01*
G02X879264Y1122138I1066J-1058D01*
G02Y1119134I0J-1502D01*
G02X878198Y1119578I0J1502D01*
G03X878056Y1119637I-142J-141D01*
G01X877772D01*
G03X877630Y1119578I0J-200D01*
G02X876564Y1119134I-1066J1058D01*
G02X875537Y1119540I0J1502D01*
G01X875510Y1119566D01*
X875439Y1119594D01*
X875089D01*
X875018Y1119566D01*
X874991Y1119540D01*
G02X872937I-1027J1096D01*
G01X872910Y1119566D01*
X872839Y1119594D01*
X872489D01*
X872418Y1119566D01*
X872391Y1119540D01*
G02X871364Y1119134I-1027J1096D01*
G02Y1122138I0J1502D01*
G02X872391Y1121732I0J-1502D01*
G01X872418Y1121706D01*
X872489Y1121678D01*
X872839D01*
X872910Y1121706D01*
X872937Y1121732D01*
G02X874991I1027J-1096D01*
G01X875018Y1121706D01*
X875089Y1121678D01*
X875439D01*
X875510Y1121706D01*
X875537Y1121732D01*
G02X876564Y1122138I1027J-1096D01*
G37*
G36*
G01X891549Y1125305D02*
G02X892615Y1124861I0J-1502D01*
G03X892757Y1124802I142J141D01*
G01X893041D01*
G03X893183Y1124861I0J200D01*
G02X894249Y1125305I1066J-1058D01*
G02Y1122301I0J-1502D01*
G02X893183Y1122745I0J1502D01*
G03X893041Y1122804I-142J-141D01*
G01X892757D01*
G03X892615Y1122745I0J-200D01*
G02X891549Y1122301I-1066J1058D01*
G02X890522Y1122707I0J1502D01*
G01X890495Y1122733D01*
X890424Y1122761D01*
X890074D01*
X890003Y1122733D01*
X889976Y1122707D01*
G02X887922I-1027J1096D01*
G01X887895Y1122733D01*
X887824Y1122761D01*
X887474D01*
X887403Y1122733D01*
X887376Y1122707D01*
G02X886349Y1122301I-1027J1096D01*
G02Y1125305I0J1502D01*
G02X887376Y1124899I0J-1502D01*
G01X887403Y1124873D01*
X887474Y1124845D01*
X887824D01*
X887895Y1124873D01*
X887922Y1124899D01*
G02X889976I1027J-1096D01*
G01X890003Y1124873D01*
X890074Y1124845D01*
X890424D01*
X890495Y1124873D01*
X890522Y1124899D01*
G02X891549Y1125305I1027J-1096D01*
G37*
G36*
G01X876564Y1131838D02*
G02X877630Y1131394I0J-1502D01*
G03X877772Y1131335I142J141D01*
G01X878056D01*
G03X878198Y1131394I0J200D01*
G02X879264Y1131838I1066J-1058D01*
G02Y1128834I0J-1502D01*
G02X878198Y1129278I0J1502D01*
G03X878056Y1129337I-142J-141D01*
G01X877772D01*
G03X877630Y1129278I0J-200D01*
G02X876564Y1128834I-1066J1058D01*
G02X875537Y1129240I0J1502D01*
G01X875510Y1129266D01*
X875439Y1129294D01*
X875089D01*
X875018Y1129266D01*
X874991Y1129240D01*
G02X872937I-1027J1096D01*
G01X872910Y1129266D01*
X872839Y1129294D01*
X872489D01*
X872418Y1129266D01*
X872391Y1129240D01*
G02X871364Y1128834I-1027J1096D01*
G02Y1131838I0J1502D01*
G02X872391Y1131432I0J-1502D01*
G01X872418Y1131406D01*
X872489Y1131378D01*
X872839D01*
X872910Y1131406D01*
X872937Y1131432D01*
G02X874991I1027J-1096D01*
G01X875018Y1131406D01*
X875089Y1131378D01*
X875439D01*
X875510Y1131406D01*
X875537Y1131432D01*
G02X876564Y1131838I1027J-1096D01*
G37*
G36*
G01X892575Y1131368D02*
G02Y1134372I0J1502D01*
G02X893641Y1133928I0J-1502D01*
G03X893783Y1133869I142J141D01*
G01X894067D01*
G03X894209Y1133928I0J200D01*
G02X895275Y1134372I1066J-1058D01*
G02Y1131368I0J-1502D01*
G02X894209Y1131812I0J1502D01*
G03X894067Y1131871I-142J-141D01*
G01X893783D01*
G03X893641Y1131812I0J-200D01*
G02X892575Y1131368I-1066J1058D01*
G37*
G36*
G01X868664Y1137834D02*
G02Y1140838I0J1502D01*
G02X869730Y1140394I0J-1502D01*
G03X869872Y1140335I142J141D01*
G01X870156D01*
G03X870298Y1140394I0J200D01*
G02X871364Y1140838I1066J-1058D01*
G02Y1137834I0J-1502D01*
G02X870298Y1138278I0J1502D01*
G03X870156Y1138337I-142J-141D01*
G01X869872D01*
G03X869730Y1138278I0J-200D01*
G02X868664Y1137834I-1066J1058D01*
G37*
G36*
G01X895547Y1143667D02*
G02Y1146671I0J1502D01*
G02X896534Y1146301I0J-1501D01*
G01X896535D01*
Y1146300D01*
G03X896665Y1146252I130J152D01*
G01X896929D01*
G03X897059Y1146300I0J200D01*
G01X897060Y1146301D01*
G02X898047Y1146671I987J-1131D01*
G02Y1143667I0J-1502D01*
G02X897060Y1144037I0J1501D01*
G01X897059D01*
Y1144038D01*
G03X896929Y1144086I-130J-152D01*
G01X896665D01*
G03X896535Y1144038I0J-200D01*
G01X896534Y1144037D01*
G02X895547Y1143667I-987J1131D01*
G37*
G36*
G01X868022Y1146578D02*
G02Y1149582I0J1502D01*
G02X869009Y1149212I0J-1501D01*
G01X869010D01*
Y1149211D01*
G03X869140Y1149163I130J152D01*
G01X869404D01*
G03X869534Y1149211I0J200D01*
G01X869535Y1149212D01*
G02X870522Y1149582I987J-1131D01*
G02Y1146578I0J-1502D01*
G02X869535Y1146948I0J1501D01*
G01X869534D01*
Y1146949D01*
G03X869404Y1146997I-130J-152D01*
G01X869140D01*
G03X869010Y1146949I0J-200D01*
G01X869009Y1146948D01*
G02X868022Y1146578I-987J1131D01*
G37*
G36*
G01X890375Y1264190D02*
X890376Y1264189D01*
G03X890506Y1264141I130J152D01*
G01X890770D01*
G03X890900Y1264189I0J200D01*
G01X890901Y1264190D01*
G02X891888Y1264560I987J-1131D01*
G02X893390Y1263058I0J-1502D01*
G02X893020Y1262071I-1501J0D01*
G01Y1262070D01*
X893019D01*
G03X892971Y1261940I152J-130D01*
G01Y1261676D01*
G03X893019Y1261546I200J0D01*
G01X893020Y1261545D01*
G02X893390Y1260558I-1131J-987D01*
G02X891888Y1259056I-1502J0D01*
G02X890901Y1259426I0J1501D01*
G01X890900D01*
Y1259427D01*
G03X890770Y1259475I-130J-152D01*
G01X890506D01*
G03X890376Y1259427I0J-200D01*
G01X890375Y1259426D01*
G02X888401I-987J1131D01*
G01X888400D01*
Y1259427D01*
G03X888270Y1259475I-130J-152D01*
G01X888006D01*
G03X887876Y1259427I0J-200D01*
G01X887875Y1259426D01*
G02X886888Y1259056I-987J1131D01*
G02X885386Y1260558I0J1502D01*
G02X885756Y1261545I1501J0D01*
G01Y1261546D01*
X885757D01*
G03X885805Y1261676I-152J130D01*
G01Y1261940D01*
G03X885757Y1262070I-200J0D01*
G01X885756Y1262071D01*
G02X885386Y1263058I1131J987D01*
G02X886888Y1264560I1502J0D01*
G02X887875Y1264190I0J-1501D01*
G01X887876D01*
Y1264189D01*
G03X888006Y1264141I130J152D01*
G01X888270D01*
G03X888400Y1264189I0J200D01*
G01X888401Y1264190D01*
G02X890375I987J-1131D01*
G37*
G36*
G01X879676Y916495D02*
Y916789D01*
G03X879611Y916936I-200J-1D01*
G02X879126Y918042I1017J1105D01*
G02X882130I1502J0D01*
G02X881645Y916936I-1502J-1D01*
G03X881580Y916789I135J-148D01*
G01Y916495D01*
G03X881645Y916348I200J1D01*
G02X882130Y915242I-1017J-1105D01*
G02X879126I-1502J0D01*
G02X879611Y916348I1502J1D01*
G03X879676Y916495I-135J148D01*
G37*
G36*
G01X887676D02*
Y916789D01*
G03X887611Y916936I-200J-1D01*
G02X887126Y918042I1017J1105D01*
G02X890130I1502J0D01*
G02X889645Y916936I-1502J-1D01*
G03X889580Y916789I135J-148D01*
G01Y916495D01*
G03X889645Y916348I200J1D01*
G02X890130Y915242I-1017J-1105D01*
G02X887126I-1502J0D01*
G02X887611Y916348I1502J1D01*
G03X887676Y916495I-135J148D01*
G37*
G36*
G01X903837Y916510D02*
X903838Y916875D01*
X903807Y916949D01*
X903779Y916977D01*
G02X903336Y918042I1059J1065D01*
G02X906340I1502J0D01*
G02X905893Y916973I-1502J0D01*
G01X905865Y916945D01*
X905834Y916872D01*
X905833Y916507D01*
X905864Y916433D01*
X905892Y916405D01*
G02X906335Y915340I-1059J-1065D01*
G02X903331I-1502J0D01*
G02X903778Y916409I1502J0D01*
G01X903806Y916437D01*
X903837Y916510D01*
G37*
G36*
G01X907676Y916495D02*
Y916789D01*
G03X907611Y916936I-200J-1D01*
G02X907126Y918042I1017J1105D01*
G02X910130I1502J0D01*
G02X909645Y916936I-1502J-1D01*
G03X909580Y916789I135J-148D01*
G01Y916495D01*
G03X909645Y916348I200J1D01*
G02X910130Y915242I-1017J-1105D01*
G02X907126I-1502J0D01*
G02X907611Y916348I1502J1D01*
G03X907676Y916495I-135J148D01*
G37*
G36*
G01X911676D02*
Y916789D01*
G03X911611Y916936I-200J-1D01*
G02X911126Y918042I1017J1105D01*
G02X914130I1502J0D01*
G02X913645Y916936I-1502J-1D01*
G03X913580Y916789I135J-148D01*
G01Y916495D01*
G03X913645Y916348I200J1D01*
G02X914130Y915242I-1017J-1105D01*
G02X911126I-1502J0D01*
G02X911611Y916348I1502J1D01*
G03X911676Y916495I-135J148D01*
G37*
G36*
G01X915676D02*
Y916789D01*
G03X915611Y916936I-200J-1D01*
G02X915126Y918042I1017J1105D01*
G02X918130I1502J0D01*
G02X917645Y916936I-1502J-1D01*
G03X917580Y916789I135J-148D01*
G01Y916495D01*
G03X917645Y916348I200J1D01*
G02X918130Y915242I-1017J-1105D01*
G02X915126I-1502J0D01*
G02X915611Y916348I1502J1D01*
G03X915676Y916495I-135J148D01*
G37*
G36*
G01X919676D02*
Y916789D01*
G03X919611Y916936I-200J-1D01*
G02X919126Y918042I1017J1105D01*
G02X922130I1502J0D01*
G02X921645Y916936I-1502J-1D01*
G03X921580Y916789I135J-148D01*
G01Y916495D01*
G03X921645Y916348I200J1D01*
G02X922130Y915242I-1017J-1105D01*
G02X919126I-1502J0D01*
G02X919611Y916348I1502J1D01*
G03X919676Y916495I-135J148D01*
G37*
G36*
G01X923676D02*
Y916789D01*
G03X923611Y916936I-200J-1D01*
G02X923126Y918042I1017J1105D01*
G02X926130I1502J0D01*
G02X925645Y916936I-1502J-1D01*
G03X925580Y916789I135J-148D01*
G01Y916495D01*
G03X925645Y916348I200J1D01*
G02X926130Y915242I-1017J-1105D01*
G02X923126I-1502J0D01*
G02X923611Y916348I1502J1D01*
G03X923676Y916495I-135J148D01*
G37*
G36*
G01X927676D02*
Y916789D01*
G03X927611Y916936I-200J-1D01*
G02X927126Y918042I1017J1105D01*
G02X930130I1502J0D01*
G02X929645Y916936I-1502J-1D01*
G03X929580Y916789I135J-148D01*
G01Y916495D01*
G03X929645Y916348I200J1D01*
G02X930130Y915242I-1017J-1105D01*
G02X927126I-1502J0D01*
G02X927611Y916348I1502J1D01*
G03X927676Y916495I-135J148D01*
G37*
G36*
G01X931676D02*
Y916789D01*
G03X931611Y916936I-200J-1D01*
G02X931126Y918042I1017J1105D01*
G02X934130I1502J0D01*
G02X933645Y916936I-1502J-1D01*
G03X933580Y916789I135J-148D01*
G01Y916495D01*
G03X933645Y916348I200J1D01*
G02X934130Y915242I-1017J-1105D01*
G02X931126I-1502J0D01*
G02X931611Y916348I1502J1D01*
G03X931676Y916495I-135J148D01*
G37*
G36*
G01X935676D02*
Y916789D01*
G03X935611Y916936I-200J-1D01*
G02X935126Y918042I1017J1105D01*
G02X938130I1502J0D01*
G02X937645Y916936I-1502J-1D01*
G03X937580Y916789I135J-148D01*
G01Y916495D01*
G03X937645Y916348I200J1D01*
G02X938130Y915242I-1017J-1105D01*
G02X935126I-1502J0D01*
G02X935611Y916348I1502J1D01*
G03X935676Y916495I-135J148D01*
G37*
G36*
G01X959828Y928544D02*
X960225Y928543D01*
X960304Y928579D01*
X960333Y928614D01*
G02X961479Y929145I1146J-971D01*
G02X962536Y928710I0J-1502D01*
G01X962567Y928679D01*
X962644Y928650D01*
X963024Y928668D01*
X963098Y928705D01*
X963126Y928738D01*
G02X964280Y929279I1154J-960D01*
G02Y926275I0J-1502D01*
G02X963223Y926710I0J1502D01*
G01X963192Y926741D01*
X963115Y926770D01*
X962735Y926752D01*
X962661Y926715D01*
X962633Y926682D01*
G02X961479Y926141I-1154J960D01*
G02X960326Y926681I0J1501D01*
G01X960297Y926716D01*
X960218Y926753D01*
X959821Y926754D01*
X959742Y926718D01*
X959713Y926683D01*
G02X958567Y926152I-1146J971D01*
G02Y929156I0J1502D01*
G02X959720Y928616I0J-1501D01*
G01X959749Y928581D01*
X959828Y928544D01*
G37*
G36*
G01X913098Y944232D02*
X912712Y944177D01*
X912640Y944131D01*
X912616Y944094D01*
G02X911355Y943407I-1261J814D01*
G02Y946411I0J1502D01*
G02X912335Y946047I0J-1501D01*
G01X912368Y946019D01*
X912450Y945995D01*
X912836Y946050D01*
X912908Y946096D01*
X912932Y946133D01*
G02X914193Y946820I1261J-814D01*
G02Y943816I0J-1502D01*
G02X913213Y944180I0J1501D01*
G01X913180Y944208D01*
X913098Y944232D01*
G37*
G36*
G01X914537Y968689D02*
X914202Y968651D01*
X914138Y968619D01*
X914113Y968591D01*
G02X913005Y968103I-1108J1014D01*
G02Y971107I0J1502D01*
G02X913859Y970841I1J-1502D01*
G01X913889Y970820D01*
X913958Y970802D01*
X914293Y970840D01*
X914357Y970872D01*
X914382Y970900D01*
G02X915490Y971388I1108J-1014D01*
G02X916638Y970855I0J-1503D01*
G01X916665Y970823D01*
X916739Y970786D01*
X917114Y970767D01*
X917191Y970796D01*
X917221Y970825D01*
G02X918265Y971247I1044J-1080D01*
G02Y968243I0J-1502D01*
G02X917117Y968776I0J1503D01*
G01X917090Y968808D01*
X917016Y968845D01*
X916641Y968864D01*
X916564Y968835D01*
X916534Y968806D01*
G02X915490Y968384I-1044J1080D01*
G02X914636Y968650I-1J1502D01*
G01X914606Y968671D01*
X914537Y968689D01*
G37*
G36*
G01X922595Y950391D02*
G02X921364Y949749I-1231J859D01*
G02Y952753I0J1502D01*
G02X922599Y952106I0J-1502D01*
G03X923256Y952104I329J227D01*
G02X924487Y952746I1231J-859D01*
G02Y949742I0J-1502D01*
G02X923252Y950389I0J1502D01*
G03X922595Y950391I-329J-227D01*
G37*
G36*
G01X907925Y961550D02*
G02X906710Y960931I-1215J883D01*
G02Y963935I0J1502D01*
G02X907944Y963290I0J-1503D01*
G03X908596Y963283I328J228D01*
G02X909811Y963902I1215J-883D01*
G02Y960898I0J-1502D01*
G02X908577Y961543I0J1503D01*
G03X907925Y961550I-328J-228D01*
G37*
G36*
G01X928171Y965694D02*
G02X926796Y964795I-1375J602D01*
G02Y967799I0J1502D01*
G02X927746Y967460I0J-1501D01*
G03X928366Y967609I253J310D01*
G02X929741Y968508I1375J-602D01*
G02Y965504I0J-1502D01*
G02X928791Y965843I0J1501D01*
G03X928171Y965694I-253J-310D01*
G37*
G36*
G01X947899Y990538D02*
G02X946642Y989859I-1257J824D01*
G02Y992863I0J1502D01*
G02X947777Y992344I0J-1501D01*
G03X948414Y992387I302J262D01*
G02X949671Y993066I1257J-824D01*
G02Y990062I0J-1502D01*
G02X948536Y990581I0J1501D01*
G03X947899Y990538I-302J-262D01*
G37*
G36*
G01X1000631Y74638D02*
G02Y77642I0J1502D01*
G01X1000632D01*
G02X1001552Y77327I0J-1502D01*
G03X1001707Y77287I123J157D01*
G01X1001995Y77334D01*
G03X1002129Y77420I-32J197D01*
G01X1002130Y77421D01*
G02X1003379Y78089I1249J-834D01*
G02Y75085I0J-1502D01*
G01X1003378D01*
G02X1002458Y75400I0J1502D01*
G03X1002303Y75440I-123J-157D01*
G01X1002015Y75393D01*
G03X1001881Y75307I32J-197D01*
G01X1001880Y75306D01*
G02X1000631Y74638I-1249J834D01*
G37*
G36*
G01X977456Y85193D02*
G02X980460I1502J0D01*
G02X980054Y84166I-1502J0D01*
G01X980028Y84139D01*
X980000Y84068D01*
Y83718D01*
X980028Y83647D01*
X980054Y83620D01*
G02Y81566I-1096J-1027D01*
G01X980028Y81539D01*
X980000Y81468D01*
Y81118D01*
X980028Y81047D01*
X980054Y81020D01*
G02Y78966I-1096J-1027D01*
G01X980028Y78939D01*
X980000Y78868D01*
Y78518D01*
X980028Y78447D01*
X980054Y78420D01*
G02Y76366I-1096J-1027D01*
G01X980028Y76339D01*
X980000Y76268D01*
Y75918D01*
X980028Y75847D01*
X980054Y75820D01*
G02X980460Y74793I-1096J-1027D01*
G02X977456I-1502J0D01*
G02X977862Y75820I1502J0D01*
G01X977888Y75847D01*
X977916Y75918D01*
Y76268D01*
X977888Y76339D01*
X977862Y76366D01*
G02Y78420I1096J1027D01*
G01X977888Y78447D01*
X977916Y78518D01*
Y78868D01*
X977888Y78939D01*
X977862Y78966D01*
G02Y81020I1096J1027D01*
G01X977888Y81047D01*
X977916Y81118D01*
Y81468D01*
X977888Y81539D01*
X977862Y81566D01*
G02Y83620I1096J1027D01*
G01X977888Y83647D01*
X977916Y83718D01*
Y84068D01*
X977888Y84139D01*
X977862Y84166D01*
G02X977456Y85193I1096J1027D01*
G37*
G36*
G01X959121Y85584D02*
G02X962125I1502J0D01*
G02X961719Y84557I-1502J0D01*
G01X961693Y84530D01*
X961665Y84459D01*
Y84109D01*
X961693Y84038D01*
X961719Y84011D01*
G02Y81957I-1096J-1027D01*
G01X961693Y81930D01*
X961665Y81859D01*
Y81509D01*
X961693Y81438D01*
X961719Y81411D01*
G02Y79357I-1096J-1027D01*
G01X961693Y79330D01*
X961665Y79259D01*
Y78909D01*
X961693Y78838D01*
X961719Y78811D01*
G02Y76757I-1096J-1027D01*
G01X961693Y76730D01*
X961665Y76659D01*
Y76309D01*
X961693Y76238D01*
X961719Y76211D01*
G02X962125Y75184I-1096J-1027D01*
G02X959121I-1502J0D01*
G02X959527Y76211I1502J0D01*
G01X959553Y76238D01*
X959581Y76309D01*
Y76659D01*
X959553Y76730D01*
X959527Y76757D01*
G02Y78811I1096J1027D01*
G01X959553Y78838D01*
X959581Y78909D01*
Y79259D01*
X959553Y79330D01*
X959527Y79357D01*
G02Y81411I1096J1027D01*
G01X959553Y81438D01*
X959581Y81509D01*
Y81859D01*
X959553Y81930D01*
X959527Y81957D01*
G02Y84011I1096J1027D01*
G01X959553Y84038D01*
X959581Y84109D01*
Y84459D01*
X959553Y84530D01*
X959527Y84557D01*
G02X959121Y85584I1096J1027D01*
G37*
G36*
G01X949861Y123626D02*
G02X949436Y123677I1J1802D01*
G01X949433D01*
G03X949277Y123649I-46J-195D01*
G01X948996Y123462D01*
X948951Y123392D01*
X948945Y123350D01*
G02X947461Y122081I-1484J233D01*
G01X947460D01*
G02X946473Y122451I0J1502D01*
G01X946446Y122475D01*
X946378Y122501D01*
X946042D01*
X945975Y122476D01*
X945948Y122452D01*
G02X944961Y122082I-987J1131D01*
G02X944693Y122106I-1J1502D01*
G03X944527Y122060I-35J-197D01*
G01X944431Y121978D01*
G03X944362Y121817I131J-151D01*
G02X944364Y121742I-1800J-86D01*
G01Y118342D01*
G02X944362Y118264I-1803J7D01*
G03X944431Y118103I200J-10D01*
G01X944527Y118020D01*
G03X944694Y117975I130J152D01*
G02X944961Y117999I267J-1478D01*
G02X945948Y117629I0J-1501D01*
G01X945949D01*
Y117628D01*
G03X946079Y117580I130J152D01*
G01X946343D01*
G03X946473Y117628I0J200D01*
G01X946474Y117629D01*
G02X947461Y117999I987J-1131D01*
G02X948944Y116732I0J-1501D01*
G01X948951Y116690D01*
X948995Y116621D01*
X949311Y116411D01*
X949394Y116396D01*
X949434Y116406D01*
G02X949861Y116458I430J-1751D01*
G02X950209Y116424I0J-1803D01*
G01X950249Y116416D01*
X950328Y116432D01*
X950631Y116642D01*
X950673Y116708D01*
X950680Y116749D01*
G02X952161Y117998I1481J-254D01*
G02Y114994I0J-1502D01*
G01X952158D01*
G02X951980Y115005I3J1502D01*
G03X951822Y114954I-23J-199D01*
G01X951728Y114870D01*
G03X951663Y114714I135J-148D01*
G02X951664Y114655I-1802J-60D01*
G01Y111255D01*
G02X951663Y111193I-1803J-2D01*
G03X951728Y111037I200J-8D01*
G01X951822Y110952D01*
G03X951980Y110901I135J148D01*
G02X952158Y110912I181J-1491D01*
G01X952161D01*
G02Y107908I0J-1502D01*
G02X950680Y109160I0J1502D01*
G03X950596Y109292I-197J-33D01*
G01X950327Y109478D01*
X950248Y109494D01*
X950208Y109486D01*
G02X949861Y109452I-348J1769D01*
G02X949436Y109504I5J1802D01*
G01X949433D01*
G03X949277Y109476I-46J-195D01*
G01X948996Y109289D01*
X948951Y109219D01*
X948945Y109177D01*
G02X947461Y107908I-1484J233D01*
G02Y110912I0J1502D01*
G02X947728Y110888I0J-1502D01*
G03X947895Y110933I37J197D01*
G01X947991Y111016D01*
G03X948060Y111177I-131J151D01*
G02X948058Y111255I1801J85D01*
G01Y114655D01*
G02X948060Y114730I1802J-11D01*
G03X947991Y114891I-200J10D01*
G01X947895Y114973D01*
G03X947729Y115019I-131J-151D01*
G02X947461Y114995I-267J1478D01*
G02X946474Y115365I0J1501D01*
G01X946473D01*
Y115366D01*
G03X946343Y115414I-130J-152D01*
G01X946079D01*
G03X945949Y115366I0J-200D01*
G01X945948Y115365D01*
G02X944961Y114995I-987J1131D01*
G02X943477Y116264I0J1502D01*
G01X943471Y116306D01*
X943426Y116376D01*
X943145Y116563D01*
G03X942989Y116591I-110J-167D01*
G01X942987D01*
G02X942561Y116540I-426J1751D01*
G02X942136Y116591I1J1802D01*
G01X942133D01*
G03X941977Y116563I-46J-195D01*
G01X941696Y116376D01*
X941651Y116306D01*
X941645Y116264D01*
G02X940161Y114995I-1484J233D01*
G02Y117999I0J1502D01*
G02X940428Y117975I0J-1502D01*
G03X940595Y118020I37J197D01*
G01X940691Y118103D01*
G03X940760Y118264I-131J151D01*
G02X940758Y118342I1801J85D01*
G01Y121742D01*
G02X940760Y121817I1802J-11D01*
G03X940691Y121978I-200J10D01*
G01X940595Y122060D01*
G03X940429Y122106I-131J-151D01*
G02X940161Y122082I-267J1478D01*
G02Y125086I0J1502D01*
G02X941644Y123819I0J-1501D01*
G01X941651Y123777D01*
X941695Y123708D01*
X942011Y123498D01*
X942094Y123483D01*
X942134Y123493D01*
G02X942561Y123544I426J-1751D01*
G02X942988Y123493I1J-1802D01*
G01X943028Y123483D01*
X943111Y123498D01*
X943392Y123685D01*
G03X943478Y123819I-111J166D01*
G02X944961Y125086I1483J-234D01*
G01X944962D01*
G02X945949Y124716I0J-1502D01*
G01X945976Y124692D01*
X946044Y124666D01*
X946380D01*
X946447Y124691D01*
X946474Y124715D01*
G02X947461Y125085I987J-1131D01*
G02X947728Y125061I0J-1502D01*
G03X947895Y125106I37J197D01*
G01X947991Y125189D01*
G03X948060Y125350I-131J151D01*
G02X948058Y125428I1801J85D01*
G01Y128828D01*
G02X948060Y128903I1802J-11D01*
G03X947991Y129064I-200J10D01*
G01X947895Y129146D01*
G03X947729Y129192I-131J-151D01*
G02X947461Y129168I-267J1478D01*
G02X946474Y129538I0J1501D01*
G01X946473D01*
Y129539D01*
G03X946343Y129587I-130J-152D01*
G01X946079D01*
G03X945949Y129539I0J-200D01*
G01X945948Y129538D01*
G02X944961Y129168I-987J1131D01*
G02X943477Y130437I0J1502D01*
G01X943471Y130479D01*
X943426Y130549D01*
X943145Y130736D01*
G03X942989Y130764I-110J-167D01*
G01X942987D01*
G02X942561Y130712I-430J1751D01*
G02X942136Y130764I5J1802D01*
G01X942133D01*
G03X941977Y130736I-46J-195D01*
G01X941696Y130549D01*
X941651Y130479D01*
X941645Y130437D01*
G02X940161Y129168I-1484J233D01*
G02Y132172I0J1502D01*
G02X940428Y132148I0J-1502D01*
G03X940595Y132193I37J197D01*
G01X940691Y132276D01*
G03X940760Y132437I-131J151D01*
G02X940758Y132515I1801J85D01*
G01Y135915D01*
G02X940760Y135990I1802J-11D01*
G03X940691Y136151I-200J10D01*
G01X940595Y136233D01*
G03X940429Y136279I-131J-151D01*
G02X940161Y136255I-267J1478D01*
G02Y139259I0J1502D01*
G02X941644Y137992I0J-1501D01*
G01X941651Y137950D01*
X941695Y137881D01*
X942011Y137671D01*
X942094Y137656D01*
X942134Y137666D01*
G02X942561Y137718I430J-1751D01*
G02X942988Y137666I-3J-1803D01*
G01X943028Y137656D01*
X943111Y137671D01*
X943392Y137858D01*
G03X943478Y137992I-111J166D01*
G02X944961Y139259I1483J-234D01*
G02Y136255I0J-1502D01*
G02X944693Y136279I-1J1502D01*
G03X944527Y136233I-35J-197D01*
G01X944431Y136151D01*
G03X944362Y135990I131J-151D01*
G02X944364Y135915I-1800J-86D01*
G01Y132515D01*
G02X944362Y132437I-1803J7D01*
G03X944431Y132276I200J-10D01*
G01X944527Y132193D01*
G03X944694Y132148I130J152D01*
G02X944961Y132172I267J-1478D01*
G02X945948Y131802I0J-1501D01*
G01X945949D01*
Y131801D01*
G03X946079Y131753I130J152D01*
G01X946343D01*
G03X946473Y131801I0J200D01*
G01X946474Y131802D01*
G02X947461Y132172I987J-1131D01*
G02X948944Y130905I0J-1501D01*
G01X948951Y130863D01*
X948995Y130794D01*
X949311Y130584D01*
X949394Y130569D01*
X949434Y130579D01*
G02X949861Y130630I426J-1751D01*
G02X950209Y130597I5J-1802D01*
G01X950249Y130589D01*
X950328Y130605D01*
X950631Y130815D01*
X950673Y130881D01*
X950680Y130922D01*
G02X952161Y132172I1481J-252D01*
G02Y129168I0J-1502D01*
G01X952158D01*
G02X951980Y129179I3J1502D01*
G03X951822Y129128I-23J-199D01*
G01X951728Y129044D01*
G03X951663Y128888I135J-148D01*
G02X951664Y128828I-1802J-60D01*
G01Y125428D01*
G02X951663Y125366I-1803J-2D01*
G03X951728Y125210I200J-8D01*
G01X951822Y125125D01*
G03X951980Y125074I135J148D01*
G02X952158Y125085I181J-1491D01*
G01X952161D01*
G02Y122081I0J-1502D01*
G02X950680Y123333I0J1502D01*
G03X950596Y123465I-197J-33D01*
G01X950327Y123651D01*
X950248Y123667D01*
X950208Y123659D01*
G02X949861Y123626I-343J1769D01*
G37*
G36*
G01X930359Y181849D02*
G02X931465Y181364I0J-1504D01*
G03X931612Y181299I148J135D01*
G01X931906D01*
G03X932053Y181364I-1J200D01*
G02X933159Y181849I1106J-1019D01*
G02Y178845I0J-1502D01*
G02X932053Y179330I0J1504D01*
G03X931906Y179395I-148J-135D01*
G01X931612D01*
G03X931465Y179330I1J-200D01*
G02X930359Y178845I-1106J1019D01*
G02X929372Y179215I0J1501D01*
G01X929371D01*
Y179216D01*
G03X929241Y179264I-130J-152D01*
G01X928977D01*
G03X928847Y179216I0J-200D01*
G01X928846Y179215D01*
G02X926872I-987J1131D01*
G01X926871D01*
Y179216D01*
G03X926741Y179264I-130J-152D01*
G01X926477D01*
G03X926347Y179216I0J-200D01*
G01X926346Y179215D01*
G02X925359Y178845I-987J1131D01*
G02Y181849I0J1502D01*
G02X926346Y181479I0J-1501D01*
G01X926347D01*
Y181478D01*
G03X926477Y181430I130J152D01*
G01X926741D01*
G03X926871Y181478I0J200D01*
G01X926872Y181479D01*
G02X928846I987J-1131D01*
G01X928847D01*
Y181478D01*
G03X928977Y181430I130J152D01*
G01X929241D01*
G03X929371Y181478I0J200D01*
G01X929372Y181479D01*
G02X930359Y181849I987J-1131D01*
G37*
G36*
G01X925219Y187062D02*
G02Y190066I0J1502D01*
G02X926206Y189696I0J-1501D01*
G01X926207D01*
Y189695D01*
G03X926337Y189647I130J152D01*
G01X926601D01*
G03X926731Y189695I0J200D01*
G01X926732Y189696D01*
G02X927719Y190066I987J-1131D01*
G02X929216Y188688I0J-1502D01*
G01X929219Y188645D01*
X929260Y188571D01*
X929532Y188365D01*
G03X929691Y188328I121J159D01*
G02X929978Y188356I289J-1474D01*
G02X931480Y186854I0J-1502D01*
G02X930995Y185748I-1504J0D01*
G03X930930Y185601I135J-148D01*
G01Y185307D01*
G03X930995Y185160I200J1D01*
G02X931480Y184054I-1019J-1106D01*
G02X928476I-1502J0D01*
G02X928961Y185160I1504J0D01*
G03X929026Y185307I-135J148D01*
G01Y185601D01*
G03X928961Y185748I-200J-1D01*
G02X928481Y186730I1017J1105D01*
G01X928478Y186773D01*
X928437Y186847D01*
X928165Y187053D01*
G03X928006Y187090I-121J-159D01*
G02X927719Y187062I-289J1474D01*
G02X926732Y187432I0J1501D01*
G01X926731D01*
Y187433D01*
G03X926601Y187481I-130J-152D01*
G01X926337D01*
G03X926207Y187433I0J-200D01*
G01X926206Y187432D01*
G02X925219Y187062I-987J1131D01*
G37*
G36*
G01X931407Y190507D02*
G02Y193511I0J1502D01*
G02X932394Y193141I0J-1501D01*
G01X932395D01*
Y193140D01*
G03X932525Y193092I130J152D01*
G01X932789D01*
G03X932919Y193140I0J200D01*
G01X932920Y193141D01*
G02X933907Y193511I987J-1131D01*
G02Y190507I0J-1502D01*
G02X932920Y190877I0J1501D01*
G01X932919D01*
Y190878D01*
G03X932789Y190926I-130J-152D01*
G01X932525D01*
G03X932395Y190878I0J-200D01*
G01X932394Y190877D01*
G02X931407Y190507I-987J1131D01*
G37*
G36*
G01X926645Y202304D02*
X926351D01*
G03X926204Y202239I1J-200D01*
G02X925098Y201754I-1106J1019D01*
G02Y204758I0J1502D01*
G02X926204Y204273I0J-1504D01*
G03X926351Y204208I148J135D01*
G01X926645D01*
G03X926792Y204273I-1J200D01*
G02X927898Y204758I1106J-1019D01*
G02Y201754I0J-1502D01*
G02X926792Y202239I0J1504D01*
G03X926645Y202304I-148J-135D01*
G37*
G36*
G01X932909Y207141D02*
G02X935913I1502J0D01*
G02X935543Y206154I-1501J0D01*
G01Y206153D01*
X935542D01*
G03X935494Y206023I152J-130D01*
G01Y205759D01*
G03X935542Y205629I200J0D01*
G01X935543Y205628D01*
G02Y203654I-1131J-987D01*
G01Y203653D01*
X935542D01*
G03X935494Y203523I152J-130D01*
G01Y203259D01*
G03X935542Y203129I200J0D01*
G01X935543Y203128D01*
G02X935913Y202141I-1131J-987D01*
G02X934411Y200639I-1502J0D01*
G02X933556Y200906I0J1502D01*
G01X933522Y200929D01*
X933441Y200946D01*
X933074Y200866D01*
X933007Y200818D01*
X932986Y200783D01*
G02X931698Y200054I-1288J773D01*
G02Y203058I0J1502D01*
G02X932553Y202791I0J-1502D01*
G01X932587Y202768D01*
X932668Y202751D01*
X933035Y202831D01*
X933102Y202879D01*
X933123Y202914D01*
G02X933279Y203127I1285J-777D01*
G03X933280Y203129I-173J88D01*
G03X933328Y203259I-152J130D01*
G01Y203523D01*
G03X933280Y203653I-200J0D01*
G01X933279Y203654D01*
G02Y205628I1131J987D01*
G01Y205629D01*
X933280D01*
G03X933328Y205759I-152J130D01*
G01Y206023D01*
G03X933280Y206153I-200J0D01*
G01X933279Y206154D01*
G02X932909Y207141I1131J987D01*
G37*
G36*
G01X1014570Y90701D02*
G02X1013900Y91951I831J1250D01*
G02X1016904I1502J0D01*
G02X1016254Y90714I-1502J0D01*
G03X1016259Y90051I227J-330D01*
G02X1016929Y88801I-831J-1250D01*
G02X1013925I-1502J0D01*
G02X1014575Y90038I1502J0D01*
G03X1014570Y90701I-227J330D01*
G37*
G36*
G01X963731Y91453D02*
G02X963177Y91347I-554J1395D01*
G02X964679Y92849I0J1502D01*
G02X964633Y92481I-1502J1D01*
G03X965169Y92011I388J-98D01*
G02X965723Y92117I554J-1395D01*
G02X964221Y90615I0J-1502D01*
G02X964267Y90983I1502J-1D01*
G03X963731Y91453I-388J98D01*
G37*
G36*
G01X969218Y101849D02*
G02X968635Y103037I919J1188D01*
G02X971639I1502J0D01*
G02X970983Y101796I-1502J0D01*
G03X970963Y101149I225J-331D01*
G02X971546Y99961I-919J-1188D01*
G02X968542I-1502J0D01*
G02X969198Y101202I1502J0D01*
G03X969218Y101849I-225J331D01*
G37*
G36*
G01X1004790Y102731D02*
G02X1004498Y103621I1210J890D01*
G02X1007502I1502J0D01*
G02X1006277Y102145I-1502J0D01*
G03X1006028Y101515I73J-393D01*
G02X1006320Y100625I-1210J-890D01*
G02X1003316I-1502J0D01*
G02X1004541Y102101I1502J0D01*
G03X1004790Y102731I-73J393D01*
G37*
G36*
G01X947878Y106561D02*
G02X950882I1502J0D01*
G02X950156Y105275I-1502J0D01*
G03X950060Y105114I104J-171D01*
G01X950042Y104782D01*
G03X950122Y104612I200J-10D01*
G02X950677Y103779I-901J-1202D01*
G03X950802Y103641I194J50D01*
G01X951111Y103526D01*
G03X951295Y103550I69J188D01*
G02X952161Y103825I866J-1226D01*
G02Y100821I0J-1502D01*
G02X950705Y101955I0J1502D01*
G03X950580Y102093I-194J-50D01*
G01X950271Y102208D01*
G03X950087Y102184I-69J-188D01*
G02X949221Y101909I-866J1226D01*
G02X947719Y103411I0J1502D01*
G02X948445Y104697I1502J0D01*
G03X948541Y104858I-104J171D01*
G01X948559Y105190D01*
G03X948479Y105360I-200J10D01*
G02X947878Y106561I901J1202D01*
G37*
G36*
G01X935753Y110018D02*
X936067D01*
G03X936225Y110095I0J200D01*
G02X937410Y110674I1185J-923D01*
G02X938912Y109172I0J-1502D01*
G02X937949Y107770I-1502J0D01*
G01X937947D01*
X937907Y107754D01*
X937848Y107694D01*
X937713Y107330D01*
X937719Y107245D01*
X937740Y107207D01*
G02X937919Y106497I-1323J-711D01*
G01Y106495D01*
G02X934915I-1502J0D01*
G02X935053Y107123I1502J-1D01*
G01Y107124D01*
G03X935032Y107327I-182J84D01*
G01X934787Y107653D01*
X934686Y107694D01*
X934631Y107686D01*
G02X934410Y107670I-219J1486D01*
G02Y110674I0J1502D01*
G02X935595Y110095I0J-1502D01*
G03X935753Y110018I158J123D01*
G37*
G36*
G01X935690Y148717D02*
G02X938694I1502J0D01*
G02X937689Y147300I-1501J0D01*
G03X937569Y147183I67J-188D01*
G01X937443Y146857D01*
X937449Y146770D01*
X937470Y146731D01*
G02X937653Y146013I-1319J-719D01*
G01Y146012D01*
G02X936993Y144768I-1502J0D01*
G03X936905Y144603I112J-166D01*
G01Y144271D01*
G03X936993Y144106I200J1D01*
G02X937638Y143074I-842J-1244D01*
G01Y143073D01*
G03X937706Y142950I198J29D01*
G01X937906Y142778D01*
G03X938039Y142730I130J152D01*
G01X938057D01*
G02Y139726I0J-1502D01*
G02X936570Y141016I0J1502D01*
G01Y141017D01*
G03X936502Y141140I-198J-29D01*
G01X936302Y141312D01*
G03X936169Y141360I-130J-152D01*
G01X936151D01*
G02X934649Y142862I0J1502D01*
G02X935309Y144106I1502J0D01*
G03X935397Y144271I-112J166D01*
G01Y144603D01*
G03X935309Y144768I-200J-1D01*
G02X934649Y146012I842J1244D01*
G02X935654Y147429I1501J0D01*
G03X935774Y147546I-67J188D01*
G01X935900Y147872D01*
X935894Y147959D01*
X935873Y147998D01*
G02X935690Y148716I1319J719D01*
G01Y148717D01*
G37*
G36*
G01X935537Y220041D02*
G02X934867Y221292I833J1251D01*
G02X937871I1502J0D01*
G02X937221Y220055I-1502J0D01*
G03X937227Y219393I227J-329D01*
G02X937897Y218142I-833J-1251D01*
G02X934893I-1502J0D01*
G02X935543Y219379I1502J0D01*
G03X935537Y220041I-227J329D01*
G37*
G36*
G01X989522Y224712D02*
G02X992526I1502J0D01*
G02X992156Y223725I-1501J0D01*
G01Y223724D01*
X992155D01*
G03X992107Y223594I152J-130D01*
G01Y223330D01*
G03X992155Y223200I200J0D01*
G01X992156Y223199D01*
G02X992526Y222212I-1131J-987D01*
G02X989522I-1502J0D01*
G02X989892Y223199I1501J0D01*
G01Y223200D01*
X989893D01*
G03X989941Y223330I-152J130D01*
G01Y223594D01*
G03X989893Y223724I-200J0D01*
G01X989892Y223725D01*
G02X989522Y224712I1131J987D01*
G37*
G36*
G01X984616Y225189D02*
X984322D01*
G03X984175Y225124I1J-200D01*
G02X983069Y224639I-1106J1019D01*
G02Y227643I0J1502D01*
G02X984175Y227158I0J-1504D01*
G03X984322Y227093I148J135D01*
G01X984616D01*
G03X984763Y227158I-1J200D01*
G02X985869Y227643I1106J-1019D01*
G02Y224639I0J-1502D01*
G02X984763Y225124I0J1504D01*
G03X984616Y225189I-148J-135D01*
G37*
G36*
G01X967404Y231226D02*
G02X970408I1502J0D01*
G02X970038Y230239I-1501J0D01*
G01Y230238D01*
X970037D01*
G03X969989Y230108I152J-130D01*
G01Y229844D01*
G03X970037Y229714I200J0D01*
G01X970038Y229713D01*
G02Y227739I-1131J-987D01*
G01Y227738D01*
X970037D01*
G03X969989Y227608I152J-130D01*
G01Y227344D01*
G03X970037Y227214I200J0D01*
G01X970038Y227213D01*
G02Y225239I-1131J-987D01*
G01Y225238D01*
X970037D01*
G03X969989Y225108I152J-130D01*
G01Y224844D01*
G03X970037Y224714I200J0D01*
G01X970038Y224713D01*
G02X970408Y223726I-1131J-987D01*
G02X967404I-1502J0D01*
G02X967774Y224713I1501J0D01*
G01Y224714D01*
X967775D01*
G03X967823Y224844I-152J130D01*
G01Y225108D01*
G03X967775Y225238I-200J0D01*
G01X967774Y225239D01*
G02Y227213I1131J987D01*
G01Y227214D01*
X967775D01*
G03X967823Y227344I-152J130D01*
G01Y227608D01*
G03X967775Y227738I-200J0D01*
G01X967774Y227739D01*
G02Y229713I1131J987D01*
G01Y229714D01*
X967775D01*
G03X967823Y229844I-152J130D01*
G01Y230108D01*
G03X967775Y230238I-200J0D01*
G01X967774Y230239D01*
G02X967404Y231226I1131J987D01*
G37*
G36*
G01X977860Y231461D02*
G02X980864I1502J0D01*
G02X980494Y230474I-1501J0D01*
G01Y230473D01*
X980493D01*
G03X980445Y230343I152J-130D01*
G01Y230079D01*
G03X980493Y229949I200J0D01*
G01X980494Y229948D01*
G02Y227974I-1131J-987D01*
G01Y227973D01*
X980493D01*
G03X980445Y227843I152J-130D01*
G01Y227579D01*
G03X980493Y227449I200J0D01*
G01X980494Y227448D01*
G02X980864Y226461I-1131J-987D01*
G02X980379Y225355I-1504J0D01*
G03X980314Y225208I135J-148D01*
G01Y224914D01*
G03X980379Y224767I200J1D01*
G02X980864Y223661I-1019J-1106D01*
G02X977860I-1502J0D01*
G02X978345Y224767I1504J0D01*
G03X978410Y224914I-135J148D01*
G01Y225208D01*
G03X978345Y225355I-200J-1D01*
G02X977860Y226461I1019J1106D01*
G02X978230Y227448I1501J0D01*
G01Y227449D01*
X978231D01*
G03X978279Y227579I-152J130D01*
G01Y227843D01*
G03X978231Y227973I-200J0D01*
G01X978230Y227974D01*
G02Y229948I1131J987D01*
G01Y229949D01*
X978231D01*
G03X978279Y230079I-152J130D01*
G01Y230343D01*
G03X978231Y230473I-200J0D01*
G01X978230Y230474D01*
G02X977860Y231461I1131J987D01*
G37*
G36*
G01X985829Y231786D02*
G02X988833I1502J0D01*
G02X988463Y230799I-1501J0D01*
G01Y230798D01*
X988462D01*
G03X988414Y230668I152J-130D01*
G01Y230404D01*
G03X988462Y230274I200J0D01*
G01X988463Y230273D01*
G02X988833Y229286I-1131J-987D01*
G02X985829I-1502J0D01*
G02X986199Y230273I1501J0D01*
G01Y230274D01*
X986200D01*
G03X986248Y230404I-152J130D01*
G01Y230668D01*
G03X986200Y230798I-200J0D01*
G01X986199Y230799D01*
G02X985829Y231786I1131J987D01*
G37*
G36*
G01X986799Y237743D02*
X986800Y237742D01*
G03X986930Y237694I130J152D01*
G01X987194D01*
G03X987324Y237742I0J200D01*
G01X987325Y237743D01*
G02X988312Y238113I987J-1131D01*
G02Y235109I0J-1502D01*
G02X987325Y235479I0J1501D01*
G01X987324D01*
Y235480D01*
G03X987194Y235528I-130J-152D01*
G01X986930D01*
G03X986800Y235480I0J-200D01*
G01X986799Y235479D01*
G02X984825I-987J1131D01*
G01X984824D01*
Y235480D01*
G03X984694Y235528I-130J-152D01*
G01X984430D01*
G03X984300Y235480I0J-200D01*
G01X984299Y235479D01*
G02X983312Y235109I-987J1131D01*
G02Y238113I0J1502D01*
G02X984299Y237743I0J-1501D01*
G01X984300D01*
Y237742D01*
G03X984430Y237694I130J152D01*
G01X984694D01*
G03X984824Y237742I0J200D01*
G01X984825Y237743D01*
G02X986799I987J-1131D01*
G37*
G36*
G01X986501Y250023D02*
X986502Y250022D01*
G03X986632Y249974I130J152D01*
G01X986896D01*
G03X987026Y250022I0J200D01*
G01X987027Y250023D01*
G02X988014Y250393I987J-1131D01*
G02Y247389I0J-1502D01*
G02X987027Y247759I0J1501D01*
G01X987026D01*
Y247760D01*
G03X986896Y247808I-130J-152D01*
G01X986632D01*
G03X986502Y247760I0J-200D01*
G01X986501Y247759D01*
G02X984527I-987J1131D01*
G01X984526D01*
Y247760D01*
G03X984396Y247808I-130J-152D01*
G01X984132D01*
G03X984002Y247760I0J-200D01*
G01X984001Y247759D01*
G02X983014Y247389I-987J1131D01*
G02Y250393I0J1502D01*
G02X984001Y250023I0J-1501D01*
G01X984002D01*
Y250022D01*
G03X984132Y249974I130J152D01*
G01X984396D01*
G03X984526Y250022I0J200D01*
G01X984527Y250023D01*
G02X986501I987J-1131D01*
G37*
G36*
G01X944980Y255940D02*
G02X947984I1502J0D01*
G02X947245Y254646I-1502J0D01*
G01X947206Y254623D01*
X947156Y254548D01*
X947105Y254192D01*
G03X947157Y254028I198J-27D01*
G02X947566Y252998I-1092J-1030D01*
G02X944562I-1502J0D01*
G02X945301Y254292I1502J0D01*
G01X945340Y254315D01*
X945390Y254390D01*
X945441Y254746D01*
G03X945389Y254910I-198J27D01*
G02X944980Y255940I1092J1030D01*
G37*
G36*
G01X988391Y190705D02*
G02X987743Y191941I855J1236D01*
G02X990747I1502J0D01*
G02X989994Y190639I-1502J0D01*
G03X989966Y189963I199J-347D01*
G02X990614Y188727I-855J-1236D01*
G02X987610I-1502J0D01*
G02X988363Y190029I1502J0D01*
G03X988391Y190705I-199J347D01*
G37*
G36*
G01X1016745Y1008703D02*
X1016451D01*
G03X1016304Y1008638I1J-200D01*
G02X1015198Y1008153I-1105J1017D01*
G02Y1011157I0J1502D01*
G02X1016304Y1010672I1J-1502D01*
G03X1016451Y1010607I148J135D01*
G01X1016745D01*
G03X1016892Y1010672I-1J200D01*
G02X1017998Y1011157I1105J-1017D01*
G02Y1008153I0J-1502D01*
G02X1016892Y1008638I-1J1502D01*
G03X1016745Y1008703I-148J-135D01*
G37*
G36*
G01X1049878Y1010637D02*
X1049872Y1011046D01*
X1049831Y1011127D01*
X1049794Y1011156D01*
G02X1049197Y1012354I905J1199D01*
G02X1052201I1502J0D01*
G02X1051640Y1011183I-1503J0D01*
G01X1051604Y1011154D01*
X1051565Y1011071D01*
X1051571Y1010662D01*
X1051612Y1010581D01*
X1051649Y1010552D01*
G02X1052246Y1009354I-905J-1199D01*
G02X1049242I-1502J0D01*
G02X1049803Y1010525I1503J0D01*
G01X1049839Y1010554D01*
X1049878Y1010637D01*
G37*
G36*
G01Y1023237D02*
X1049872Y1023646D01*
X1049831Y1023727D01*
X1049794Y1023756D01*
G02X1049197Y1024954I905J1199D01*
G02X1052201I1502J0D01*
G02X1051640Y1023783I-1503J0D01*
G01X1051604Y1023754D01*
X1051565Y1023671D01*
X1051571Y1023262D01*
X1051612Y1023181D01*
X1051649Y1023152D01*
G02X1052246Y1021954I-905J-1199D01*
G02X1049242I-1502J0D01*
G02X1049803Y1023125I1503J0D01*
G01X1049839Y1023154D01*
X1049878Y1023237D01*
G37*
G36*
G01X1020485Y1031518D02*
X1020801D01*
G03X1020958Y1031595I-1J200D01*
G02X1023328I1185J-923D01*
G03X1023485Y1031518I158J123D01*
G01X1023801D01*
G03X1023958Y1031595I-1J200D01*
G02X1025143Y1032174I1185J-923D01*
G02Y1029170I0J-1502D01*
G02X1023958Y1029749I0J1502D01*
G03X1023801Y1029826I-158J-123D01*
G01X1023485D01*
G03X1023328Y1029749I1J-200D01*
G02X1020958I-1185J923D01*
G03X1020801Y1029826I-158J-123D01*
G01X1020485D01*
G03X1020328Y1029749I1J-200D01*
G02X1017958I-1185J923D01*
G03X1017801Y1029826I-158J-123D01*
G01X1017485D01*
G03X1017328Y1029749I1J-200D01*
G02X1016143Y1029170I-1185J923D01*
G02Y1032174I0J1502D01*
G02X1017328Y1031595I0J-1502D01*
G03X1017485Y1031518I158J123D01*
G01X1017801D01*
G03X1017958Y1031595I-1J200D01*
G02X1020328I1185J-923D01*
G03X1020485Y1031518I158J123D01*
G37*
G36*
G01X1038232Y1115974D02*
X1038226Y1116383D01*
X1038185Y1116464D01*
X1038148Y1116493D01*
G02X1037551Y1117691I905J1199D01*
G02X1040555I1502J0D01*
G02X1039994Y1116520I-1503J0D01*
G01X1039958Y1116491D01*
X1039919Y1116408D01*
X1039925Y1115999D01*
X1039966Y1115918D01*
X1040003Y1115889D01*
G02X1040600Y1114691I-905J-1199D01*
G02X1037596I-1502J0D01*
G02X1038157Y1115862I1503J0D01*
G01X1038193Y1115891D01*
X1038232Y1115974D01*
G37*
G36*
G01Y1128574D02*
X1038226Y1128983D01*
X1038185Y1129064D01*
X1038148Y1129093D01*
G02X1037551Y1130291I905J1199D01*
G02X1040555I1502J0D01*
G02X1039994Y1129120I-1503J0D01*
G01X1039958Y1129091D01*
X1039919Y1129008D01*
X1039925Y1128599D01*
X1039966Y1128518D01*
X1040003Y1128489D01*
G02X1040600Y1127291I-905J-1199D01*
G02X1037596I-1502J0D01*
G02X1038157Y1128462I1503J0D01*
G01X1038193Y1128491D01*
X1038232Y1128574D01*
G37*
G36*
G01Y1141174D02*
X1038226Y1141583D01*
X1038185Y1141664D01*
X1038148Y1141693D01*
G02X1037551Y1142891I905J1199D01*
G02X1040555I1502J0D01*
G02X1039994Y1141720I-1503J0D01*
G01X1039958Y1141691D01*
X1039919Y1141608D01*
X1039925Y1141199D01*
X1039966Y1141118D01*
X1040003Y1141089D01*
G02X1040600Y1139891I-905J-1199D01*
G02X1037596I-1502J0D01*
G02X1038157Y1141062I1503J0D01*
G01X1038193Y1141091D01*
X1038232Y1141174D01*
G37*
G36*
G01Y1153774D02*
X1038226Y1154183D01*
X1038185Y1154264D01*
X1038148Y1154293D01*
G02X1037551Y1155491I905J1199D01*
G02X1040555I1502J0D01*
G02X1039994Y1154320I-1503J0D01*
G01X1039958Y1154291D01*
X1039919Y1154208D01*
X1039925Y1153799D01*
X1039966Y1153718D01*
X1040003Y1153689D01*
G02X1040600Y1152491I-905J-1199D01*
G02X1037596I-1502J0D01*
G02X1038157Y1153662I1503J0D01*
G01X1038193Y1153691D01*
X1038232Y1153774D01*
G37*
G36*
G01X1006613Y1005828D02*
G02X1005301Y1005058I-1312J733D01*
G02Y1008062I0J1502D01*
G02X1006572Y1007361I0J-1503D01*
G03X1007259Y1007380I338J214D01*
G02X1008571Y1008150I1312J-733D01*
G02Y1005146I0J-1502D01*
G02X1007300Y1005847I0J1503D01*
G03X1006613Y1005828I-338J-214D01*
G37*
G36*
G01X1072347Y1013361D02*
X1072374Y1013393D01*
G02X1073525Y1013930I1151J-965D01*
G02X1074712Y1013348I0J-1501D01*
G01X1074746Y1013305D01*
X1074845Y1013265D01*
X1075297Y1013330D01*
X1075381Y1013396D01*
X1075401Y1013447D01*
G02X1076800Y1014402I1399J-547D01*
G02Y1011398I0J-1502D01*
G02X1075613Y1011980I0J1501D01*
G01X1075579Y1012023D01*
X1075480Y1012063D01*
X1075028Y1011998D01*
X1074944Y1011932D01*
X1074924Y1011881D01*
G02X1073525Y1010926I-1399J547D01*
G02X1072507Y1011324I0J1501D01*
G01X1072476Y1011352D01*
X1072400Y1011379D01*
X1072028Y1011355D01*
X1071956Y1011319D01*
X1071929Y1011287D01*
G02X1070778Y1010750I-1151J965D01*
G02Y1013754I0J1502D01*
G02X1071796Y1013356I0J-1501D01*
G01X1071827Y1013328D01*
X1071903Y1013301D01*
X1072275Y1013325D01*
X1072347Y1013361D01*
G37*
G36*
G01X987365Y1018794D02*
G02X986738Y1020015I875J1221D01*
G02X989742I1502J0D01*
G02X989115Y1018794I-1502J0D01*
G03X989031Y1018632I116J-163D01*
G01Y1018306D01*
G03X989115Y1018144I200J1D01*
G02X989742Y1016923I-875J-1221D01*
G02X989201Y1015769I-1501J0D01*
G01X989164Y1015738D01*
X989126Y1015649D01*
X989156Y1015228D01*
X989206Y1015146D01*
X989248Y1015121D01*
G02X989963Y1013841I-788J-1280D01*
G02X986959I-1502J0D01*
G02X987500Y1014995I1501J0D01*
G01X987537Y1015026D01*
X987575Y1015115D01*
X987545Y1015536D01*
X987495Y1015618D01*
X987453Y1015643D01*
G02X986738Y1016923I788J1280D01*
G02X987365Y1018144I1502J0D01*
G03X987449Y1018306I-116J163D01*
G01Y1018632D01*
G03X987365Y1018794I-200J-1D01*
G37*
G36*
G01X1078579Y1033522D02*
X1078553Y1033562D01*
G02X1078307Y1034386I1257J824D01*
G02X1081311I1502J0D01*
G02X1080233Y1032945I-1502J0D01*
G01X1080187Y1032932D01*
X1080118Y1032867D01*
X1079974Y1032476D01*
X1079985Y1032382D01*
X1080011Y1032342D01*
G02X1080257Y1031518I-1257J-824D01*
G02X1078755Y1030016I-1502J0D01*
G02X1078156Y1030140I-1J1502D01*
G01X1078107Y1030162D01*
X1078000Y1030150D01*
X1077635Y1029876D01*
X1077593Y1029777D01*
X1077600Y1029723D01*
G02X1077612Y1029535I-1490J-189D01*
G02X1076110Y1031037I-1502J0D01*
G02X1076709Y1030913I1J-1502D01*
G01X1076758Y1030891D01*
X1076865Y1030903D01*
X1077230Y1031177D01*
X1077272Y1031276D01*
X1077265Y1031330D01*
G02X1077253Y1031518I1490J189D01*
G02X1078331Y1032959I1502J0D01*
G01X1078377Y1032972D01*
X1078446Y1033037D01*
X1078590Y1033428D01*
X1078579Y1033522D01*
G37*
G36*
G01X1044462Y1034188D02*
G02X1043553Y1033882I-909J1197D01*
G02Y1036886I0J1502D01*
G02X1044959Y1035912I0J-1502D01*
G03X1045576Y1035734I375J140D01*
G02X1046485Y1036040I909J-1197D01*
G02Y1033036I0J-1502D01*
G02X1045079Y1034010I0J1502D01*
G03X1044462Y1034188I-375J-140D01*
G37*
G36*
G01X1059645Y1052460D02*
G02X1059266Y1053457I1122J997D01*
G02X1062270I1502J0D01*
G02X1061420Y1052104I-1502J0D01*
G03X1061295Y1051478I174J-360D01*
G02X1061674Y1050481I-1122J-997D01*
G02X1058670I-1502J0D01*
G02X1059520Y1051834I1502J0D01*
G03X1059645Y1052460I-174J360D01*
G37*
G36*
G01X1072226Y1056646D02*
G02X1071641Y1056527I-586J1383D01*
G02X1073143Y1058029I0J1502D01*
G02X1073102Y1057681I-1502J1D01*
G03X1073647Y1057219I389J-94D01*
G02X1074232Y1057338I586J-1383D01*
G02X1072730Y1055836I0J-1502D01*
G02X1072771Y1056184I1502J-1D01*
G03X1072226Y1056646I-389J94D01*
G37*
G36*
G01X1038185Y1103864D02*
X1038148Y1103893D01*
G02X1037551Y1105091I905J1199D01*
G02X1040555I1502J0D01*
G02X1039994Y1103920I-1503J0D01*
G01X1039958Y1103891D01*
X1039919Y1103808D01*
X1039925Y1103399D01*
X1039966Y1103318D01*
X1040003Y1103289D01*
G02X1040600Y1102091I-905J-1199D01*
G02X1039958Y1100859I-1503J0D01*
G01X1039912Y1100827D01*
X1039867Y1100727D01*
X1039922Y1100265D01*
X1039990Y1100179D01*
X1040042Y1100158D01*
G02X1041001Y1098758I-542J-1400D01*
G02X1037997I-1502J0D01*
G02X1038639Y1099990I1503J0D01*
G01X1038685Y1100022D01*
X1038730Y1100122D01*
X1038675Y1100584D01*
X1038607Y1100670D01*
X1038555Y1100691D01*
G02X1037596Y1102091I542J1400D01*
G02X1038157Y1103262I1503J0D01*
G01X1038193Y1103291D01*
X1038232Y1103374D01*
X1038226Y1103783D01*
X1038185Y1103864D01*
G37*
G36*
G01X1093611Y1110457D02*
X1093602Y1110506D01*
G02X1093581Y1110728I1181J224D01*
G02X1095985I1202J0D01*
G02X1095964Y1110506I-1202J2D01*
G01X1095955Y1110457D01*
X1095984Y1110364D01*
X1096289Y1110059D01*
X1096382Y1110030D01*
X1096431Y1110039D01*
G02X1096653Y1110060I224J-1181D01*
G02X1095451Y1108858I0J-1202D01*
G02X1095472Y1109080I1202J-2D01*
G01X1095481Y1109129D01*
X1095452Y1109222D01*
X1095147Y1109527D01*
X1095054Y1109556D01*
X1095005Y1109547D01*
G02X1094783Y1109526I-224J1181D01*
G02X1094561Y1109547I2J1202D01*
G01X1094512Y1109556D01*
X1094419Y1109527D01*
X1094114Y1109222D01*
X1094085Y1109129D01*
X1094094Y1109080D01*
G02X1094115Y1108858I-1181J-224D01*
G02X1091711I-1202J0D01*
G02X1091732Y1109080I1202J-2D01*
G01X1091741Y1109129D01*
X1091712Y1109222D01*
X1091407Y1109527D01*
X1091314Y1109556D01*
X1091265Y1109547D01*
G02X1091043Y1109526I-224J1181D01*
G02X1090820Y1109547I1J1202D01*
G01X1090772Y1109556D01*
X1090677Y1109527D01*
X1090373Y1109223D01*
X1090344Y1109129D01*
X1090353Y1109080D01*
G02X1090374Y1108858I-1181J-224D01*
G02X1089172Y1107656I-1202J0D01*
G02X1088950Y1107677I2J1202D01*
G01X1088901Y1107686D01*
X1088808Y1107657D01*
X1088503Y1107352D01*
X1088474Y1107259D01*
X1088483Y1107210D01*
G02X1088504Y1106988I-1181J-224D01*
G02X1088483Y1106765I-1202J1D01*
G01X1088474Y1106717D01*
X1088503Y1106622D01*
X1088807Y1106318D01*
X1088901Y1106289D01*
X1088950Y1106298D01*
G02X1089172Y1106319I224J-1181D01*
G02X1087970Y1105117I0J-1202D01*
G02X1087991Y1105340I1202J-1D01*
G01X1088000Y1105388D01*
X1087971Y1105483D01*
X1087667Y1105787D01*
X1087573Y1105816D01*
X1087524Y1105807D01*
G02X1087302Y1105786I-224J1181D01*
G02Y1108190I0J1202D01*
G02X1087524Y1108169I-2J-1202D01*
G01X1087573Y1108160D01*
X1087666Y1108189D01*
X1087971Y1108494D01*
X1088000Y1108587D01*
X1087991Y1108636D01*
G02X1087970Y1108858I1181J224D01*
G02X1087991Y1109080I1202J-2D01*
G01X1088000Y1109129D01*
X1087971Y1109222D01*
X1087666Y1109527D01*
X1087573Y1109556D01*
X1087524Y1109547D01*
G02X1087302Y1109526I-224J1181D01*
G02X1088504Y1110728I0J1202D01*
G02X1088483Y1110506I-1202J2D01*
G01X1088474Y1110457D01*
X1088503Y1110364D01*
X1088808Y1110059D01*
X1088901Y1110030D01*
X1088950Y1110039D01*
G02X1089172Y1110060I224J-1181D01*
G02X1089395Y1110039I-1J-1202D01*
G01X1089443Y1110030D01*
X1089538Y1110059D01*
X1089842Y1110363D01*
X1089871Y1110457D01*
X1089862Y1110506D01*
G02X1089841Y1110728I1181J224D01*
G02X1092245I1202J0D01*
G02X1092224Y1110506I-1202J2D01*
G01X1092215Y1110457D01*
X1092244Y1110364D01*
X1092549Y1110059D01*
X1092642Y1110030D01*
X1092691Y1110039D01*
G02X1092913Y1110060I224J-1181D01*
G02X1093135Y1110039I-2J-1202D01*
G01X1093184Y1110030D01*
X1093277Y1110059D01*
X1093582Y1110364D01*
X1093611Y1110457D01*
G37*
G36*
G01X1131012Y1114197D02*
X1131003Y1114246D01*
G02X1130982Y1114468I1181J224D01*
G02X1132184Y1113266I1202J0D01*
G02X1131962Y1113287I2J1202D01*
G01X1131913Y1113296D01*
X1131820Y1113267D01*
X1131515Y1112962D01*
X1131486Y1112869D01*
X1131495Y1112820D01*
G02X1131516Y1112598I-1181J-224D01*
G02X1129112I-1202J0D01*
G02X1129133Y1112820I1202J-2D01*
G01X1129142Y1112869D01*
X1129113Y1112962D01*
X1128808Y1113267D01*
X1128715Y1113296D01*
X1128666Y1113287D01*
G02X1128444Y1113266I-224J1181D01*
G02X1129646Y1114468I0J1202D01*
G02X1129625Y1114246I-1202J2D01*
G01X1129616Y1114197D01*
X1129645Y1114104D01*
X1129950Y1113799D01*
X1130043Y1113770D01*
X1130092Y1113779D01*
G02X1130314Y1113800I224J-1181D01*
G02X1130536Y1113779I-2J-1202D01*
G01X1130585Y1113770D01*
X1130678Y1113799D01*
X1130983Y1114104D01*
X1131012Y1114197D01*
G37*
G36*
G01X1212820Y1193700D02*
G02X1212598Y1193679I-224J1181D01*
G02X1213800Y1194881I0J1202D01*
G02X1213779Y1194659I-1202J2D01*
G03X1214246Y1194192I393J-74D01*
G02X1214468Y1194213I224J-1181D01*
G02X1213266Y1193011I0J-1202D01*
G02X1213287Y1193233I1202J-2D01*
G03X1212820Y1193700I-393J74D01*
G37*
G36*
G01X1222646Y1194610D02*
X1222637Y1194659D01*
G02X1222616Y1194881I1181J224D01*
G02X1225020I1202J0D01*
G02X1224999Y1194659I-1202J2D01*
G01X1224990Y1194610D01*
X1225019Y1194517D01*
X1225324Y1194212D01*
X1225417Y1194183D01*
X1225466Y1194192D01*
G02X1225688Y1194213I224J-1181D01*
G02X1224486Y1193011I0J-1202D01*
G02X1224507Y1193233I1202J-2D01*
G01X1224516Y1193282D01*
X1224487Y1193375D01*
X1224182Y1193680D01*
X1224089Y1193709D01*
X1224040Y1193700D01*
G02X1223818Y1193679I-224J1181D01*
G02X1223596Y1193700I2J1202D01*
G01X1223547Y1193709D01*
X1223454Y1193680D01*
X1223149Y1193375D01*
X1223120Y1193282D01*
X1223129Y1193233D01*
G02X1223150Y1193011I-1181J-224D01*
G02X1221948Y1194213I-1202J0D01*
G02X1222170Y1194192I-2J-1202D01*
G01X1222219Y1194183D01*
X1222312Y1194212D01*
X1222617Y1194517D01*
X1222646Y1194610D01*
G37*
G36*
G01X1233867Y1198350D02*
X1233858Y1198399D01*
G02X1233837Y1198621I1181J224D01*
G02X1235039Y1197419I1202J0D01*
G02X1234817Y1197440I2J1202D01*
G01X1234768Y1197449D01*
X1234675Y1197420D01*
X1234370Y1197115D01*
X1234341Y1197022D01*
X1234350Y1196973D01*
G02X1234371Y1196751I-1181J-224D01*
G02X1231967I-1202J0D01*
G02X1231988Y1196973I1202J-2D01*
G01X1231997Y1197022D01*
X1231968Y1197116D01*
X1231664Y1197420D01*
X1231569Y1197449D01*
X1231521Y1197440D01*
G02X1231298Y1197419I-224J1181D01*
G02X1231076Y1197440I2J1202D01*
G01X1231027Y1197449D01*
X1230934Y1197420D01*
X1230629Y1197115D01*
X1230600Y1197022D01*
X1230609Y1196973D01*
G02X1230630Y1196751I-1181J-224D01*
G02X1228226I-1202J0D01*
G02X1228247Y1196973I1202J-2D01*
G01X1228256Y1197022D01*
X1228227Y1197115D01*
X1227922Y1197420D01*
X1227829Y1197449D01*
X1227780Y1197440D01*
G02X1227558Y1197419I-224J1181D01*
G02X1228760Y1198621I0J1202D01*
G02X1228739Y1198399I-1202J2D01*
G01X1228730Y1198350D01*
X1228759Y1198257D01*
X1229064Y1197952D01*
X1229157Y1197923D01*
X1229206Y1197932D01*
G02X1229428Y1197953I224J-1181D01*
G02X1229650Y1197932I-2J-1202D01*
G01X1229699Y1197923D01*
X1229792Y1197952D01*
X1230097Y1198257D01*
X1230126Y1198350D01*
X1230117Y1198399D01*
G02X1230096Y1198621I1181J224D01*
G02X1232500I1202J0D01*
G02X1232479Y1198399I-1202J2D01*
G01X1232470Y1198350D01*
X1232499Y1198256D01*
X1232803Y1197952D01*
X1232898Y1197923D01*
X1232946Y1197932D01*
G02X1233169Y1197953I224J-1181D01*
G02X1233391Y1197932I-2J-1202D01*
G01X1233440Y1197923D01*
X1233533Y1197952D01*
X1233838Y1198257D01*
X1233867Y1198350D01*
G37*
G36*
G01X1115576Y1216141D02*
G02X1115354Y1216120I-224J1181D01*
G02X1116556Y1217322I0J1202D01*
G02X1116535Y1217100I-1202J2D01*
G03X1117002Y1216633I393J-74D01*
G02X1117224Y1216654I224J-1181D01*
G02X1116022Y1215452I0J-1202D01*
G02X1116043Y1215674I1202J-2D01*
G03X1115576Y1216141I-393J74D01*
G37*
G36*
G01X1132882Y1217051D02*
X1132873Y1217100D01*
G02X1132852Y1217322I1181J224D01*
G02X1135256I1202J0D01*
G02X1135235Y1217100I-1202J2D01*
G01X1135226Y1217051D01*
X1135255Y1216957D01*
X1135559Y1216653D01*
X1135654Y1216624D01*
X1135702Y1216633D01*
G02X1135925Y1216654I224J-1181D01*
G02X1134723Y1215452I0J-1202D01*
G02X1134744Y1215674I1202J-2D01*
G01X1134753Y1215723D01*
X1134724Y1215817D01*
X1134420Y1216121D01*
X1134325Y1216150D01*
X1134277Y1216141D01*
G02X1134054Y1216120I-224J1181D01*
G02X1133832Y1216141I2J1202D01*
G01X1133783Y1216150D01*
X1133690Y1216121D01*
X1133385Y1215816D01*
X1133356Y1215723D01*
X1133365Y1215674D01*
G02X1133386Y1215452I-1181J-224D01*
G02X1132184Y1216654I-1202J0D01*
G02X1132406Y1216633I-2J-1202D01*
G01X1132455Y1216624D01*
X1132548Y1216653D01*
X1132853Y1216958D01*
X1132882Y1217051D01*
G37*
G36*
G01X1155323D02*
X1155314Y1217100D01*
G02X1155293Y1217322I1181J224D01*
G02X1157697I1202J0D01*
G02X1157676Y1217100I-1202J2D01*
G01X1157667Y1217051D01*
X1157696Y1216958D01*
X1158001Y1216653D01*
X1158094Y1216624D01*
X1158143Y1216633D01*
G02X1158365Y1216654I224J-1181D01*
G02X1157163Y1215452I0J-1202D01*
G02X1157184Y1215674I1202J-2D01*
G01X1157193Y1215723D01*
X1157164Y1215816D01*
X1156859Y1216121D01*
X1156766Y1216150D01*
X1156717Y1216141D01*
G02X1156495Y1216120I-224J1181D01*
G02X1156273Y1216141I2J1202D01*
G01X1156224Y1216150D01*
X1156131Y1216121D01*
X1155826Y1215816D01*
X1155797Y1215723D01*
X1155806Y1215674D01*
G02X1155827Y1215452I-1181J-224D01*
G02X1153423I-1202J0D01*
G02X1153444Y1215674I1202J-2D01*
G01X1153453Y1215723D01*
X1153424Y1215816D01*
X1153119Y1216121D01*
X1153026Y1216150D01*
X1152977Y1216141D01*
G02X1152755Y1216120I-224J1181D01*
G02X1152533Y1216141I2J1202D01*
G01X1152484Y1216150D01*
X1152391Y1216121D01*
X1152086Y1215816D01*
X1152057Y1215723D01*
X1152066Y1215674D01*
G02X1152087Y1215452I-1181J-224D01*
G02X1150885Y1216654I-1202J0D01*
G02X1151107Y1216633I-2J-1202D01*
G01X1151156Y1216624D01*
X1151249Y1216653D01*
X1151554Y1216958D01*
X1151583Y1217051D01*
X1151574Y1217100D01*
G02X1151553Y1217322I1181J224D01*
G02X1153957I1202J0D01*
G02X1153936Y1217100I-1202J2D01*
G01X1153927Y1217051D01*
X1153956Y1216958D01*
X1154261Y1216653D01*
X1154354Y1216624D01*
X1154403Y1216633D01*
G02X1154625Y1216654I224J-1181D01*
G02X1154847Y1216633I-2J-1202D01*
G01X1154896Y1216624D01*
X1154989Y1216653D01*
X1155294Y1216958D01*
X1155323Y1217051D01*
G37*
G36*
G01X1226386Y1224532D02*
X1226377Y1224580D01*
G02X1226356Y1224803I1181J224D01*
G02X1227558Y1223601I1202J0D01*
G02X1227336Y1223622I2J1202D01*
G01X1227287Y1223631D01*
X1227193Y1223602D01*
X1226889Y1223298D01*
X1226860Y1223203D01*
X1226869Y1223155D01*
G02X1226890Y1222932I-1181J-224D01*
G02X1226869Y1222710I-1202J2D01*
G01X1226860Y1222661D01*
X1226889Y1222568D01*
X1227194Y1222263D01*
X1227287Y1222234D01*
X1227336Y1222243D01*
G02X1227558Y1222264I224J-1181D01*
G02X1226356Y1221062I0J-1202D01*
G02X1226377Y1221284I1202J-2D01*
G01X1226386Y1221333D01*
X1226357Y1221426D01*
X1226052Y1221731D01*
X1225959Y1221760D01*
X1225910Y1221751D01*
G02X1225688Y1221730I-224J1181D01*
G02X1225466Y1221751I2J1202D01*
G01X1225417Y1221760D01*
X1225324Y1221731D01*
X1225019Y1221426D01*
X1224990Y1221333D01*
X1224999Y1221284D01*
G02X1225020Y1221062I-1181J-224D01*
G02X1223818Y1222264I-1202J0D01*
G02X1224040Y1222243I-2J-1202D01*
G01X1224089Y1222234D01*
X1224182Y1222263D01*
X1224487Y1222568D01*
X1224516Y1222661D01*
X1224507Y1222710D01*
G02X1224486Y1222932I1181J224D01*
G02X1224507Y1223155I1202J-1D01*
G01X1224516Y1223203D01*
X1224487Y1223298D01*
X1224183Y1223602D01*
X1224089Y1223631D01*
X1224040Y1223622D01*
G02X1223818Y1223601I-224J1181D01*
G02X1225020Y1224803I0J1202D01*
G02X1224999Y1224580I-1202J1D01*
G01X1224990Y1224532D01*
X1225019Y1224437D01*
X1225323Y1224133D01*
X1225417Y1224104D01*
X1225466Y1224113D01*
G02X1225688Y1224134I224J-1181D01*
G02X1225910Y1224113I-2J-1202D01*
G01X1225959Y1224104D01*
X1226053Y1224133D01*
X1226357Y1224437D01*
X1226386Y1224532D01*
G37*
G36*
G01X1066953Y1409998D02*
X1070353D01*
G02Y1406992I0J-1503D01*
G01X1066953D01*
G02Y1409998I0J1503D01*
G37*
G36*
G01Y1398086D02*
X1070353D01*
G02Y1395080I0J-1503D01*
G01X1066953D01*
G02Y1398086I0J1503D01*
G37*
G36*
G01X1079193D02*
X1082593D01*
G02Y1395080I0J-1503D01*
G01X1079193D01*
G02Y1398086I0J1503D01*
G37*
G36*
G01Y1409998D02*
X1082593D01*
G02Y1406992I0J-1503D01*
G01X1079193D01*
G02Y1409998I0J1503D01*
G37*
G36*
G01X1091433D02*
X1094833D01*
G02Y1406992I0J-1503D01*
G01X1091433D01*
G02Y1409998I0J1503D01*
G37*
G36*
G01Y1398086D02*
X1094833D01*
G02Y1395080I0J-1503D01*
G01X1091433D01*
G02Y1398086I0J1503D01*
G37*
G36*
G01X1103673Y1409998D02*
X1107073D01*
G02Y1406992I0J-1503D01*
G01X1103673D01*
G02Y1409998I0J1503D01*
G37*
G36*
G01Y1398086D02*
X1107073D01*
G02Y1395080I0J-1503D01*
G01X1103673D01*
G02Y1398086I0J1503D01*
G37*
G36*
G01X1115913Y1409998D02*
X1119313D01*
G02Y1406992I0J-1503D01*
G01X1115913D01*
G02Y1409998I0J1503D01*
G37*
G36*
G01Y1398086D02*
X1119313D01*
G02Y1395080I0J-1503D01*
G01X1115913D01*
G02Y1398086I0J1503D01*
G37*
G36*
G01X1128153Y1409998D02*
X1131553D01*
G02Y1406992I0J-1503D01*
G01X1128153D01*
G02Y1409998I0J1503D01*
G37*
G36*
G01Y1398086D02*
X1131553D01*
G02Y1395080I0J-1503D01*
G01X1128153D01*
G02Y1398086I0J1503D01*
G37*
G36*
G01X1140393D02*
X1143793D01*
G02Y1395080I0J-1503D01*
G01X1140393D01*
G02Y1398086I0J1503D01*
G37*
G36*
G01Y1409998D02*
X1143793D01*
G02Y1406992I0J-1503D01*
G01X1140393D01*
G02Y1409998I0J1503D01*
G37*
G36*
G01X1152633D02*
X1156033D01*
G02Y1406992I0J-1503D01*
G01X1152633D01*
G02Y1409998I0J1503D01*
G37*
G36*
G01Y1398086D02*
X1156033D01*
G02Y1395080I0J-1503D01*
G01X1152633D01*
G02Y1398086I0J1503D01*
G37*
G36*
G01X1164873Y1409998D02*
X1168273D01*
G02Y1406992I0J-1503D01*
G01X1164873D01*
G02Y1409998I0J1503D01*
G37*
G36*
G01Y1398086D02*
X1168273D01*
G02Y1395080I0J-1503D01*
G01X1164873D01*
G02Y1398086I0J1503D01*
G37*
G36*
G01X1177113D02*
X1180513D01*
G02Y1395080I0J-1503D01*
G01X1177113D01*
G02Y1398086I0J1503D01*
G37*
G36*
G01Y1409998D02*
X1180513D01*
G02Y1406992I0J-1503D01*
G01X1177113D01*
G02Y1409998I0J1503D01*
G37*
G36*
G01Y1385800D02*
X1180513D01*
G02Y1382794I0J-1503D01*
G01X1177113D01*
G02Y1385800I0J1503D01*
G37*
G36*
G01Y1373888D02*
X1180513D01*
G02Y1370882I0J-1503D01*
G01X1177113D01*
G02Y1373888I0J1503D01*
G37*
G36*
G01X1164873D02*
X1168273D01*
G02Y1370882I0J-1503D01*
G01X1164873D01*
G02Y1373888I0J1503D01*
G37*
G36*
G01Y1385800D02*
X1168273D01*
G02Y1382794I0J-1503D01*
G01X1164873D01*
G02Y1385800I0J1503D01*
G37*
G36*
G01X1152633D02*
X1156033D01*
G02Y1382794I0J-1503D01*
G01X1152633D01*
G02Y1385800I0J1503D01*
G37*
G36*
G01Y1373888D02*
X1156033D01*
G02Y1370882I0J-1503D01*
G01X1152633D01*
G02Y1373888I0J1503D01*
G37*
G36*
G01X1140393D02*
X1143793D01*
G02Y1370882I0J-1503D01*
G01X1140393D01*
G02Y1373888I0J1503D01*
G37*
G36*
G01Y1385800D02*
X1143793D01*
G02Y1382794I0J-1503D01*
G01X1140393D01*
G02Y1385800I0J1503D01*
G37*
G36*
G01X1128153D02*
X1131553D01*
G02Y1382794I0J-1503D01*
G01X1128153D01*
G02Y1385800I0J1503D01*
G37*
G36*
G01Y1373888D02*
X1131553D01*
G02Y1370882I0J-1503D01*
G01X1128153D01*
G02Y1373888I0J1503D01*
G37*
G36*
G01X1115913D02*
X1119313D01*
G02Y1370882I0J-1503D01*
G01X1115913D01*
G02Y1373888I0J1503D01*
G37*
G36*
G01Y1385800D02*
X1119313D01*
G02Y1382794I0J-1503D01*
G01X1115913D01*
G02Y1385800I0J1503D01*
G37*
G36*
G01X1103673D02*
X1107073D01*
G02Y1382794I0J-1503D01*
G01X1103673D01*
G02Y1385800I0J1503D01*
G37*
G36*
G01Y1373888D02*
X1107073D01*
G02Y1370882I0J-1503D01*
G01X1103673D01*
G02Y1373888I0J1503D01*
G37*
G36*
G01X1091433D02*
X1094833D01*
G02Y1370882I0J-1503D01*
G01X1091433D01*
G02Y1373888I0J1503D01*
G37*
G36*
G01Y1385800D02*
X1094833D01*
G02Y1382794I0J-1503D01*
G01X1091433D01*
G02Y1385800I0J1503D01*
G37*
G36*
G01X1079193D02*
X1082593D01*
G02Y1382794I0J-1503D01*
G01X1079193D01*
G02Y1385800I0J1503D01*
G37*
G36*
G01Y1373888D02*
X1082593D01*
G02Y1370882I0J-1503D01*
G01X1079193D01*
G02Y1373888I0J1503D01*
G37*
G36*
G01X1066953D02*
X1070353D01*
G02Y1370882I0J-1503D01*
G01X1066953D01*
G02Y1373888I0J1503D01*
G37*
G36*
G01Y1385800D02*
X1070353D01*
G02Y1382794I0J-1503D01*
G01X1066953D01*
G02Y1385800I0J1503D01*
G37*
G36*
G01X1054713D02*
X1058113D01*
G02Y1382794I0J-1503D01*
G01X1054713D01*
G02Y1385800I0J1503D01*
G37*
G36*
G01Y1373888D02*
X1058113D01*
G02Y1370882I0J-1503D01*
G01X1054713D01*
G02Y1373888I0J1503D01*
G37*
G36*
G01Y1361602D02*
X1058113D01*
G02Y1358596I0J-1503D01*
G01X1054713D01*
G02Y1361602I0J1503D01*
G37*
G36*
G01Y1349690D02*
X1058113D01*
G02Y1346684I0J-1503D01*
G01X1054713D01*
G02Y1349690I0J1503D01*
G37*
G36*
G01X1066953D02*
X1070353D01*
G02Y1346684I0J-1503D01*
G01X1066953D01*
G02Y1349690I0J1503D01*
G37*
G36*
G01Y1361602D02*
X1070353D01*
G02Y1358596I0J-1503D01*
G01X1066953D01*
G02Y1361602I0J1503D01*
G37*
G36*
G01X1079193D02*
X1082593D01*
G02Y1358596I0J-1503D01*
G01X1079193D01*
G02Y1361602I0J1503D01*
G37*
G36*
G01Y1349690D02*
X1082593D01*
G02Y1346684I0J-1503D01*
G01X1079193D01*
G02Y1349690I0J1503D01*
G37*
G36*
G01X1091433D02*
X1094833D01*
G02Y1346684I0J-1503D01*
G01X1091433D01*
G02Y1349690I0J1503D01*
G37*
G36*
G01Y1361602D02*
X1094833D01*
G02Y1358596I0J-1503D01*
G01X1091433D01*
G02Y1361602I0J1503D01*
G37*
G36*
G01X1103673D02*
X1107073D01*
G02Y1358596I0J-1503D01*
G01X1103673D01*
G02Y1361602I0J1503D01*
G37*
G36*
G01Y1349690D02*
X1107073D01*
G02Y1346684I0J-1503D01*
G01X1103673D01*
G02Y1349690I0J1503D01*
G37*
G36*
G01X1115913D02*
X1119313D01*
G02Y1346684I0J-1503D01*
G01X1115913D01*
G02Y1349690I0J1503D01*
G37*
G36*
G01Y1361602D02*
X1119313D01*
G02Y1358596I0J-1503D01*
G01X1115913D01*
G02Y1361602I0J1503D01*
G37*
G36*
G01X1128153D02*
X1131553D01*
G02Y1358596I0J-1503D01*
G01X1128153D01*
G02Y1361602I0J1503D01*
G37*
G36*
G01Y1349690D02*
X1131553D01*
G02Y1346684I0J-1503D01*
G01X1128153D01*
G02Y1349690I0J1503D01*
G37*
G36*
G01X1140393Y1361602D02*
X1143793D01*
G02Y1358596I0J-1503D01*
G01X1140393D01*
G02Y1361602I0J1503D01*
G37*
G36*
G01Y1349690D02*
X1143793D01*
G02Y1346684I0J-1503D01*
G01X1140393D01*
G02Y1349690I0J1503D01*
G37*
G36*
G01X1152633Y1361602D02*
X1156033D01*
G02Y1358596I0J-1503D01*
G01X1152633D01*
G02Y1361602I0J1503D01*
G37*
G36*
G01Y1349690D02*
X1156033D01*
G02Y1346684I0J-1503D01*
G01X1152633D01*
G02Y1349690I0J1503D01*
G37*
G36*
G01X1164873D02*
X1168273D01*
G02Y1346684I0J-1503D01*
G01X1164873D01*
G02Y1349690I0J1503D01*
G37*
G36*
G01Y1361602D02*
X1168273D01*
G02Y1358596I0J-1503D01*
G01X1164873D01*
G02Y1361602I0J1503D01*
G37*
G36*
G01X1177113D02*
X1180513D01*
G02Y1358596I0J-1503D01*
G01X1177113D01*
G02Y1361602I0J1503D01*
G37*
G36*
G01X1061120Y1169268D02*
X1057380D01*
G02Y1171872I0J1302D01*
G01X1061120D01*
G02Y1169268I0J-1302D01*
G37*
G36*
G01X955526Y1115605D02*
G02X956592Y1115161I0J-1502D01*
G03X956734Y1115102I142J141D01*
G01X957018D01*
G03X957160Y1115161I0J200D01*
G02X958226Y1115605I1066J-1058D01*
G02Y1112601I0J-1502D01*
G02X957160Y1113045I0J1502D01*
G03X957018Y1113104I-142J-141D01*
G01X956734D01*
G03X956592Y1113045I0J-200D01*
G02X955526Y1112601I-1066J1058D01*
G02X954499Y1113007I0J1502D01*
G01X954472Y1113033D01*
X954401Y1113061D01*
X954051D01*
X953980Y1113033D01*
X953953Y1113007D01*
G02X951899I-1027J1096D01*
G01X951872Y1113033D01*
X951801Y1113061D01*
X951451D01*
X951380Y1113033D01*
X951353Y1113007D01*
G02X950326Y1112601I-1027J1096D01*
G02Y1115605I0J1502D01*
G02X951353Y1115199I0J-1502D01*
G01X951380Y1115173D01*
X951451Y1115145D01*
X951801D01*
X951872Y1115173D01*
X951899Y1115199D01*
G02X953953I1027J-1096D01*
G01X953980Y1115173D01*
X954051Y1115145D01*
X954401D01*
X954472Y1115173D01*
X954499Y1115199D01*
G02X955526Y1115605I1027J-1096D01*
G37*
G36*
G01X940541Y1122138D02*
G02X941607Y1121694I0J-1502D01*
G03X941749Y1121635I142J141D01*
G01X942033D01*
G03X942175Y1121694I0J200D01*
G02X943241Y1122138I1066J-1058D01*
G02Y1119134I0J-1502D01*
G02X942175Y1119578I0J1502D01*
G03X942033Y1119637I-142J-141D01*
G01X941749D01*
G03X941607Y1119578I0J-200D01*
G02X940541Y1119134I-1066J1058D01*
G02X939514Y1119540I0J1502D01*
G01X939487Y1119566D01*
X939416Y1119594D01*
X939066D01*
X938995Y1119566D01*
X938968Y1119540D01*
G02X936914I-1027J1096D01*
G01X936887Y1119566D01*
X936816Y1119594D01*
X936466D01*
X936395Y1119566D01*
X936368Y1119540D01*
G02X935341Y1119134I-1027J1096D01*
G02Y1122138I0J1502D01*
G02X936368Y1121732I0J-1502D01*
G01X936395Y1121706D01*
X936466Y1121678D01*
X936816D01*
X936887Y1121706D01*
X936914Y1121732D01*
G02X938968I1027J-1096D01*
G01X938995Y1121706D01*
X939066Y1121678D01*
X939416D01*
X939487Y1121706D01*
X939514Y1121732D01*
G02X940541Y1122138I1027J-1096D01*
G37*
G36*
G01X955526Y1125305D02*
G02X956592Y1124861I0J-1502D01*
G03X956734Y1124802I142J141D01*
G01X957018D01*
G03X957160Y1124861I0J200D01*
G02X958226Y1125305I1066J-1058D01*
G02Y1122301I0J-1502D01*
G02X957160Y1122745I0J1502D01*
G03X957018Y1122804I-142J-141D01*
G01X956734D01*
G03X956592Y1122745I0J-200D01*
G02X955526Y1122301I-1066J1058D01*
G02X954499Y1122707I0J1502D01*
G01X954472Y1122733D01*
X954401Y1122761D01*
X954051D01*
X953980Y1122733D01*
X953953Y1122707D01*
G02X951899I-1027J1096D01*
G01X951872Y1122733D01*
X951801Y1122761D01*
X951451D01*
X951380Y1122733D01*
X951353Y1122707D01*
G02X950326Y1122301I-1027J1096D01*
G02Y1125305I0J1502D01*
G02X951353Y1124899I0J-1502D01*
G01X951380Y1124873D01*
X951451Y1124845D01*
X951801D01*
X951872Y1124873D01*
X951899Y1124899D01*
G02X953953I1027J-1096D01*
G01X953980Y1124873D01*
X954051Y1124845D01*
X954401D01*
X954472Y1124873D01*
X954499Y1124899D01*
G02X955526Y1125305I1027J-1096D01*
G37*
G36*
G01X940541Y1131838D02*
G02X941607Y1131394I0J-1502D01*
G03X941749Y1131335I142J141D01*
G01X942033D01*
G03X942175Y1131394I0J200D01*
G02X943241Y1131838I1066J-1058D01*
G02Y1128834I0J-1502D01*
G02X942175Y1129278I0J1502D01*
G03X942033Y1129337I-142J-141D01*
G01X941749D01*
G03X941607Y1129278I0J-200D01*
G02X940541Y1128834I-1066J1058D01*
G02X939514Y1129240I0J1502D01*
G01X939487Y1129266D01*
X939416Y1129294D01*
X939066D01*
X938995Y1129266D01*
X938968Y1129240D01*
G02X936914I-1027J1096D01*
G01X936887Y1129266D01*
X936816Y1129294D01*
X936466D01*
X936395Y1129266D01*
X936368Y1129240D01*
G02X935341Y1128834I-1027J1096D01*
G02Y1131838I0J1502D01*
G02X936368Y1131432I0J-1502D01*
G01X936395Y1131406D01*
X936466Y1131378D01*
X936816D01*
X936887Y1131406D01*
X936914Y1131432D01*
G02X938968I1027J-1096D01*
G01X938995Y1131406D01*
X939066Y1131378D01*
X939416D01*
X939487Y1131406D01*
X939514Y1131432D01*
G02X940541Y1131838I1027J-1096D01*
G37*
G36*
G01X956552Y1131368D02*
G02Y1134372I0J1502D01*
G02X957618Y1133928I0J-1502D01*
G03X957760Y1133869I142J141D01*
G01X958044D01*
G03X958186Y1133928I0J200D01*
G02X959252Y1134372I1066J-1058D01*
G02Y1131368I0J-1502D01*
G02X958186Y1131812I0J1502D01*
G03X958044Y1131871I-142J-141D01*
G01X957760D01*
G03X957618Y1131812I0J-200D01*
G02X956552Y1131368I-1066J1058D01*
G37*
G36*
G01X932641Y1137834D02*
G02Y1140838I0J1502D01*
G02X933707Y1140394I0J-1502D01*
G03X933849Y1140335I142J141D01*
G01X934133D01*
G03X934275Y1140394I0J200D01*
G02X935341Y1140838I1066J-1058D01*
G02Y1137834I0J-1502D01*
G02X934275Y1138278I0J1502D01*
G03X934133Y1138337I-142J-141D01*
G01X933849D01*
G03X933707Y1138278I0J-200D01*
G02X932641Y1137834I-1066J1058D01*
G37*
G36*
G01X959524Y1143667D02*
G02Y1146671I0J1502D01*
G02X960511Y1146301I0J-1501D01*
G01X960512D01*
Y1146300D01*
G03X960642Y1146252I130J152D01*
G01X960906D01*
G03X961036Y1146300I0J200D01*
G01X961037Y1146301D01*
G02X962024Y1146671I987J-1131D01*
G02Y1143667I0J-1502D01*
G02X961037Y1144037I0J1501D01*
G01X961036D01*
Y1144038D01*
G03X960906Y1144086I-130J-152D01*
G01X960642D01*
G03X960512Y1144038I0J-200D01*
G01X960511Y1144037D01*
G02X959524Y1143667I-987J1131D01*
G37*
G36*
G01X932000Y1146206D02*
G02Y1149210I0J1502D01*
G02X932987Y1148840I0J-1501D01*
G01X932988D01*
Y1148839D01*
G03X933118Y1148791I130J152D01*
G01X933382D01*
G03X933512Y1148839I0J200D01*
G01X933513Y1148840D01*
G02X934500Y1149210I987J-1131D01*
G02Y1146206I0J-1502D01*
G02X933513Y1146576I0J1501D01*
G01X933512D01*
Y1146577D01*
G03X933382Y1146625I-130J-152D01*
G01X933118D01*
G03X932988Y1146577I0J-200D01*
G01X932987Y1146576D01*
G02X932000Y1146206I-987J1131D01*
G37*
G36*
G01X1037551Y1180691D02*
G02X1040555I1502J0D01*
G02X1039994Y1179520I-1503J0D01*
G01X1039958Y1179491D01*
X1039919Y1179408D01*
X1039924Y1179046D01*
G03X1040003Y1178889I200J2D01*
G02X1040600Y1177691I-905J-1199D01*
G02X1037596I-1502J0D01*
G02X1038157Y1178862I1503J0D01*
G01X1038193Y1178891D01*
X1038232Y1178974D01*
X1038227Y1179336D01*
G03X1038148Y1179493I-200J-2D01*
G02X1037551Y1180691I905J1199D01*
G37*
G36*
G01X954352Y1264190D02*
X954353Y1264189D01*
G03X954483Y1264141I130J152D01*
G01X954747D01*
G03X954877Y1264189I0J200D01*
G01X954878Y1264190D01*
G02X955865Y1264560I987J-1131D01*
G02X957367Y1263058I0J-1502D01*
G02X956997Y1262071I-1501J0D01*
G01Y1262070D01*
X956996D01*
G03X956948Y1261940I152J-130D01*
G01Y1261676D01*
G03X956996Y1261546I200J0D01*
G01X956997Y1261545D01*
G02X957367Y1260558I-1131J-987D01*
G02X955865Y1259056I-1502J0D01*
G02X954878Y1259426I0J1501D01*
G01X954877D01*
Y1259427D01*
G03X954747Y1259475I-130J-152D01*
G01X954483D01*
G03X954353Y1259427I0J-200D01*
G01X954352Y1259426D01*
G02X952378I-987J1131D01*
G01X952377D01*
Y1259427D01*
G03X952247Y1259475I-130J-152D01*
G01X951983D01*
G03X951853Y1259427I0J-200D01*
G01X951852Y1259426D01*
G02X950865Y1259056I-987J1131D01*
G02X949363Y1260558I0J1502D01*
G02X949733Y1261545I1501J0D01*
G01Y1261546D01*
X949734D01*
G03X949782Y1261676I-152J130D01*
G01Y1261940D01*
G03X949734Y1262070I-200J0D01*
G01X949733Y1262071D01*
G02X949363Y1263058I1131J987D01*
G02X950865Y1264560I1502J0D01*
G02X951852Y1264190I0J-1501D01*
G01X951853D01*
Y1264189D01*
G03X951983Y1264141I130J152D01*
G01X952247D01*
G03X952377Y1264189I0J200D01*
G01X952378Y1264190D01*
G02X954352I987J-1131D01*
G37*
G36*
G01X1050002Y1291781D02*
G02Y1294785I0J1502D01*
G02X1051062Y1294347I0J-1502D01*
G01X1051063Y1294346D01*
G03X1051201Y1294289I140J143D01*
G01X1051520Y1294285D01*
X1051592Y1294314D01*
X1051621Y1294342D01*
G02X1052660Y1294759I1039J-1086D01*
G02Y1291755I0J-1502D01*
G02X1051600Y1292193I0J1502D01*
G01X1051599Y1292194D01*
G03X1051461Y1292251I-140J-143D01*
G01X1051142Y1292255D01*
X1051070Y1292226D01*
X1051041Y1292198D01*
G02X1050002Y1291781I-1039J1086D01*
G37*
G36*
G01X991866Y1328000D02*
X992160D01*
G03X992307Y1328065I-1J200D01*
G02X994519I1106J-1017D01*
G03X994666Y1328000I148J135D01*
G01X994960D01*
G03X995107Y1328065I-1J200D01*
G02X996213Y1328550I1106J-1019D01*
G02X997715Y1327048I0J-1502D01*
G02X997230Y1325942I-1504J0D01*
G03X997165Y1325795I135J-148D01*
G01Y1325501D01*
G03X997230Y1325354I200J1D01*
G02X997715Y1324248I-1019J-1106D01*
G02X996213Y1322746I-1502J0D01*
G02X995107Y1323231I0J1504D01*
G03X994960Y1323296I-148J-135D01*
G01X994666D01*
G03X994519Y1323231I1J-200D01*
G02X992307I-1106J1017D01*
G03X992160Y1323296I-148J-135D01*
G01X991866D01*
G03X991719Y1323231I1J-200D01*
G02X990613Y1322746I-1106J1019D01*
G02X989111Y1324248I0J1502D01*
G02X989596Y1325354I1504J0D01*
G03X989661Y1325501I-135J148D01*
G01Y1325795D01*
G03X989596Y1325942I-200J-1D01*
G02X989111Y1327048I1019J1106D01*
G02X990613Y1328550I1502J0D01*
G02X991719Y1328065I0J-1504D01*
G03X991866Y1328000I148J135D01*
G37*
G36*
G01X1130238Y1464825D02*
Y1465951D01*
G02X1130440Y1466154I202J1D01*
G01X1133260D01*
G02X1133462Y1465951I-1J-203D01*
G01Y1464825D01*
G03X1133490Y1464722I200J-1D01*
G02X1133762Y1463741I-1640J-983D01*
G02X1133490Y1462760I-1912J2D01*
G03X1133462Y1462657I172J-102D01*
G01Y1459706D01*
G03X1133490Y1459603I200J-1D01*
G02X1133762Y1458622I-1640J-983D01*
G02X1133490Y1457641I-1912J2D01*
G03X1133462Y1457538I172J-102D01*
G01Y1456413D01*
G02X1133260Y1456210I-202J-1D01*
G01X1130440D01*
G02X1130238Y1456413I1J203D01*
G01Y1457538D01*
G03X1130210Y1457641I-200J1D01*
G02X1129938Y1458622I1640J983D01*
G02X1130210Y1459603I1912J-2D01*
G03X1130238Y1459706I-172J102D01*
G01Y1462657D01*
G03X1130210Y1462760I-200J1D01*
G02X1129938Y1463741I1640J983D01*
G02X1130210Y1464722I1912J-2D01*
G03X1130238Y1464825I-172J102D01*
G37*
G36*
G01X1147560D02*
Y1465951D01*
G02X1147763Y1466154I203J0D01*
G01X1150583D01*
G02X1150786Y1465951I0J-203D01*
G01Y1464825D01*
G03X1150814Y1464722I200J-1D01*
G02Y1462760I-1642J-981D01*
G03X1150786Y1462657I172J-102D01*
G01Y1459706D01*
G03X1150814Y1459603I200J-1D01*
G02Y1457641I-1642J-981D01*
G03X1150786Y1457538I172J-102D01*
G01Y1456413D01*
G02X1150583Y1456210I-203J0D01*
G01X1147763D01*
G02X1147560Y1456413I0J203D01*
G01Y1457538D01*
G03X1147532Y1457641I-200J1D01*
G02Y1459603I1642J981D01*
G03X1147560Y1459706I-172J102D01*
G01Y1462657D01*
G03X1147532Y1462760I-200J1D01*
G02Y1464722I1642J981D01*
G03X1147560Y1464825I-172J102D01*
G37*
G36*
G01X1164884D02*
Y1465951D01*
G02X1165086Y1466154I202J1D01*
G01X1167906D01*
G02X1168108Y1465951I-1J-203D01*
G01Y1464825D01*
G03X1168136Y1464722I200J-1D01*
G02X1168408Y1463741I-1640J-983D01*
G02X1168136Y1462760I-1912J2D01*
G03X1168108Y1462657I172J-102D01*
G01Y1459706D01*
G03X1168136Y1459603I200J-1D01*
G02X1168408Y1458622I-1640J-983D01*
G02X1168136Y1457641I-1912J2D01*
G03X1168108Y1457538I172J-102D01*
G01Y1456413D01*
G02X1167906Y1456210I-202J-1D01*
G01X1165086D01*
G02X1164884Y1456413I1J203D01*
G01Y1457538D01*
G03X1164856Y1457641I-200J1D01*
G02X1164584Y1458622I1640J983D01*
G02X1164856Y1459603I1912J-2D01*
G03X1164884Y1459706I-172J102D01*
G01Y1462657D01*
G03X1164856Y1462760I-200J1D01*
G02X1164584Y1463741I1640J983D01*
G02X1164856Y1464722I1912J-2D01*
G03X1164884Y1464825I-172J102D01*
G37*
G36*
G01X1182206D02*
Y1465951D01*
G02X1182408Y1466154I202J1D01*
G01X1185228D01*
G02X1185430Y1465951I-1J-203D01*
G01Y1464825D01*
G03X1185458Y1464722I200J-1D01*
G02X1185730Y1463741I-1640J-983D01*
G02X1185458Y1462760I-1912J2D01*
G03X1185430Y1462657I172J-102D01*
G01Y1459706D01*
G03X1185458Y1459603I200J-1D01*
G02X1185730Y1458622I-1640J-983D01*
G02X1185458Y1457641I-1912J2D01*
G03X1185430Y1457538I172J-102D01*
G01Y1456413D01*
G02X1185228Y1456210I-202J-1D01*
G01X1182408D01*
G02X1182206Y1456413I1J203D01*
G01Y1457538D01*
G03X1182178Y1457641I-200J1D01*
G02X1181906Y1458622I1640J983D01*
G02X1182178Y1459603I1912J-2D01*
G03X1182206Y1459706I-172J102D01*
G01Y1462657D01*
G03X1182178Y1462760I-200J1D01*
G02X1181906Y1463741I1640J983D01*
G02X1182178Y1464722I1912J-2D01*
G03X1182206Y1464825I-172J102D01*
G37*
G36*
G01X1476694D02*
Y1465951D01*
G02X1476897Y1466154I203J0D01*
G01X1479717D01*
G02X1479920Y1465951I0J-203D01*
G01Y1464825D01*
G03X1479948Y1464722I200J-1D01*
G02Y1462760I-1642J-981D01*
G03X1479920Y1462657I172J-102D01*
G01Y1459706D01*
G03X1479948Y1459603I200J-1D01*
G02Y1457641I-1642J-981D01*
G03X1479920Y1457538I172J-102D01*
G01Y1456413D01*
G02X1479717Y1456210I-203J0D01*
G01X1476897D01*
G02X1476694Y1456413I0J203D01*
G01Y1457538D01*
G03X1476666Y1457641I-200J1D01*
G02Y1459603I1642J981D01*
G03X1476694Y1459706I-172J102D01*
G01Y1462657D01*
G03X1476666Y1462760I-200J1D01*
G02Y1464722I1642J981D01*
G03X1476694Y1464825I-172J102D01*
G37*
G36*
G01X1494018D02*
Y1465951D01*
G02X1494220Y1466154I202J1D01*
G01X1497040D01*
G02X1497242Y1465951I-1J-203D01*
G01Y1464825D01*
G03X1497270Y1464722I200J-1D01*
G02X1497542Y1463741I-1640J-983D01*
G02X1497270Y1462760I-1912J2D01*
G03X1497242Y1462657I172J-102D01*
G01Y1459706D01*
G03X1497270Y1459603I200J-1D01*
G02X1497542Y1458622I-1640J-983D01*
G02X1497270Y1457641I-1912J2D01*
G03X1497242Y1457538I172J-102D01*
G01Y1456413D01*
G02X1497040Y1456210I-202J-1D01*
G01X1494220D01*
G02X1494018Y1456413I1J203D01*
G01Y1457538D01*
G03X1493990Y1457641I-200J1D01*
G02X1493718Y1458622I1640J983D01*
G02X1493990Y1459603I1912J-2D01*
G03X1494018Y1459706I-172J102D01*
G01Y1462657D01*
G03X1493990Y1462760I-200J1D01*
G02X1493718Y1463741I1640J983D01*
G02X1493990Y1464722I1912J-2D01*
G03X1494018Y1464825I-172J102D01*
G37*
G36*
G01X1511340D02*
Y1465951D01*
G02X1511543Y1466154I203J0D01*
G01X1514363D01*
G02X1514566Y1465951I0J-203D01*
G01Y1464825D01*
G03X1514594Y1464722I200J-1D01*
G02Y1462760I-1642J-981D01*
G03X1514566Y1462657I172J-102D01*
G01Y1459706D01*
G03X1514594Y1459603I200J-1D01*
G02Y1457641I-1642J-981D01*
G03X1514566Y1457538I172J-102D01*
G01Y1456413D01*
G02X1514363Y1456210I-203J0D01*
G01X1511543D01*
G02X1511340Y1456413I0J203D01*
G01Y1457538D01*
G03X1511312Y1457641I-200J1D01*
G02Y1459603I1642J981D01*
G03X1511340Y1459706I-172J102D01*
G01Y1462657D01*
G03X1511312Y1462760I-200J1D01*
G02Y1464722I1642J981D01*
G03X1511340Y1464825I-172J102D01*
G37*
G36*
G01X1528662D02*
Y1465951D01*
G02X1528865Y1466154I203J0D01*
G01X1531685D01*
G02X1531888Y1465951I0J-203D01*
G01Y1464825D01*
G03X1531916Y1464722I200J-1D01*
G02Y1462760I-1642J-981D01*
G03X1531888Y1462657I172J-102D01*
G01Y1459706D01*
G03X1531916Y1459603I200J-1D01*
G02Y1457641I-1642J-981D01*
G03X1531888Y1457538I172J-102D01*
G01Y1456413D01*
G02X1531685Y1456210I-203J0D01*
G01X1528865D01*
G02X1528662Y1456413I0J203D01*
G01Y1457538D01*
G03X1528634Y1457641I-200J1D01*
G02Y1459603I1642J981D01*
G03X1528662Y1459706I-172J102D01*
G01Y1462657D01*
G03X1528634Y1462760I-200J1D01*
G02Y1464722I1642J981D01*
G03X1528662Y1464825I-172J102D01*
G37*
G36*
G01X1138898Y1469155D02*
Y1470281D01*
G02X1139101Y1470484I203J0D01*
G01X1141921D01*
G02X1142124Y1470281I0J-203D01*
G01Y1469155D01*
G03X1142152Y1469052I200J-1D01*
G02Y1467090I-1642J-981D01*
G03X1142124Y1466987I172J-102D01*
G01Y1464037D01*
G03X1142152Y1463934I200J-1D01*
G02Y1461972I-1642J-981D01*
G03X1142124Y1461869I172J-102D01*
G01Y1460743D01*
G02X1141921Y1460540I-203J0D01*
G01X1139101D01*
G02X1138898Y1460743I0J203D01*
G01Y1461869D01*
G03X1138870Y1461972I-200J1D01*
G02Y1463934I1642J981D01*
G03X1138898Y1464037I-172J102D01*
G01Y1466987D01*
G03X1138870Y1467090I-200J1D01*
G02Y1469052I1642J981D01*
G03X1138898Y1469155I-172J102D01*
G37*
G36*
G01X1156222D02*
Y1470281D01*
G02X1156424Y1470484I202J1D01*
G01X1159244D01*
G02X1159446Y1470281I-1J-203D01*
G01Y1469155D01*
G03X1159474Y1469052I200J-1D01*
G02X1159746Y1468071I-1640J-983D01*
G02X1159474Y1467090I-1912J2D01*
G03X1159446Y1466987I172J-102D01*
G01Y1464037D01*
G03X1159474Y1463934I200J-1D01*
G02X1159746Y1462953I-1640J-983D01*
G02X1159474Y1461972I-1912J2D01*
G03X1159446Y1461869I172J-102D01*
G01Y1460743D01*
G02X1159244Y1460540I-202J-1D01*
G01X1156424D01*
G02X1156222Y1460743I1J203D01*
G01Y1461869D01*
G03X1156194Y1461972I-200J1D01*
G02X1155922Y1462953I1640J983D01*
G02X1156194Y1463934I1912J-2D01*
G03X1156222Y1464037I-172J102D01*
G01Y1466987D01*
G03X1156194Y1467090I-200J1D01*
G02X1155922Y1468071I1640J983D01*
G02X1156194Y1469052I1912J-2D01*
G03X1156222Y1469155I-172J102D01*
G37*
G36*
G01X1173544D02*
Y1470281D01*
G02X1173747Y1470484I203J0D01*
G01X1176567D01*
G02X1176770Y1470281I0J-203D01*
G01Y1469155D01*
G03X1176798Y1469052I200J-1D01*
G02Y1467090I-1642J-981D01*
G03X1176770Y1466987I172J-102D01*
G01Y1464037D01*
G03X1176798Y1463934I200J-1D01*
G02Y1461972I-1642J-981D01*
G03X1176770Y1461869I172J-102D01*
G01Y1460743D01*
G02X1176567Y1460540I-203J0D01*
G01X1173747D01*
G02X1173544Y1460743I0J203D01*
G01Y1461869D01*
G03X1173516Y1461972I-200J1D01*
G02Y1463934I1642J981D01*
G03X1173544Y1464037I-172J102D01*
G01Y1466987D01*
G03X1173516Y1467090I-200J1D01*
G02Y1469052I1642J981D01*
G03X1173544Y1469155I-172J102D01*
G37*
G36*
G01X1190868D02*
Y1470281D01*
G02X1191070Y1470484I202J1D01*
G01X1193890D01*
G02X1194092Y1470281I-1J-203D01*
G01Y1469155D01*
G03X1194120Y1469052I200J-1D01*
G02X1194392Y1468071I-1640J-983D01*
G02X1194120Y1467090I-1912J2D01*
G03X1194092Y1466987I172J-102D01*
G01Y1464037D01*
G03X1194120Y1463934I200J-1D01*
G02X1194392Y1462953I-1640J-983D01*
G02X1194120Y1461972I-1912J2D01*
G03X1194092Y1461869I172J-102D01*
G01Y1460743D01*
G02X1193890Y1460540I-202J-1D01*
G01X1191070D01*
G02X1190868Y1460743I1J203D01*
G01Y1461869D01*
G03X1190840Y1461972I-200J1D01*
G02X1190568Y1462953I1640J983D01*
G02X1190840Y1463934I1912J-2D01*
G03X1190868Y1464037I-172J102D01*
G01Y1466987D01*
G03X1190840Y1467090I-200J1D01*
G02X1190568Y1468071I1640J983D01*
G02X1190840Y1469052I1912J-2D01*
G03X1190868Y1469155I-172J102D01*
G37*
G36*
G01X1485356D02*
Y1470281D01*
G02X1485558Y1470484I202J1D01*
G01X1488378D01*
G02X1488580Y1470281I-1J-203D01*
G01Y1469155D01*
G03X1488608Y1469052I200J-1D01*
G02X1488880Y1468071I-1640J-983D01*
G02X1488608Y1467090I-1912J2D01*
G03X1488580Y1466987I172J-102D01*
G01Y1464037D01*
G03X1488608Y1463934I200J-1D01*
G02X1488880Y1462953I-1640J-983D01*
G02X1488608Y1461972I-1912J2D01*
G03X1488580Y1461869I172J-102D01*
G01Y1460743D01*
G02X1488378Y1460540I-202J-1D01*
G01X1485558D01*
G02X1485356Y1460743I1J203D01*
G01Y1461869D01*
G03X1485328Y1461972I-200J1D01*
G02X1485056Y1462953I1640J983D01*
G02X1485328Y1463934I1912J-2D01*
G03X1485356Y1464037I-172J102D01*
G01Y1466987D01*
G03X1485328Y1467090I-200J1D01*
G02X1485056Y1468071I1640J983D01*
G02X1485328Y1469052I1912J-2D01*
G03X1485356Y1469155I-172J102D01*
G37*
G36*
G01X1502678D02*
Y1470281D01*
G02X1502881Y1470484I203J0D01*
G01X1505701D01*
G02X1505904Y1470281I0J-203D01*
G01Y1469155D01*
G03X1505932Y1469052I200J-1D01*
G02Y1467090I-1642J-981D01*
G03X1505904Y1466987I172J-102D01*
G01Y1464037D01*
G03X1505932Y1463934I200J-1D01*
G02Y1461972I-1642J-981D01*
G03X1505904Y1461869I172J-102D01*
G01Y1460743D01*
G02X1505701Y1460540I-203J0D01*
G01X1502881D01*
G02X1502678Y1460743I0J203D01*
G01Y1461869D01*
G03X1502650Y1461972I-200J1D01*
G02Y1463934I1642J981D01*
G03X1502678Y1464037I-172J102D01*
G01Y1466987D01*
G03X1502650Y1467090I-200J1D01*
G02Y1469052I1642J981D01*
G03X1502678Y1469155I-172J102D01*
G37*
G36*
G01X1520002D02*
Y1470281D01*
G02X1520204Y1470484I202J1D01*
G01X1523024D01*
G02X1523226Y1470281I-1J-203D01*
G01Y1469155D01*
G03X1523254Y1469052I200J-1D01*
G02X1523526Y1468071I-1640J-983D01*
G02X1523254Y1467090I-1912J2D01*
G03X1523226Y1466987I172J-102D01*
G01Y1464037D01*
G03X1523254Y1463934I200J-1D01*
G02X1523526Y1462953I-1640J-983D01*
G02X1523254Y1461972I-1912J2D01*
G03X1523226Y1461869I172J-102D01*
G01Y1460743D01*
G02X1523024Y1460540I-202J-1D01*
G01X1520204D01*
G02X1520002Y1460743I1J203D01*
G01Y1461869D01*
G03X1519974Y1461972I-200J1D01*
G02X1519702Y1462953I1640J983D01*
G02X1519974Y1463934I1912J-2D01*
G03X1520002Y1464037I-172J102D01*
G01Y1466987D01*
G03X1519974Y1467090I-200J1D01*
G02X1519702Y1468071I1640J983D01*
G02X1519974Y1469052I1912J-2D01*
G03X1520002Y1469155I-172J102D01*
G37*
G36*
G01X1537324D02*
Y1470281D01*
G02X1537527Y1470484I203J0D01*
G01X1540347D01*
G02X1540550Y1470281I0J-203D01*
G01Y1469155D01*
G03X1540578Y1469052I200J-1D01*
G02Y1467090I-1642J-981D01*
G03X1540550Y1466987I172J-102D01*
G01Y1464037D01*
G03X1540578Y1463934I200J-1D01*
G02Y1461972I-1642J-981D01*
G03X1540550Y1461869I172J-102D01*
G01Y1460743D01*
G02X1540347Y1460540I-203J0D01*
G01X1537527D01*
G02X1537324Y1460743I0J203D01*
G01Y1461869D01*
G03X1537296Y1461972I-200J1D01*
G02Y1463934I1642J981D01*
G03X1537324Y1464037I-172J102D01*
G01Y1466987D01*
G03X1537296Y1467090I-200J1D01*
G02Y1469052I1642J981D01*
G03X1537324Y1469155I-172J102D01*
G37*
G36*
G01X1130238Y1480179D02*
Y1481305D01*
G02X1130440Y1481508I202J1D01*
G01X1133260D01*
G02X1133462Y1481305I-1J-203D01*
G01Y1480179D01*
G03X1133490Y1480076I200J-1D01*
G02X1133762Y1479095I-1640J-983D01*
G02X1133490Y1478114I-1912J2D01*
G03X1133462Y1478011I172J-102D01*
G01Y1475061D01*
G03X1133490Y1474958I200J-1D01*
G02X1133762Y1473977I-1640J-983D01*
G02X1133490Y1472996I-1912J2D01*
G03X1133462Y1472893I172J-102D01*
G01Y1471767D01*
G02X1133260Y1471564I-202J-1D01*
G01X1130440D01*
G02X1130238Y1471767I1J203D01*
G01Y1472893D01*
G03X1130210Y1472996I-200J1D01*
G02X1129938Y1473977I1640J983D01*
G02X1130210Y1474958I1912J-2D01*
G03X1130238Y1475061I-172J102D01*
G01Y1478011D01*
G03X1130210Y1478114I-200J1D01*
G02X1129938Y1479095I1640J983D01*
G02X1130210Y1480076I1912J-2D01*
G03X1130238Y1480179I-172J102D01*
G37*
G36*
G01X1147560D02*
Y1481305D01*
G02X1147763Y1481508I203J0D01*
G01X1150583D01*
G02X1150786Y1481305I0J-203D01*
G01Y1480179D01*
G03X1150814Y1480076I200J-1D01*
G02Y1478114I-1642J-981D01*
G03X1150786Y1478011I172J-102D01*
G01Y1475061D01*
G03X1150814Y1474958I200J-1D01*
G02Y1472996I-1642J-981D01*
G03X1150786Y1472893I172J-102D01*
G01Y1471767D01*
G02X1150583Y1471564I-203J0D01*
G01X1147763D01*
G02X1147560Y1471767I0J203D01*
G01Y1472893D01*
G03X1147532Y1472996I-200J1D01*
G02Y1474958I1642J981D01*
G03X1147560Y1475061I-172J102D01*
G01Y1478011D01*
G03X1147532Y1478114I-200J1D01*
G02Y1480076I1642J981D01*
G03X1147560Y1480179I-172J102D01*
G37*
G36*
G01X1164884D02*
Y1481305D01*
G02X1165086Y1481508I202J1D01*
G01X1167906D01*
G02X1168108Y1481305I-1J-203D01*
G01Y1480179D01*
G03X1168136Y1480076I200J-1D01*
G02X1168408Y1479095I-1640J-983D01*
G02X1168136Y1478114I-1912J2D01*
G03X1168108Y1478011I172J-102D01*
G01Y1475061D01*
G03X1168136Y1474958I200J-1D01*
G02X1168408Y1473977I-1640J-983D01*
G02X1168136Y1472996I-1912J2D01*
G03X1168108Y1472893I172J-102D01*
G01Y1471767D01*
G02X1167906Y1471564I-202J-1D01*
G01X1165086D01*
G02X1164884Y1471767I1J203D01*
G01Y1472893D01*
G03X1164856Y1472996I-200J1D01*
G02X1164584Y1473977I1640J983D01*
G02X1164856Y1474958I1912J-2D01*
G03X1164884Y1475061I-172J102D01*
G01Y1478011D01*
G03X1164856Y1478114I-200J1D01*
G02X1164584Y1479095I1640J983D01*
G02X1164856Y1480076I1912J-2D01*
G03X1164884Y1480179I-172J102D01*
G37*
G36*
G01X1182206D02*
Y1481305D01*
G02X1182408Y1481508I202J1D01*
G01X1185228D01*
G02X1185430Y1481305I-1J-203D01*
G01Y1480179D01*
G03X1185458Y1480076I200J-1D01*
G02X1185730Y1479095I-1640J-983D01*
G02X1185458Y1478114I-1912J2D01*
G03X1185430Y1478011I172J-102D01*
G01Y1475061D01*
G03X1185458Y1474958I200J-1D01*
G02X1185730Y1473977I-1640J-983D01*
G02X1185458Y1472996I-1912J2D01*
G03X1185430Y1472893I172J-102D01*
G01Y1471767D01*
G02X1185228Y1471564I-202J-1D01*
G01X1182408D01*
G02X1182206Y1471767I1J203D01*
G01Y1472893D01*
G03X1182178Y1472996I-200J1D01*
G02X1181906Y1473977I1640J983D01*
G02X1182178Y1474958I1912J-2D01*
G03X1182206Y1475061I-172J102D01*
G01Y1478011D01*
G03X1182178Y1478114I-200J1D01*
G02X1181906Y1479095I1640J983D01*
G02X1182178Y1480076I1912J-2D01*
G03X1182206Y1480179I-172J102D01*
G37*
G36*
G01X1476694D02*
Y1481305D01*
G02X1476897Y1481508I203J0D01*
G01X1479717D01*
G02X1479920Y1481305I0J-203D01*
G01Y1480179D01*
G03X1479948Y1480076I200J-1D01*
G02Y1478114I-1642J-981D01*
G03X1479920Y1478011I172J-102D01*
G01Y1475061D01*
G03X1479948Y1474958I200J-1D01*
G02Y1472996I-1642J-981D01*
G03X1479920Y1472893I172J-102D01*
G01Y1471767D01*
G02X1479717Y1471564I-203J0D01*
G01X1476897D01*
G02X1476694Y1471767I0J203D01*
G01Y1472893D01*
G03X1476666Y1472996I-200J1D01*
G02Y1474958I1642J981D01*
G03X1476694Y1475061I-172J102D01*
G01Y1478011D01*
G03X1476666Y1478114I-200J1D01*
G02Y1480076I1642J981D01*
G03X1476694Y1480179I-172J102D01*
G37*
G36*
G01X1494018D02*
Y1481305D01*
G02X1494220Y1481508I202J1D01*
G01X1497040D01*
G02X1497242Y1481305I-1J-203D01*
G01Y1480179D01*
G03X1497270Y1480076I200J-1D01*
G02X1497542Y1479095I-1640J-983D01*
G02X1497270Y1478114I-1912J2D01*
G03X1497242Y1478011I172J-102D01*
G01Y1475061D01*
G03X1497270Y1474958I200J-1D01*
G02X1497542Y1473977I-1640J-983D01*
G02X1497270Y1472996I-1912J2D01*
G03X1497242Y1472893I172J-102D01*
G01Y1471767D01*
G02X1497040Y1471564I-202J-1D01*
G01X1494220D01*
G02X1494018Y1471767I1J203D01*
G01Y1472893D01*
G03X1493990Y1472996I-200J1D01*
G02X1493718Y1473977I1640J983D01*
G02X1493990Y1474958I1912J-2D01*
G03X1494018Y1475061I-172J102D01*
G01Y1478011D01*
G03X1493990Y1478114I-200J1D01*
G02X1493718Y1479095I1640J983D01*
G02X1493990Y1480076I1912J-2D01*
G03X1494018Y1480179I-172J102D01*
G37*
G36*
G01X1511340D02*
Y1481305D01*
G02X1511543Y1481508I203J0D01*
G01X1514363D01*
G02X1514566Y1481305I0J-203D01*
G01Y1480179D01*
G03X1514594Y1480076I200J-1D01*
G02Y1478114I-1642J-981D01*
G03X1514566Y1478011I172J-102D01*
G01Y1475061D01*
G03X1514594Y1474958I200J-1D01*
G02Y1472996I-1642J-981D01*
G03X1514566Y1472893I172J-102D01*
G01Y1471767D01*
G02X1514363Y1471564I-203J0D01*
G01X1511543D01*
G02X1511340Y1471767I0J203D01*
G01Y1472893D01*
G03X1511312Y1472996I-200J1D01*
G02Y1474958I1642J981D01*
G03X1511340Y1475061I-172J102D01*
G01Y1478011D01*
G03X1511312Y1478114I-200J1D01*
G02Y1480076I1642J981D01*
G03X1511340Y1480179I-172J102D01*
G37*
G36*
G01X1528662D02*
Y1481305D01*
G02X1528865Y1481508I203J0D01*
G01X1531685D01*
G02X1531888Y1481305I0J-203D01*
G01Y1480179D01*
G03X1531916Y1480076I200J-1D01*
G02Y1478114I-1642J-981D01*
G03X1531888Y1478011I172J-102D01*
G01Y1475061D01*
G03X1531916Y1474958I200J-1D01*
G02Y1472996I-1642J-981D01*
G03X1531888Y1472893I172J-102D01*
G01Y1471767D01*
G02X1531685Y1471564I-203J0D01*
G01X1528865D01*
G02X1528662Y1471767I0J203D01*
G01Y1472893D01*
G03X1528634Y1472996I-200J1D01*
G02Y1474958I1642J981D01*
G03X1528662Y1475061I-172J102D01*
G01Y1478011D01*
G03X1528634Y1478114I-200J1D01*
G02Y1480076I1642J981D01*
G03X1528662Y1480179I-172J102D01*
G37*
G36*
G01X1138898Y1484510D02*
Y1485635D01*
G02X1139101Y1485838I203J0D01*
G01X1141921D01*
G02X1142124Y1485635I0J-203D01*
G01Y1484510D01*
G03X1142152Y1484407I200J-1D01*
G02Y1482445I-1642J-981D01*
G03X1142124Y1482342I172J-102D01*
G01Y1479392D01*
G03X1142152Y1479289I200J-1D01*
G02Y1477327I-1642J-981D01*
G03X1142124Y1477224I172J-102D01*
G01Y1476097D01*
G02X1141921Y1475894I-203J0D01*
G01X1139101D01*
G02X1138898Y1476097I0J203D01*
G01Y1477224D01*
G03X1138870Y1477327I-200J1D01*
G02Y1479289I1642J981D01*
G03X1138898Y1479392I-172J102D01*
G01Y1482342D01*
G03X1138870Y1482445I-200J1D01*
G02Y1484407I1642J981D01*
G03X1138898Y1484510I-172J102D01*
G37*
G36*
G01X1156222D02*
Y1485635D01*
G02X1156424Y1485838I202J1D01*
G01X1159244D01*
G02X1159446Y1485635I-1J-203D01*
G01Y1484510D01*
G03X1159474Y1484407I200J-1D01*
G02X1159746Y1483426I-1640J-983D01*
G02X1159474Y1482445I-1912J2D01*
G03X1159446Y1482342I172J-102D01*
G01Y1479392D01*
G03X1159474Y1479289I200J-1D01*
G02X1159746Y1478308I-1640J-983D01*
G02X1159474Y1477327I-1912J2D01*
G03X1159446Y1477224I172J-102D01*
G01Y1476097D01*
G02X1159244Y1475894I-202J-1D01*
G01X1156424D01*
G02X1156222Y1476097I1J203D01*
G01Y1477224D01*
G03X1156194Y1477327I-200J1D01*
G02X1155922Y1478308I1640J983D01*
G02X1156194Y1479289I1912J-2D01*
G03X1156222Y1479392I-172J102D01*
G01Y1482342D01*
G03X1156194Y1482445I-200J1D01*
G02X1155922Y1483426I1640J983D01*
G02X1156194Y1484407I1912J-2D01*
G03X1156222Y1484510I-172J102D01*
G37*
G36*
G01X1173544D02*
Y1485635D01*
G02X1173747Y1485838I203J0D01*
G01X1176567D01*
G02X1176770Y1485635I0J-203D01*
G01Y1484510D01*
G03X1176798Y1484407I200J-1D01*
G02Y1482445I-1642J-981D01*
G03X1176770Y1482342I172J-102D01*
G01Y1479392D01*
G03X1176798Y1479289I200J-1D01*
G02Y1477327I-1642J-981D01*
G03X1176770Y1477224I172J-102D01*
G01Y1476097D01*
G02X1176567Y1475894I-203J0D01*
G01X1173747D01*
G02X1173544Y1476097I0J203D01*
G01Y1477224D01*
G03X1173516Y1477327I-200J1D01*
G02Y1479289I1642J981D01*
G03X1173544Y1479392I-172J102D01*
G01Y1482342D01*
G03X1173516Y1482445I-200J1D01*
G02Y1484407I1642J981D01*
G03X1173544Y1484510I-172J102D01*
G37*
G36*
G01X1190868D02*
Y1485635D01*
G02X1191070Y1485838I202J1D01*
G01X1193890D01*
G02X1194092Y1485635I-1J-203D01*
G01Y1484510D01*
G03X1194120Y1484407I200J-1D01*
G02X1194392Y1483426I-1640J-983D01*
G02X1194120Y1482445I-1912J2D01*
G03X1194092Y1482342I172J-102D01*
G01Y1479392D01*
G03X1194120Y1479289I200J-1D01*
G02X1194392Y1478308I-1640J-983D01*
G02X1194120Y1477327I-1912J2D01*
G03X1194092Y1477224I172J-102D01*
G01Y1476097D01*
G02X1193890Y1475894I-202J-1D01*
G01X1191070D01*
G02X1190868Y1476097I1J203D01*
G01Y1477224D01*
G03X1190840Y1477327I-200J1D01*
G02X1190568Y1478308I1640J983D01*
G02X1190840Y1479289I1912J-2D01*
G03X1190868Y1479392I-172J102D01*
G01Y1482342D01*
G03X1190840Y1482445I-200J1D01*
G02X1190568Y1483426I1640J983D01*
G02X1190840Y1484407I1912J-2D01*
G03X1190868Y1484510I-172J102D01*
G37*
G36*
G01X1485356D02*
Y1485635D01*
G02X1485558Y1485838I202J1D01*
G01X1488378D01*
G02X1488580Y1485635I-1J-203D01*
G01Y1484510D01*
G03X1488608Y1484407I200J-1D01*
G02X1488880Y1483426I-1640J-983D01*
G02X1488608Y1482445I-1912J2D01*
G03X1488580Y1482342I172J-102D01*
G01Y1479392D01*
G03X1488608Y1479289I200J-1D01*
G02X1488880Y1478308I-1640J-983D01*
G02X1488608Y1477327I-1912J2D01*
G03X1488580Y1477224I172J-102D01*
G01Y1476097D01*
G02X1488378Y1475894I-202J-1D01*
G01X1485558D01*
G02X1485356Y1476097I1J203D01*
G01Y1477224D01*
G03X1485328Y1477327I-200J1D01*
G02X1485056Y1478308I1640J983D01*
G02X1485328Y1479289I1912J-2D01*
G03X1485356Y1479392I-172J102D01*
G01Y1482342D01*
G03X1485328Y1482445I-200J1D01*
G02X1485056Y1483426I1640J983D01*
G02X1485328Y1484407I1912J-2D01*
G03X1485356Y1484510I-172J102D01*
G37*
G36*
G01X1502678D02*
Y1485635D01*
G02X1502881Y1485838I203J0D01*
G01X1505701D01*
G02X1505904Y1485635I0J-203D01*
G01Y1484510D01*
G03X1505932Y1484407I200J-1D01*
G02Y1482445I-1642J-981D01*
G03X1505904Y1482342I172J-102D01*
G01Y1479392D01*
G03X1505932Y1479289I200J-1D01*
G02Y1477327I-1642J-981D01*
G03X1505904Y1477224I172J-102D01*
G01Y1476097D01*
G02X1505701Y1475894I-203J0D01*
G01X1502881D01*
G02X1502678Y1476097I0J203D01*
G01Y1477224D01*
G03X1502650Y1477327I-200J1D01*
G02Y1479289I1642J981D01*
G03X1502678Y1479392I-172J102D01*
G01Y1482342D01*
G03X1502650Y1482445I-200J1D01*
G02Y1484407I1642J981D01*
G03X1502678Y1484510I-172J102D01*
G37*
G36*
G01X1520002D02*
Y1485635D01*
G02X1520204Y1485838I202J1D01*
G01X1523024D01*
G02X1523226Y1485635I-1J-203D01*
G01Y1484510D01*
G03X1523254Y1484407I200J-1D01*
G02X1523526Y1483426I-1640J-983D01*
G02X1523254Y1482445I-1912J2D01*
G03X1523226Y1482342I172J-102D01*
G01Y1479392D01*
G03X1523254Y1479289I200J-1D01*
G02X1523526Y1478308I-1640J-983D01*
G02X1523254Y1477327I-1912J2D01*
G03X1523226Y1477224I172J-102D01*
G01Y1476097D01*
G02X1523024Y1475894I-202J-1D01*
G01X1520204D01*
G02X1520002Y1476097I1J203D01*
G01Y1477224D01*
G03X1519974Y1477327I-200J1D01*
G02X1519702Y1478308I1640J983D01*
G02X1519974Y1479289I1912J-2D01*
G03X1520002Y1479392I-172J102D01*
G01Y1482342D01*
G03X1519974Y1482445I-200J1D01*
G02X1519702Y1483426I1640J983D01*
G02X1519974Y1484407I1912J-2D01*
G03X1520002Y1484510I-172J102D01*
G37*
G36*
G01X1537324D02*
Y1485635D01*
G02X1537527Y1485838I203J0D01*
G01X1540347D01*
G02X1540550Y1485635I0J-203D01*
G01Y1484510D01*
G03X1540578Y1484407I200J-1D01*
G02Y1482445I-1642J-981D01*
G03X1540550Y1482342I172J-102D01*
G01Y1479392D01*
G03X1540578Y1479289I200J-1D01*
G02Y1477327I-1642J-981D01*
G03X1540550Y1477224I172J-102D01*
G01Y1476097D01*
G02X1540347Y1475894I-203J0D01*
G01X1537527D01*
G02X1537324Y1476097I0J203D01*
G01Y1477224D01*
G03X1537296Y1477327I-200J1D01*
G02Y1479289I1642J981D01*
G03X1537324Y1479392I-172J102D01*
G01Y1482342D01*
G03X1537296Y1482445I-200J1D01*
G02Y1484407I1642J981D01*
G03X1537324Y1484510I-172J102D01*
G37*
G36*
G01X1130238Y1495533D02*
Y1496659D01*
G02X1130440Y1496862I202J1D01*
G01X1133260D01*
G02X1133462Y1496659I-1J-203D01*
G01Y1495533D01*
G03X1133490Y1495430I200J-1D01*
G02X1133762Y1494449I-1640J-983D01*
G02X1133490Y1493468I-1912J2D01*
G03X1133462Y1493365I172J-102D01*
G01Y1490415D01*
G03X1133490Y1490312I200J-1D01*
G02X1133762Y1489331I-1640J-983D01*
G02X1133490Y1488350I-1912J2D01*
G03X1133462Y1488247I172J-102D01*
G01Y1487121D01*
G02X1133260Y1486918I-202J-1D01*
G01X1130440D01*
G02X1130238Y1487121I1J203D01*
G01Y1488247D01*
G03X1130210Y1488350I-200J1D01*
G02X1129938Y1489331I1640J983D01*
G02X1130210Y1490312I1912J-2D01*
G03X1130238Y1490415I-172J102D01*
G01Y1493365D01*
G03X1130210Y1493468I-200J1D01*
G02X1129938Y1494449I1640J983D01*
G02X1130210Y1495430I1912J-2D01*
G03X1130238Y1495533I-172J102D01*
G37*
G36*
G01X1147560D02*
Y1496659D01*
G02X1147763Y1496862I203J0D01*
G01X1150583D01*
G02X1150786Y1496659I0J-203D01*
G01Y1495533D01*
G03X1150814Y1495430I200J-1D01*
G02Y1493468I-1642J-981D01*
G03X1150786Y1493365I172J-102D01*
G01Y1490415D01*
G03X1150814Y1490312I200J-1D01*
G02Y1488350I-1642J-981D01*
G03X1150786Y1488247I172J-102D01*
G01Y1487121D01*
G02X1150583Y1486918I-203J0D01*
G01X1147763D01*
G02X1147560Y1487121I0J203D01*
G01Y1488247D01*
G03X1147532Y1488350I-200J1D01*
G02Y1490312I1642J981D01*
G03X1147560Y1490415I-172J102D01*
G01Y1493365D01*
G03X1147532Y1493468I-200J1D01*
G02Y1495430I1642J981D01*
G03X1147560Y1495533I-172J102D01*
G37*
G36*
G01X1164884D02*
Y1496659D01*
G02X1165086Y1496862I202J1D01*
G01X1167906D01*
G02X1168108Y1496659I-1J-203D01*
G01Y1495533D01*
G03X1168136Y1495430I200J-1D01*
G02X1168408Y1494449I-1640J-983D01*
G02X1168136Y1493468I-1912J2D01*
G03X1168108Y1493365I172J-102D01*
G01Y1490415D01*
G03X1168136Y1490312I200J-1D01*
G02X1168408Y1489331I-1640J-983D01*
G02X1168136Y1488350I-1912J2D01*
G03X1168108Y1488247I172J-102D01*
G01Y1487121D01*
G02X1167906Y1486918I-202J-1D01*
G01X1165086D01*
G02X1164884Y1487121I1J203D01*
G01Y1488247D01*
G03X1164856Y1488350I-200J1D01*
G02X1164584Y1489331I1640J983D01*
G02X1164856Y1490312I1912J-2D01*
G03X1164884Y1490415I-172J102D01*
G01Y1493365D01*
G03X1164856Y1493468I-200J1D01*
G02X1164584Y1494449I1640J983D01*
G02X1164856Y1495430I1912J-2D01*
G03X1164884Y1495533I-172J102D01*
G37*
G36*
G01X1182206D02*
Y1496659D01*
G02X1182408Y1496862I202J1D01*
G01X1185228D01*
G02X1185430Y1496659I-1J-203D01*
G01Y1495533D01*
G03X1185458Y1495430I200J-1D01*
G02X1185730Y1494449I-1640J-983D01*
G02X1185458Y1493468I-1912J2D01*
G03X1185430Y1493365I172J-102D01*
G01Y1490415D01*
G03X1185458Y1490312I200J-1D01*
G02X1185730Y1489331I-1640J-983D01*
G02X1185458Y1488350I-1912J2D01*
G03X1185430Y1488247I172J-102D01*
G01Y1487121D01*
G02X1185228Y1486918I-202J-1D01*
G01X1182408D01*
G02X1182206Y1487121I1J203D01*
G01Y1488247D01*
G03X1182178Y1488350I-200J1D01*
G02X1181906Y1489331I1640J983D01*
G02X1182178Y1490312I1912J-2D01*
G03X1182206Y1490415I-172J102D01*
G01Y1493365D01*
G03X1182178Y1493468I-200J1D01*
G02X1181906Y1494449I1640J983D01*
G02X1182178Y1495430I1912J-2D01*
G03X1182206Y1495533I-172J102D01*
G37*
G36*
G01X1303466D02*
Y1496659D01*
G02X1303669Y1496862I203J0D01*
G01X1306489D01*
G02X1306692Y1496659I0J-203D01*
G01Y1495533D01*
G03X1306720Y1495430I200J-1D01*
G02Y1493468I-1642J-981D01*
G03X1306692Y1493365I172J-102D01*
G01Y1490415D01*
G03X1306720Y1490312I200J-1D01*
G02Y1488350I-1642J-981D01*
G03X1306692Y1488247I172J-102D01*
G01Y1487121D01*
G02X1306489Y1486918I-203J0D01*
G01X1303669D01*
G02X1303466Y1487121I0J203D01*
G01Y1488247D01*
G03X1303438Y1488350I-200J1D01*
G02Y1490312I1642J981D01*
G03X1303466Y1490415I-172J102D01*
G01Y1493365D01*
G03X1303438Y1493468I-200J1D01*
G02Y1495430I1642J981D01*
G03X1303466Y1495533I-172J102D01*
G37*
G36*
G01X1320790D02*
Y1496659D01*
G02X1320992Y1496862I202J1D01*
G01X1323812D01*
G02X1324014Y1496659I-1J-203D01*
G01Y1495533D01*
G03X1324042Y1495430I200J-1D01*
G02X1324314Y1494449I-1640J-983D01*
G02X1324042Y1493468I-1912J2D01*
G03X1324014Y1493365I172J-102D01*
G01Y1490415D01*
G03X1324042Y1490312I200J-1D01*
G02X1324314Y1489331I-1640J-983D01*
G02X1324042Y1488350I-1912J2D01*
G03X1324014Y1488247I172J-102D01*
G01Y1487121D01*
G02X1323812Y1486918I-202J-1D01*
G01X1320992D01*
G02X1320790Y1487121I1J203D01*
G01Y1488247D01*
G03X1320762Y1488350I-200J1D01*
G02X1320490Y1489331I1640J983D01*
G02X1320762Y1490312I1912J-2D01*
G03X1320790Y1490415I-172J102D01*
G01Y1493365D01*
G03X1320762Y1493468I-200J1D01*
G02X1320490Y1494449I1640J983D01*
G02X1320762Y1495430I1912J-2D01*
G03X1320790Y1495533I-172J102D01*
G37*
G36*
G01X1338112D02*
Y1496659D01*
G02X1338315Y1496862I203J0D01*
G01X1341135D01*
G02X1341338Y1496659I0J-203D01*
G01Y1495533D01*
G03X1341366Y1495430I200J-1D01*
G02Y1493468I-1642J-981D01*
G03X1341338Y1493365I172J-102D01*
G01Y1490415D01*
G03X1341366Y1490312I200J-1D01*
G02Y1488350I-1642J-981D01*
G03X1341338Y1488247I172J-102D01*
G01Y1487121D01*
G02X1341135Y1486918I-203J0D01*
G01X1338315D01*
G02X1338112Y1487121I0J203D01*
G01Y1488247D01*
G03X1338084Y1488350I-200J1D01*
G02Y1490312I1642J981D01*
G03X1338112Y1490415I-172J102D01*
G01Y1493365D01*
G03X1338084Y1493468I-200J1D01*
G02Y1495430I1642J981D01*
G03X1338112Y1495533I-172J102D01*
G37*
G36*
G01X1355434D02*
Y1496659D01*
G02X1355637Y1496862I203J0D01*
G01X1358457D01*
G02X1358660Y1496659I0J-203D01*
G01Y1495533D01*
G03X1358688Y1495430I200J-1D01*
G02Y1493468I-1642J-981D01*
G03X1358660Y1493365I172J-102D01*
G01Y1490415D01*
G03X1358688Y1490312I200J-1D01*
G02Y1488350I-1642J-981D01*
G03X1358660Y1488247I172J-102D01*
G01Y1487121D01*
G02X1358457Y1486918I-203J0D01*
G01X1355637D01*
G02X1355434Y1487121I0J203D01*
G01Y1488247D01*
G03X1355406Y1488350I-200J1D01*
G02Y1490312I1642J981D01*
G03X1355434Y1490415I-172J102D01*
G01Y1493365D01*
G03X1355406Y1493468I-200J1D01*
G02Y1495430I1642J981D01*
G03X1355434Y1495533I-172J102D01*
G37*
G36*
G01X1476694D02*
Y1496659D01*
G02X1476897Y1496862I203J0D01*
G01X1479717D01*
G02X1479920Y1496659I0J-203D01*
G01Y1495533D01*
G03X1479948Y1495430I200J-1D01*
G02Y1493468I-1642J-981D01*
G03X1479920Y1493365I172J-102D01*
G01Y1490415D01*
G03X1479948Y1490312I200J-1D01*
G02Y1488350I-1642J-981D01*
G03X1479920Y1488247I172J-102D01*
G01Y1487121D01*
G02X1479717Y1486918I-203J0D01*
G01X1476897D01*
G02X1476694Y1487121I0J203D01*
G01Y1488247D01*
G03X1476666Y1488350I-200J1D01*
G02Y1490312I1642J981D01*
G03X1476694Y1490415I-172J102D01*
G01Y1493365D01*
G03X1476666Y1493468I-200J1D01*
G02Y1495430I1642J981D01*
G03X1476694Y1495533I-172J102D01*
G37*
G36*
G01X1494018D02*
Y1496659D01*
G02X1494220Y1496862I202J1D01*
G01X1497040D01*
G02X1497242Y1496659I-1J-203D01*
G01Y1495533D01*
G03X1497270Y1495430I200J-1D01*
G02X1497542Y1494449I-1640J-983D01*
G02X1497270Y1493468I-1912J2D01*
G03X1497242Y1493365I172J-102D01*
G01Y1490415D01*
G03X1497270Y1490312I200J-1D01*
G02X1497542Y1489331I-1640J-983D01*
G02X1497270Y1488350I-1912J2D01*
G03X1497242Y1488247I172J-102D01*
G01Y1487121D01*
G02X1497040Y1486918I-202J-1D01*
G01X1494220D01*
G02X1494018Y1487121I1J203D01*
G01Y1488247D01*
G03X1493990Y1488350I-200J1D01*
G02X1493718Y1489331I1640J983D01*
G02X1493990Y1490312I1912J-2D01*
G03X1494018Y1490415I-172J102D01*
G01Y1493365D01*
G03X1493990Y1493468I-200J1D01*
G02X1493718Y1494449I1640J983D01*
G02X1493990Y1495430I1912J-2D01*
G03X1494018Y1495533I-172J102D01*
G37*
G36*
G01X1511340D02*
Y1496659D01*
G02X1511543Y1496862I203J0D01*
G01X1514363D01*
G02X1514566Y1496659I0J-203D01*
G01Y1495533D01*
G03X1514594Y1495430I200J-1D01*
G02Y1493468I-1642J-981D01*
G03X1514566Y1493365I172J-102D01*
G01Y1490415D01*
G03X1514594Y1490312I200J-1D01*
G02Y1488350I-1642J-981D01*
G03X1514566Y1488247I172J-102D01*
G01Y1487121D01*
G02X1514363Y1486918I-203J0D01*
G01X1511543D01*
G02X1511340Y1487121I0J203D01*
G01Y1488247D01*
G03X1511312Y1488350I-200J1D01*
G02Y1490312I1642J981D01*
G03X1511340Y1490415I-172J102D01*
G01Y1493365D01*
G03X1511312Y1493468I-200J1D01*
G02Y1495430I1642J981D01*
G03X1511340Y1495533I-172J102D01*
G37*
G36*
G01X1528662D02*
Y1496659D01*
G02X1528865Y1496862I203J0D01*
G01X1531685D01*
G02X1531888Y1496659I0J-203D01*
G01Y1495533D01*
G03X1531916Y1495430I200J-1D01*
G02Y1493468I-1642J-981D01*
G03X1531888Y1493365I172J-102D01*
G01Y1490415D01*
G03X1531916Y1490312I200J-1D01*
G02Y1488350I-1642J-981D01*
G03X1531888Y1488247I172J-102D01*
G01Y1487121D01*
G02X1531685Y1486918I-203J0D01*
G01X1528865D01*
G02X1528662Y1487121I0J203D01*
G01Y1488247D01*
G03X1528634Y1488350I-200J1D01*
G02Y1490312I1642J981D01*
G03X1528662Y1490415I-172J102D01*
G01Y1493365D01*
G03X1528634Y1493468I-200J1D01*
G02Y1495430I1642J981D01*
G03X1528662Y1495533I-172J102D01*
G37*
G36*
G01X1138898Y1499864D02*
Y1500989D01*
G02X1139101Y1501192I203J0D01*
G01X1141921D01*
G02X1142124Y1500989I0J-203D01*
G01Y1499864D01*
G03X1142152Y1499761I200J-1D01*
G02Y1497799I-1642J-981D01*
G03X1142124Y1497696I172J-102D01*
G01Y1494746D01*
G03X1142152Y1494643I200J-1D01*
G02Y1492681I-1642J-981D01*
G03X1142124Y1492578I172J-102D01*
G01Y1491451D01*
G02X1141921Y1491248I-203J0D01*
G01X1139101D01*
G02X1138898Y1491451I0J203D01*
G01Y1492578D01*
G03X1138870Y1492681I-200J1D01*
G02Y1494643I1642J981D01*
G03X1138898Y1494746I-172J102D01*
G01Y1497696D01*
G03X1138870Y1497799I-200J1D01*
G02Y1499761I1642J981D01*
G03X1138898Y1499864I-172J102D01*
G37*
G36*
G01X1156222D02*
Y1500989D01*
G02X1156424Y1501192I202J1D01*
G01X1159244D01*
G02X1159446Y1500989I-1J-203D01*
G01Y1499864D01*
G03X1159474Y1499761I200J-1D01*
G02X1159746Y1498780I-1640J-983D01*
G02X1159474Y1497799I-1912J2D01*
G03X1159446Y1497696I172J-102D01*
G01Y1494746D01*
G03X1159474Y1494643I200J-1D01*
G02X1159746Y1493662I-1640J-983D01*
G02X1159474Y1492681I-1912J2D01*
G03X1159446Y1492578I172J-102D01*
G01Y1491451D01*
G02X1159244Y1491248I-202J-1D01*
G01X1156424D01*
G02X1156222Y1491451I1J203D01*
G01Y1492578D01*
G03X1156194Y1492681I-200J1D01*
G02X1155922Y1493662I1640J983D01*
G02X1156194Y1494643I1912J-2D01*
G03X1156222Y1494746I-172J102D01*
G01Y1497696D01*
G03X1156194Y1497799I-200J1D01*
G02X1155922Y1498780I1640J983D01*
G02X1156194Y1499761I1912J-2D01*
G03X1156222Y1499864I-172J102D01*
G37*
G36*
G01X1173544D02*
Y1500989D01*
G02X1173747Y1501192I203J0D01*
G01X1176567D01*
G02X1176770Y1500989I0J-203D01*
G01Y1499864D01*
G03X1176798Y1499761I200J-1D01*
G02Y1497799I-1642J-981D01*
G03X1176770Y1497696I172J-102D01*
G01Y1494746D01*
G03X1176798Y1494643I200J-1D01*
G02Y1492681I-1642J-981D01*
G03X1176770Y1492578I172J-102D01*
G01Y1491451D01*
G02X1176567Y1491248I-203J0D01*
G01X1173747D01*
G02X1173544Y1491451I0J203D01*
G01Y1492578D01*
G03X1173516Y1492681I-200J1D01*
G02Y1494643I1642J981D01*
G03X1173544Y1494746I-172J102D01*
G01Y1497696D01*
G03X1173516Y1497799I-200J1D01*
G02Y1499761I1642J981D01*
G03X1173544Y1499864I-172J102D01*
G37*
G36*
G01X1190868D02*
Y1500989D01*
G02X1191070Y1501192I202J1D01*
G01X1193890D01*
G02X1194092Y1500989I-1J-203D01*
G01Y1499864D01*
G03X1194120Y1499761I200J-1D01*
G02X1194392Y1498780I-1640J-983D01*
G02X1194120Y1497799I-1912J2D01*
G03X1194092Y1497696I172J-102D01*
G01Y1494746D01*
G03X1194120Y1494643I200J-1D01*
G02X1194392Y1493662I-1640J-983D01*
G02X1194120Y1492681I-1912J2D01*
G03X1194092Y1492578I172J-102D01*
G01Y1491451D01*
G02X1193890Y1491248I-202J-1D01*
G01X1191070D01*
G02X1190868Y1491451I1J203D01*
G01Y1492578D01*
G03X1190840Y1492681I-200J1D01*
G02X1190568Y1493662I1640J983D01*
G02X1190840Y1494643I1912J-2D01*
G03X1190868Y1494746I-172J102D01*
G01Y1497696D01*
G03X1190840Y1497799I-200J1D01*
G02X1190568Y1498780I1640J983D01*
G02X1190840Y1499761I1912J-2D01*
G03X1190868Y1499864I-172J102D01*
G37*
G36*
G01X1312128D02*
Y1500989D01*
G02X1312330Y1501192I202J1D01*
G01X1315150D01*
G02X1315352Y1500989I-1J-203D01*
G01Y1499864D01*
G03X1315380Y1499761I200J-1D01*
G02X1315652Y1498780I-1640J-983D01*
G02X1315380Y1497799I-1912J2D01*
G03X1315352Y1497696I172J-102D01*
G01Y1494746D01*
G03X1315380Y1494643I200J-1D01*
G02X1315652Y1493662I-1640J-983D01*
G02X1315380Y1492681I-1912J2D01*
G03X1315352Y1492578I172J-102D01*
G01Y1491451D01*
G02X1315150Y1491248I-202J-1D01*
G01X1312330D01*
G02X1312128Y1491451I1J203D01*
G01Y1492578D01*
G03X1312100Y1492681I-200J1D01*
G02X1311828Y1493662I1640J983D01*
G02X1312100Y1494643I1912J-2D01*
G03X1312128Y1494746I-172J102D01*
G01Y1497696D01*
G03X1312100Y1497799I-200J1D01*
G02X1311828Y1498780I1640J983D01*
G02X1312100Y1499761I1912J-2D01*
G03X1312128Y1499864I-172J102D01*
G37*
G36*
G01X1329450D02*
Y1500989D01*
G02X1329653Y1501192I203J0D01*
G01X1332473D01*
G02X1332676Y1500989I0J-203D01*
G01Y1499864D01*
G03X1332704Y1499761I200J-1D01*
G02Y1497799I-1642J-981D01*
G03X1332676Y1497696I172J-102D01*
G01Y1494746D01*
G03X1332704Y1494643I200J-1D01*
G02Y1492681I-1642J-981D01*
G03X1332676Y1492578I172J-102D01*
G01Y1491451D01*
G02X1332473Y1491248I-203J0D01*
G01X1329653D01*
G02X1329450Y1491451I0J203D01*
G01Y1492578D01*
G03X1329422Y1492681I-200J1D01*
G02Y1494643I1642J981D01*
G03X1329450Y1494746I-172J102D01*
G01Y1497696D01*
G03X1329422Y1497799I-200J1D01*
G02Y1499761I1642J981D01*
G03X1329450Y1499864I-172J102D01*
G37*
G36*
G01X1346774D02*
Y1500989D01*
G02X1346976Y1501192I202J1D01*
G01X1349796D01*
G02X1349998Y1500989I-1J-203D01*
G01Y1499864D01*
G03X1350026Y1499761I200J-1D01*
G02X1350298Y1498780I-1640J-983D01*
G02X1350026Y1497799I-1912J2D01*
G03X1349998Y1497696I172J-102D01*
G01Y1494746D01*
G03X1350026Y1494643I200J-1D01*
G02X1350298Y1493662I-1640J-983D01*
G02X1350026Y1492681I-1912J2D01*
G03X1349998Y1492578I172J-102D01*
G01Y1491451D01*
G02X1349796Y1491248I-202J-1D01*
G01X1346976D01*
G02X1346774Y1491451I1J203D01*
G01Y1492578D01*
G03X1346746Y1492681I-200J1D01*
G02X1346474Y1493662I1640J983D01*
G02X1346746Y1494643I1912J-2D01*
G03X1346774Y1494746I-172J102D01*
G01Y1497696D01*
G03X1346746Y1497799I-200J1D01*
G02X1346474Y1498780I1640J983D01*
G02X1346746Y1499761I1912J-2D01*
G03X1346774Y1499864I-172J102D01*
G37*
G36*
G01X1364096D02*
Y1500989D01*
G02X1364299Y1501192I203J0D01*
G01X1367119D01*
G02X1367322Y1500989I0J-203D01*
G01Y1499864D01*
G03X1367350Y1499761I200J-1D01*
G02Y1497799I-1642J-981D01*
G03X1367322Y1497696I172J-102D01*
G01Y1494746D01*
G03X1367350Y1494643I200J-1D01*
G02Y1492681I-1642J-981D01*
G03X1367322Y1492578I172J-102D01*
G01Y1491451D01*
G02X1367119Y1491248I-203J0D01*
G01X1364299D01*
G02X1364096Y1491451I0J203D01*
G01Y1492578D01*
G03X1364068Y1492681I-200J1D01*
G02Y1494643I1642J981D01*
G03X1364096Y1494746I-172J102D01*
G01Y1497696D01*
G03X1364068Y1497799I-200J1D01*
G02Y1499761I1642J981D01*
G03X1364096Y1499864I-172J102D01*
G37*
G36*
G01X1485356D02*
Y1500989D01*
G02X1485558Y1501192I202J1D01*
G01X1488378D01*
G02X1488580Y1500989I-1J-203D01*
G01Y1499864D01*
G03X1488608Y1499761I200J-1D01*
G02X1488880Y1498780I-1640J-983D01*
G02X1488608Y1497799I-1912J2D01*
G03X1488580Y1497696I172J-102D01*
G01Y1494746D01*
G03X1488608Y1494643I200J-1D01*
G02X1488880Y1493662I-1640J-983D01*
G02X1488608Y1492681I-1912J2D01*
G03X1488580Y1492578I172J-102D01*
G01Y1491451D01*
G02X1488378Y1491248I-202J-1D01*
G01X1485558D01*
G02X1485356Y1491451I1J203D01*
G01Y1492578D01*
G03X1485328Y1492681I-200J1D01*
G02X1485056Y1493662I1640J983D01*
G02X1485328Y1494643I1912J-2D01*
G03X1485356Y1494746I-172J102D01*
G01Y1497696D01*
G03X1485328Y1497799I-200J1D01*
G02X1485056Y1498780I1640J983D01*
G02X1485328Y1499761I1912J-2D01*
G03X1485356Y1499864I-172J102D01*
G37*
G36*
G01X1502678D02*
Y1500989D01*
G02X1502881Y1501192I203J0D01*
G01X1505701D01*
G02X1505904Y1500989I0J-203D01*
G01Y1499864D01*
G03X1505932Y1499761I200J-1D01*
G02Y1497799I-1642J-981D01*
G03X1505904Y1497696I172J-102D01*
G01Y1494746D01*
G03X1505932Y1494643I200J-1D01*
G02Y1492681I-1642J-981D01*
G03X1505904Y1492578I172J-102D01*
G01Y1491451D01*
G02X1505701Y1491248I-203J0D01*
G01X1502881D01*
G02X1502678Y1491451I0J203D01*
G01Y1492578D01*
G03X1502650Y1492681I-200J1D01*
G02Y1494643I1642J981D01*
G03X1502678Y1494746I-172J102D01*
G01Y1497696D01*
G03X1502650Y1497799I-200J1D01*
G02Y1499761I1642J981D01*
G03X1502678Y1499864I-172J102D01*
G37*
G36*
G01X1520002D02*
Y1500989D01*
G02X1520204Y1501192I202J1D01*
G01X1523024D01*
G02X1523226Y1500989I-1J-203D01*
G01Y1499864D01*
G03X1523254Y1499761I200J-1D01*
G02X1523526Y1498780I-1640J-983D01*
G02X1523254Y1497799I-1912J2D01*
G03X1523226Y1497696I172J-102D01*
G01Y1494746D01*
G03X1523254Y1494643I200J-1D01*
G02X1523526Y1493662I-1640J-983D01*
G02X1523254Y1492681I-1912J2D01*
G03X1523226Y1492578I172J-102D01*
G01Y1491451D01*
G02X1523024Y1491248I-202J-1D01*
G01X1520204D01*
G02X1520002Y1491451I1J203D01*
G01Y1492578D01*
G03X1519974Y1492681I-200J1D01*
G02X1519702Y1493662I1640J983D01*
G02X1519974Y1494643I1912J-2D01*
G03X1520002Y1494746I-172J102D01*
G01Y1497696D01*
G03X1519974Y1497799I-200J1D01*
G02X1519702Y1498780I1640J983D01*
G02X1519974Y1499761I1912J-2D01*
G03X1520002Y1499864I-172J102D01*
G37*
G36*
G01X1537324D02*
Y1500989D01*
G02X1537527Y1501192I203J0D01*
G01X1540347D01*
G02X1540550Y1500989I0J-203D01*
G01Y1499864D01*
G03X1540578Y1499761I200J-1D01*
G02Y1497799I-1642J-981D01*
G03X1540550Y1497696I172J-102D01*
G01Y1494746D01*
G03X1540578Y1494643I200J-1D01*
G02Y1492681I-1642J-981D01*
G03X1540550Y1492578I172J-102D01*
G01Y1491451D01*
G02X1540347Y1491248I-203J0D01*
G01X1537527D01*
G02X1537324Y1491451I0J203D01*
G01Y1492578D01*
G03X1537296Y1492681I-200J1D01*
G02Y1494643I1642J981D01*
G03X1537324Y1494746I-172J102D01*
G01Y1497696D01*
G03X1537296Y1497799I-200J1D01*
G02Y1499761I1642J981D01*
G03X1537324Y1499864I-172J102D01*
G37*
G36*
G01X1130238Y1510888D02*
Y1512014D01*
G02X1130440Y1512216I202J0D01*
G01X1133260D01*
G02X1133462Y1512014I0J-202D01*
G01Y1510888D01*
G03X1133490Y1510785I200J-1D01*
G02X1133762Y1509804I-1640J-983D01*
G02X1133490Y1508823I-1912J2D01*
G03X1133462Y1508720I172J-102D01*
G01Y1505769D01*
G03X1133490Y1505666I200J-1D01*
G02X1133762Y1504685I-1640J-983D01*
G02X1133490Y1503704I-1912J2D01*
G03X1133462Y1503601I172J-102D01*
G01Y1502476D01*
G02X1133260Y1502274I-202J0D01*
G01X1130440D01*
G02X1130238Y1502476I0J202D01*
G01Y1503601D01*
G03X1130210Y1503704I-200J1D01*
G02X1129938Y1504685I1640J983D01*
G02X1130210Y1505666I1912J-2D01*
G03X1130238Y1505769I-172J102D01*
G01Y1508720D01*
G03X1130210Y1508823I-200J1D01*
G02X1129938Y1509804I1640J983D01*
G02X1130210Y1510785I1912J-2D01*
G03X1130238Y1510888I-172J102D01*
G37*
G36*
G01X1147560D02*
Y1512014D01*
G02X1147763Y1512216I203J-1D01*
G01X1150583D01*
G02X1150786Y1512014I1J-202D01*
G01Y1510888D01*
G03X1150814Y1510785I200J-1D01*
G02Y1508823I-1642J-981D01*
G03X1150786Y1508720I172J-102D01*
G01Y1505769D01*
G03X1150814Y1505666I200J-1D01*
G02Y1503704I-1642J-981D01*
G03X1150786Y1503601I172J-102D01*
G01Y1502476D01*
G02X1150583Y1502274I-203J1D01*
G01X1147763D01*
G02X1147560Y1502476I-1J202D01*
G01Y1503601D01*
G03X1147532Y1503704I-200J1D01*
G02Y1505666I1642J981D01*
G03X1147560Y1505769I-172J102D01*
G01Y1508720D01*
G03X1147532Y1508823I-200J1D01*
G02Y1510785I1642J981D01*
G03X1147560Y1510888I-172J102D01*
G37*
G36*
G01X1164884D02*
Y1512014D01*
G02X1165086Y1512216I202J0D01*
G01X1167906D01*
G02X1168108Y1512014I0J-202D01*
G01Y1510888D01*
G03X1168136Y1510785I200J-1D01*
G02X1168408Y1509804I-1640J-983D01*
G02X1168136Y1508823I-1912J2D01*
G03X1168108Y1508720I172J-102D01*
G01Y1505769D01*
G03X1168136Y1505666I200J-1D01*
G02X1168408Y1504685I-1640J-983D01*
G02X1168136Y1503704I-1912J2D01*
G03X1168108Y1503601I172J-102D01*
G01Y1502476D01*
G02X1167906Y1502274I-202J0D01*
G01X1165086D01*
G02X1164884Y1502476I0J202D01*
G01Y1503601D01*
G03X1164856Y1503704I-200J1D01*
G02X1164584Y1504685I1640J983D01*
G02X1164856Y1505666I1912J-2D01*
G03X1164884Y1505769I-172J102D01*
G01Y1508720D01*
G03X1164856Y1508823I-200J1D01*
G02X1164584Y1509804I1640J983D01*
G02X1164856Y1510785I1912J-2D01*
G03X1164884Y1510888I-172J102D01*
G37*
G36*
G01X1182206D02*
Y1512014D01*
G02X1182408Y1512216I202J0D01*
G01X1185228D01*
G02X1185430Y1512014I0J-202D01*
G01Y1510888D01*
G03X1185458Y1510785I200J-1D01*
G02X1185730Y1509804I-1640J-983D01*
G02X1185458Y1508823I-1912J2D01*
G03X1185430Y1508720I172J-102D01*
G01Y1505769D01*
G03X1185458Y1505666I200J-1D01*
G02X1185730Y1504685I-1640J-983D01*
G02X1185458Y1503704I-1912J2D01*
G03X1185430Y1503601I172J-102D01*
G01Y1502476D01*
G02X1185228Y1502274I-202J0D01*
G01X1182408D01*
G02X1182206Y1502476I0J202D01*
G01Y1503601D01*
G03X1182178Y1503704I-200J1D01*
G02X1181906Y1504685I1640J983D01*
G02X1182178Y1505666I1912J-2D01*
G03X1182206Y1505769I-172J102D01*
G01Y1508720D01*
G03X1182178Y1508823I-200J1D01*
G02X1181906Y1509804I1640J983D01*
G02X1182178Y1510785I1912J-2D01*
G03X1182206Y1510888I-172J102D01*
G37*
G36*
G01X1303466D02*
Y1512014D01*
G02X1303669Y1512216I203J-1D01*
G01X1306489D01*
G02X1306692Y1512014I1J-202D01*
G01Y1510888D01*
G03X1306720Y1510785I200J-1D01*
G02Y1508823I-1642J-981D01*
G03X1306692Y1508720I172J-102D01*
G01Y1505769D01*
G03X1306720Y1505666I200J-1D01*
G02Y1503704I-1642J-981D01*
G03X1306692Y1503601I172J-102D01*
G01Y1502476D01*
G02X1306489Y1502274I-203J1D01*
G01X1303669D01*
G02X1303466Y1502476I-1J202D01*
G01Y1503601D01*
G03X1303438Y1503704I-200J1D01*
G02Y1505666I1642J981D01*
G03X1303466Y1505769I-172J102D01*
G01Y1508720D01*
G03X1303438Y1508823I-200J1D01*
G02Y1510785I1642J981D01*
G03X1303466Y1510888I-172J102D01*
G37*
G36*
G01X1320790D02*
Y1512014D01*
G02X1320992Y1512216I202J0D01*
G01X1323812D01*
G02X1324014Y1512014I0J-202D01*
G01Y1510888D01*
G03X1324042Y1510785I200J-1D01*
G02X1324314Y1509804I-1640J-983D01*
G02X1324042Y1508823I-1912J2D01*
G03X1324014Y1508720I172J-102D01*
G01Y1505769D01*
G03X1324042Y1505666I200J-1D01*
G02X1324314Y1504685I-1640J-983D01*
G02X1324042Y1503704I-1912J2D01*
G03X1324014Y1503601I172J-102D01*
G01Y1502476D01*
G02X1323812Y1502274I-202J0D01*
G01X1320992D01*
G02X1320790Y1502476I0J202D01*
G01Y1503601D01*
G03X1320762Y1503704I-200J1D01*
G02X1320490Y1504685I1640J983D01*
G02X1320762Y1505666I1912J-2D01*
G03X1320790Y1505769I-172J102D01*
G01Y1508720D01*
G03X1320762Y1508823I-200J1D01*
G02X1320490Y1509804I1640J983D01*
G02X1320762Y1510785I1912J-2D01*
G03X1320790Y1510888I-172J102D01*
G37*
G36*
G01X1338112D02*
Y1512014D01*
G02X1338315Y1512216I203J-1D01*
G01X1341135D01*
G02X1341338Y1512014I1J-202D01*
G01Y1510888D01*
G03X1341366Y1510785I200J-1D01*
G02Y1508823I-1642J-981D01*
G03X1341338Y1508720I172J-102D01*
G01Y1505769D01*
G03X1341366Y1505666I200J-1D01*
G02Y1503704I-1642J-981D01*
G03X1341338Y1503601I172J-102D01*
G01Y1502476D01*
G02X1341135Y1502274I-203J1D01*
G01X1338315D01*
G02X1338112Y1502476I-1J202D01*
G01Y1503601D01*
G03X1338084Y1503704I-200J1D01*
G02Y1505666I1642J981D01*
G03X1338112Y1505769I-172J102D01*
G01Y1508720D01*
G03X1338084Y1508823I-200J1D01*
G02Y1510785I1642J981D01*
G03X1338112Y1510888I-172J102D01*
G37*
G36*
G01X1355434D02*
Y1512014D01*
G02X1355637Y1512216I203J-1D01*
G01X1358457D01*
G02X1358660Y1512014I1J-202D01*
G01Y1510888D01*
G03X1358688Y1510785I200J-1D01*
G02Y1508823I-1642J-981D01*
G03X1358660Y1508720I172J-102D01*
G01Y1505769D01*
G03X1358688Y1505666I200J-1D01*
G02Y1503704I-1642J-981D01*
G03X1358660Y1503601I172J-102D01*
G01Y1502476D01*
G02X1358457Y1502274I-203J1D01*
G01X1355637D01*
G02X1355434Y1502476I-1J202D01*
G01Y1503601D01*
G03X1355406Y1503704I-200J1D01*
G02Y1505666I1642J981D01*
G03X1355434Y1505769I-172J102D01*
G01Y1508720D01*
G03X1355406Y1508823I-200J1D01*
G02Y1510785I1642J981D01*
G03X1355434Y1510888I-172J102D01*
G37*
G36*
G01X1476694D02*
Y1512014D01*
G02X1476897Y1512216I203J-1D01*
G01X1479717D01*
G02X1479920Y1512014I1J-202D01*
G01Y1510888D01*
G03X1479948Y1510785I200J-1D01*
G02Y1508823I-1642J-981D01*
G03X1479920Y1508720I172J-102D01*
G01Y1505769D01*
G03X1479948Y1505666I200J-1D01*
G02Y1503704I-1642J-981D01*
G03X1479920Y1503601I172J-102D01*
G01Y1502476D01*
G02X1479717Y1502274I-203J1D01*
G01X1476897D01*
G02X1476694Y1502476I-1J202D01*
G01Y1503601D01*
G03X1476666Y1503704I-200J1D01*
G02Y1505666I1642J981D01*
G03X1476694Y1505769I-172J102D01*
G01Y1508720D01*
G03X1476666Y1508823I-200J1D01*
G02Y1510785I1642J981D01*
G03X1476694Y1510888I-172J102D01*
G37*
G36*
G01X1494018D02*
Y1512014D01*
G02X1494220Y1512216I202J0D01*
G01X1497040D01*
G02X1497242Y1512014I0J-202D01*
G01Y1510888D01*
G03X1497270Y1510785I200J-1D01*
G02X1497542Y1509804I-1640J-983D01*
G02X1497270Y1508823I-1912J2D01*
G03X1497242Y1508720I172J-102D01*
G01Y1505769D01*
G03X1497270Y1505666I200J-1D01*
G02X1497542Y1504685I-1640J-983D01*
G02X1497270Y1503704I-1912J2D01*
G03X1497242Y1503601I172J-102D01*
G01Y1502476D01*
G02X1497040Y1502274I-202J0D01*
G01X1494220D01*
G02X1494018Y1502476I0J202D01*
G01Y1503601D01*
G03X1493990Y1503704I-200J1D01*
G02X1493718Y1504685I1640J983D01*
G02X1493990Y1505666I1912J-2D01*
G03X1494018Y1505769I-172J102D01*
G01Y1508720D01*
G03X1493990Y1508823I-200J1D01*
G02X1493718Y1509804I1640J983D01*
G02X1493990Y1510785I1912J-2D01*
G03X1494018Y1510888I-172J102D01*
G37*
G36*
G01X1511340D02*
Y1512014D01*
G02X1511543Y1512216I203J-1D01*
G01X1514363D01*
G02X1514566Y1512014I1J-202D01*
G01Y1510888D01*
G03X1514594Y1510785I200J-1D01*
G02Y1508823I-1642J-981D01*
G03X1514566Y1508720I172J-102D01*
G01Y1505769D01*
G03X1514594Y1505666I200J-1D01*
G02Y1503704I-1642J-981D01*
G03X1514566Y1503601I172J-102D01*
G01Y1502476D01*
G02X1514363Y1502274I-203J1D01*
G01X1511543D01*
G02X1511340Y1502476I-1J202D01*
G01Y1503601D01*
G03X1511312Y1503704I-200J1D01*
G02Y1505666I1642J981D01*
G03X1511340Y1505769I-172J102D01*
G01Y1508720D01*
G03X1511312Y1508823I-200J1D01*
G02Y1510785I1642J981D01*
G03X1511340Y1510888I-172J102D01*
G37*
G36*
G01X1528662D02*
Y1512014D01*
G02X1528865Y1512216I203J-1D01*
G01X1531685D01*
G02X1531888Y1512014I1J-202D01*
G01Y1510888D01*
G03X1531916Y1510785I200J-1D01*
G02Y1508823I-1642J-981D01*
G03X1531888Y1508720I172J-102D01*
G01Y1505769D01*
G03X1531916Y1505666I200J-1D01*
G02Y1503704I-1642J-981D01*
G03X1531888Y1503601I172J-102D01*
G01Y1502476D01*
G02X1531685Y1502274I-203J1D01*
G01X1528865D01*
G02X1528662Y1502476I-1J202D01*
G01Y1503601D01*
G03X1528634Y1503704I-200J1D01*
G02Y1505666I1642J981D01*
G03X1528662Y1505769I-172J102D01*
G01Y1508720D01*
G03X1528634Y1508823I-200J1D01*
G02Y1510785I1642J981D01*
G03X1528662Y1510888I-172J102D01*
G37*
G36*
G01X1138898Y1515218D02*
Y1516344D01*
G02X1139101Y1516546I203J-1D01*
G01X1141921D01*
G02X1142124Y1516344I1J-202D01*
G01Y1515218D01*
G03X1142152Y1515115I200J-1D01*
G02Y1513153I-1642J-981D01*
G03X1142124Y1513050I172J-102D01*
G01Y1510100D01*
G03X1142152Y1509997I200J-1D01*
G02Y1508035I-1642J-981D01*
G03X1142124Y1507932I172J-102D01*
G01Y1506806D01*
G02X1141921Y1506604I-203J1D01*
G01X1139101D01*
G02X1138898Y1506806I-1J202D01*
G01Y1507932D01*
G03X1138870Y1508035I-200J1D01*
G02Y1509997I1642J981D01*
G03X1138898Y1510100I-172J102D01*
G01Y1513050D01*
G03X1138870Y1513153I-200J1D01*
G02Y1515115I1642J981D01*
G03X1138898Y1515218I-172J102D01*
G37*
G36*
G01X1156222D02*
Y1516344D01*
G02X1156424Y1516546I202J0D01*
G01X1159244D01*
G02X1159446Y1516344I0J-202D01*
G01Y1515218D01*
G03X1159474Y1515115I200J-1D01*
G02X1159746Y1514134I-1640J-983D01*
G02X1159474Y1513153I-1912J2D01*
G03X1159446Y1513050I172J-102D01*
G01Y1510100D01*
G03X1159474Y1509997I200J-1D01*
G02X1159746Y1509016I-1640J-983D01*
G02X1159474Y1508035I-1912J2D01*
G03X1159446Y1507932I172J-102D01*
G01Y1506806D01*
G02X1159244Y1506604I-202J0D01*
G01X1156424D01*
G02X1156222Y1506806I0J202D01*
G01Y1507932D01*
G03X1156194Y1508035I-200J1D01*
G02X1155922Y1509016I1640J983D01*
G02X1156194Y1509997I1912J-2D01*
G03X1156222Y1510100I-172J102D01*
G01Y1513050D01*
G03X1156194Y1513153I-200J1D01*
G02X1155922Y1514134I1640J983D01*
G02X1156194Y1515115I1912J-2D01*
G03X1156222Y1515218I-172J102D01*
G37*
G36*
G01X1173544D02*
Y1516344D01*
G02X1173747Y1516546I203J-1D01*
G01X1176567D01*
G02X1176770Y1516344I1J-202D01*
G01Y1515218D01*
G03X1176798Y1515115I200J-1D01*
G02Y1513153I-1642J-981D01*
G03X1176770Y1513050I172J-102D01*
G01Y1510100D01*
G03X1176798Y1509997I200J-1D01*
G02Y1508035I-1642J-981D01*
G03X1176770Y1507932I172J-102D01*
G01Y1506806D01*
G02X1176567Y1506604I-203J1D01*
G01X1173747D01*
G02X1173544Y1506806I-1J202D01*
G01Y1507932D01*
G03X1173516Y1508035I-200J1D01*
G02Y1509997I1642J981D01*
G03X1173544Y1510100I-172J102D01*
G01Y1513050D01*
G03X1173516Y1513153I-200J1D01*
G02Y1515115I1642J981D01*
G03X1173544Y1515218I-172J102D01*
G37*
G36*
G01X1190868D02*
Y1516344D01*
G02X1191070Y1516546I202J0D01*
G01X1193890D01*
G02X1194092Y1516344I0J-202D01*
G01Y1515218D01*
G03X1194120Y1515115I200J-1D01*
G02X1194392Y1514134I-1640J-983D01*
G02X1194120Y1513153I-1912J2D01*
G03X1194092Y1513050I172J-102D01*
G01Y1510100D01*
G03X1194120Y1509997I200J-1D01*
G02X1194392Y1509016I-1640J-983D01*
G02X1194120Y1508035I-1912J2D01*
G03X1194092Y1507932I172J-102D01*
G01Y1506806D01*
G02X1193890Y1506604I-202J0D01*
G01X1191070D01*
G02X1190868Y1506806I0J202D01*
G01Y1507932D01*
G03X1190840Y1508035I-200J1D01*
G02X1190568Y1509016I1640J983D01*
G02X1190840Y1509997I1912J-2D01*
G03X1190868Y1510100I-172J102D01*
G01Y1513050D01*
G03X1190840Y1513153I-200J1D01*
G02X1190568Y1514134I1640J983D01*
G02X1190840Y1515115I1912J-2D01*
G03X1190868Y1515218I-172J102D01*
G37*
G36*
G01X1312128D02*
Y1516344D01*
G02X1312330Y1516546I202J0D01*
G01X1315150D01*
G02X1315352Y1516344I0J-202D01*
G01Y1515218D01*
G03X1315380Y1515115I200J-1D01*
G02X1315652Y1514134I-1640J-983D01*
G02X1315380Y1513153I-1912J2D01*
G03X1315352Y1513050I172J-102D01*
G01Y1510100D01*
G03X1315380Y1509997I200J-1D01*
G02X1315652Y1509016I-1640J-983D01*
G02X1315380Y1508035I-1912J2D01*
G03X1315352Y1507932I172J-102D01*
G01Y1506806D01*
G02X1315150Y1506604I-202J0D01*
G01X1312330D01*
G02X1312128Y1506806I0J202D01*
G01Y1507932D01*
G03X1312100Y1508035I-200J1D01*
G02X1311828Y1509016I1640J983D01*
G02X1312100Y1509997I1912J-2D01*
G03X1312128Y1510100I-172J102D01*
G01Y1513050D01*
G03X1312100Y1513153I-200J1D01*
G02X1311828Y1514134I1640J983D01*
G02X1312100Y1515115I1912J-2D01*
G03X1312128Y1515218I-172J102D01*
G37*
G36*
G01X1329450D02*
Y1516344D01*
G02X1329653Y1516546I203J-1D01*
G01X1332473D01*
G02X1332676Y1516344I1J-202D01*
G01Y1515218D01*
G03X1332704Y1515115I200J-1D01*
G02Y1513153I-1642J-981D01*
G03X1332676Y1513050I172J-102D01*
G01Y1510100D01*
G03X1332704Y1509997I200J-1D01*
G02Y1508035I-1642J-981D01*
G03X1332676Y1507932I172J-102D01*
G01Y1506806D01*
G02X1332473Y1506604I-203J1D01*
G01X1329653D01*
G02X1329450Y1506806I-1J202D01*
G01Y1507932D01*
G03X1329422Y1508035I-200J1D01*
G02Y1509997I1642J981D01*
G03X1329450Y1510100I-172J102D01*
G01Y1513050D01*
G03X1329422Y1513153I-200J1D01*
G02Y1515115I1642J981D01*
G03X1329450Y1515218I-172J102D01*
G37*
G36*
G01X1346774D02*
Y1516344D01*
G02X1346976Y1516546I202J0D01*
G01X1349796D01*
G02X1349998Y1516344I0J-202D01*
G01Y1515218D01*
G03X1350026Y1515115I200J-1D01*
G02X1350298Y1514134I-1640J-983D01*
G02X1350026Y1513153I-1912J2D01*
G03X1349998Y1513050I172J-102D01*
G01Y1510100D01*
G03X1350026Y1509997I200J-1D01*
G02X1350298Y1509016I-1640J-983D01*
G02X1350026Y1508035I-1912J2D01*
G03X1349998Y1507932I172J-102D01*
G01Y1506806D01*
G02X1349796Y1506604I-202J0D01*
G01X1346976D01*
G02X1346774Y1506806I0J202D01*
G01Y1507932D01*
G03X1346746Y1508035I-200J1D01*
G02X1346474Y1509016I1640J983D01*
G02X1346746Y1509997I1912J-2D01*
G03X1346774Y1510100I-172J102D01*
G01Y1513050D01*
G03X1346746Y1513153I-200J1D01*
G02X1346474Y1514134I1640J983D01*
G02X1346746Y1515115I1912J-2D01*
G03X1346774Y1515218I-172J102D01*
G37*
G36*
G01X1364096D02*
Y1516344D01*
G02X1364299Y1516546I203J-1D01*
G01X1367119D01*
G02X1367322Y1516344I1J-202D01*
G01Y1515218D01*
G03X1367350Y1515115I200J-1D01*
G02Y1513153I-1642J-981D01*
G03X1367322Y1513050I172J-102D01*
G01Y1510100D01*
G03X1367350Y1509997I200J-1D01*
G02Y1508035I-1642J-981D01*
G03X1367322Y1507932I172J-102D01*
G01Y1506806D01*
G02X1367119Y1506604I-203J1D01*
G01X1364299D01*
G02X1364096Y1506806I-1J202D01*
G01Y1507932D01*
G03X1364068Y1508035I-200J1D01*
G02Y1509997I1642J981D01*
G03X1364096Y1510100I-172J102D01*
G01Y1513050D01*
G03X1364068Y1513153I-200J1D01*
G02Y1515115I1642J981D01*
G03X1364096Y1515218I-172J102D01*
G37*
G36*
G01X1485356D02*
Y1516344D01*
G02X1485558Y1516546I202J0D01*
G01X1488378D01*
G02X1488580Y1516344I0J-202D01*
G01Y1515218D01*
G03X1488608Y1515115I200J-1D01*
G02X1488880Y1514134I-1640J-983D01*
G02X1488608Y1513153I-1912J2D01*
G03X1488580Y1513050I172J-102D01*
G01Y1510100D01*
G03X1488608Y1509997I200J-1D01*
G02X1488880Y1509016I-1640J-983D01*
G02X1488608Y1508035I-1912J2D01*
G03X1488580Y1507932I172J-102D01*
G01Y1506806D01*
G02X1488378Y1506604I-202J0D01*
G01X1485558D01*
G02X1485356Y1506806I0J202D01*
G01Y1507932D01*
G03X1485328Y1508035I-200J1D01*
G02X1485056Y1509016I1640J983D01*
G02X1485328Y1509997I1912J-2D01*
G03X1485356Y1510100I-172J102D01*
G01Y1513050D01*
G03X1485328Y1513153I-200J1D01*
G02X1485056Y1514134I1640J983D01*
G02X1485328Y1515115I1912J-2D01*
G03X1485356Y1515218I-172J102D01*
G37*
G36*
G01X1502678D02*
Y1516344D01*
G02X1502881Y1516546I203J-1D01*
G01X1505701D01*
G02X1505904Y1516344I1J-202D01*
G01Y1515218D01*
G03X1505932Y1515115I200J-1D01*
G02Y1513153I-1642J-981D01*
G03X1505904Y1513050I172J-102D01*
G01Y1510100D01*
G03X1505932Y1509997I200J-1D01*
G02Y1508035I-1642J-981D01*
G03X1505904Y1507932I172J-102D01*
G01Y1506806D01*
G02X1505701Y1506604I-203J1D01*
G01X1502881D01*
G02X1502678Y1506806I-1J202D01*
G01Y1507932D01*
G03X1502650Y1508035I-200J1D01*
G02Y1509997I1642J981D01*
G03X1502678Y1510100I-172J102D01*
G01Y1513050D01*
G03X1502650Y1513153I-200J1D01*
G02Y1515115I1642J981D01*
G03X1502678Y1515218I-172J102D01*
G37*
G36*
G01X1520002D02*
Y1516344D01*
G02X1520204Y1516546I202J0D01*
G01X1523024D01*
G02X1523226Y1516344I0J-202D01*
G01Y1515218D01*
G03X1523254Y1515115I200J-1D01*
G02X1523526Y1514134I-1640J-983D01*
G02X1523254Y1513153I-1912J2D01*
G03X1523226Y1513050I172J-102D01*
G01Y1510100D01*
G03X1523254Y1509997I200J-1D01*
G02X1523526Y1509016I-1640J-983D01*
G02X1523254Y1508035I-1912J2D01*
G03X1523226Y1507932I172J-102D01*
G01Y1506806D01*
G02X1523024Y1506604I-202J0D01*
G01X1520204D01*
G02X1520002Y1506806I0J202D01*
G01Y1507932D01*
G03X1519974Y1508035I-200J1D01*
G02X1519702Y1509016I1640J983D01*
G02X1519974Y1509997I1912J-2D01*
G03X1520002Y1510100I-172J102D01*
G01Y1513050D01*
G03X1519974Y1513153I-200J1D01*
G02X1519702Y1514134I1640J983D01*
G02X1519974Y1515115I1912J-2D01*
G03X1520002Y1515218I-172J102D01*
G37*
G36*
G01X1537324D02*
Y1516344D01*
G02X1537527Y1516546I203J-1D01*
G01X1540347D01*
G02X1540550Y1516344I1J-202D01*
G01Y1515218D01*
G03X1540578Y1515115I200J-1D01*
G02Y1513153I-1642J-981D01*
G03X1540550Y1513050I172J-102D01*
G01Y1510100D01*
G03X1540578Y1509997I200J-1D01*
G02Y1508035I-1642J-981D01*
G03X1540550Y1507932I172J-102D01*
G01Y1506806D01*
G02X1540347Y1506604I-203J1D01*
G01X1537527D01*
G02X1537324Y1506806I-1J202D01*
G01Y1507932D01*
G03X1537296Y1508035I-200J1D01*
G02Y1509997I1642J981D01*
G03X1537324Y1510100I-172J102D01*
G01Y1513050D01*
G03X1537296Y1513153I-200J1D01*
G02Y1515115I1642J981D01*
G03X1537324Y1515218I-172J102D01*
G37*
G36*
G01X1130238Y1567187D02*
Y1568313D01*
G02X1130440Y1568516I202J1D01*
G01X1133260D01*
G02X1133462Y1568313I-1J-203D01*
G01Y1567187D01*
G03X1133490Y1567084I200J-1D01*
G02X1133762Y1566103I-1640J-983D01*
G02X1133490Y1565122I-1912J2D01*
G03X1133462Y1565019I172J-102D01*
G01Y1562069D01*
G03X1133490Y1561966I200J-1D01*
G02X1133762Y1560985I-1640J-983D01*
G02X1133490Y1560004I-1912J2D01*
G03X1133462Y1559901I172J-102D01*
G01Y1558775D01*
G02X1133260Y1558572I-202J-1D01*
G01X1130440D01*
G02X1130238Y1558775I1J203D01*
G01Y1559901D01*
G03X1130210Y1560004I-200J1D01*
G02X1129938Y1560985I1640J983D01*
G02X1130210Y1561966I1912J-2D01*
G03X1130238Y1562069I-172J102D01*
G01Y1565019D01*
G03X1130210Y1565122I-200J1D01*
G02X1129938Y1566103I1640J983D01*
G02X1130210Y1567084I1912J-2D01*
G03X1130238Y1567187I-172J102D01*
G37*
G36*
G01X1147560D02*
Y1568313D01*
G02X1147763Y1568516I203J0D01*
G01X1150583D01*
G02X1150786Y1568313I0J-203D01*
G01Y1567187D01*
G03X1150814Y1567084I200J-1D01*
G02Y1565122I-1642J-981D01*
G03X1150786Y1565019I172J-102D01*
G01Y1562069D01*
G03X1150814Y1561966I200J-1D01*
G02Y1560004I-1642J-981D01*
G03X1150786Y1559901I172J-102D01*
G01Y1558775D01*
G02X1150583Y1558572I-203J0D01*
G01X1147763D01*
G02X1147560Y1558775I0J203D01*
G01Y1559901D01*
G03X1147532Y1560004I-200J1D01*
G02Y1561966I1642J981D01*
G03X1147560Y1562069I-172J102D01*
G01Y1565019D01*
G03X1147532Y1565122I-200J1D01*
G02Y1567084I1642J981D01*
G03X1147560Y1567187I-172J102D01*
G37*
G36*
G01X1164884D02*
Y1568313D01*
G02X1165086Y1568516I202J1D01*
G01X1167906D01*
G02X1168108Y1568313I-1J-203D01*
G01Y1567187D01*
G03X1168136Y1567084I200J-1D01*
G02X1168408Y1566103I-1640J-983D01*
G02X1168136Y1565122I-1912J2D01*
G03X1168108Y1565019I172J-102D01*
G01Y1562069D01*
G03X1168136Y1561966I200J-1D01*
G02X1168408Y1560985I-1640J-983D01*
G02X1168136Y1560004I-1912J2D01*
G03X1168108Y1559901I172J-102D01*
G01Y1558775D01*
G02X1167906Y1558572I-202J-1D01*
G01X1165086D01*
G02X1164884Y1558775I1J203D01*
G01Y1559901D01*
G03X1164856Y1560004I-200J1D01*
G02X1164584Y1560985I1640J983D01*
G02X1164856Y1561966I1912J-2D01*
G03X1164884Y1562069I-172J102D01*
G01Y1565019D01*
G03X1164856Y1565122I-200J1D01*
G02X1164584Y1566103I1640J983D01*
G02X1164856Y1567084I1912J-2D01*
G03X1164884Y1567187I-172J102D01*
G37*
G36*
G01X1182206D02*
Y1568313D01*
G02X1182408Y1568516I202J1D01*
G01X1185228D01*
G02X1185430Y1568313I-1J-203D01*
G01Y1567187D01*
G03X1185458Y1567084I200J-1D01*
G02X1185730Y1566103I-1640J-983D01*
G02X1185458Y1565122I-1912J2D01*
G03X1185430Y1565019I172J-102D01*
G01Y1562069D01*
G03X1185458Y1561966I200J-1D01*
G02X1185730Y1560985I-1640J-983D01*
G02X1185458Y1560004I-1912J2D01*
G03X1185430Y1559901I172J-102D01*
G01Y1558775D01*
G02X1185228Y1558572I-202J-1D01*
G01X1182408D01*
G02X1182206Y1558775I1J203D01*
G01Y1559901D01*
G03X1182178Y1560004I-200J1D01*
G02X1181906Y1560985I1640J983D01*
G02X1182178Y1561966I1912J-2D01*
G03X1182206Y1562069I-172J102D01*
G01Y1565019D01*
G03X1182178Y1565122I-200J1D01*
G02X1181906Y1566103I1640J983D01*
G02X1182178Y1567084I1912J-2D01*
G03X1182206Y1567187I-172J102D01*
G37*
G36*
G01X1476694D02*
Y1568313D01*
G02X1476897Y1568516I203J0D01*
G01X1479717D01*
G02X1479920Y1568313I0J-203D01*
G01Y1567187D01*
G03X1479948Y1567084I200J-1D01*
G02Y1565122I-1642J-981D01*
G03X1479920Y1565019I172J-102D01*
G01Y1562069D01*
G03X1479948Y1561966I200J-1D01*
G02Y1560004I-1642J-981D01*
G03X1479920Y1559901I172J-102D01*
G01Y1558775D01*
G02X1479717Y1558572I-203J0D01*
G01X1476897D01*
G02X1476694Y1558775I0J203D01*
G01Y1559901D01*
G03X1476666Y1560004I-200J1D01*
G02Y1561966I1642J981D01*
G03X1476694Y1562069I-172J102D01*
G01Y1565019D01*
G03X1476666Y1565122I-200J1D01*
G02Y1567084I1642J981D01*
G03X1476694Y1567187I-172J102D01*
G37*
G36*
G01X1494018D02*
Y1568313D01*
G02X1494220Y1568516I202J1D01*
G01X1497040D01*
G02X1497242Y1568313I-1J-203D01*
G01Y1567187D01*
G03X1497270Y1567084I200J-1D01*
G02X1497542Y1566103I-1640J-983D01*
G02X1497270Y1565122I-1912J2D01*
G03X1497242Y1565019I172J-102D01*
G01Y1562069D01*
G03X1497270Y1561966I200J-1D01*
G02X1497542Y1560985I-1640J-983D01*
G02X1497270Y1560004I-1912J2D01*
G03X1497242Y1559901I172J-102D01*
G01Y1558775D01*
G02X1497040Y1558572I-202J-1D01*
G01X1494220D01*
G02X1494018Y1558775I1J203D01*
G01Y1559901D01*
G03X1493990Y1560004I-200J1D01*
G02X1493718Y1560985I1640J983D01*
G02X1493990Y1561966I1912J-2D01*
G03X1494018Y1562069I-172J102D01*
G01Y1565019D01*
G03X1493990Y1565122I-200J1D01*
G02X1493718Y1566103I1640J983D01*
G02X1493990Y1567084I1912J-2D01*
G03X1494018Y1567187I-172J102D01*
G37*
G36*
G01X1511340D02*
Y1568313D01*
G02X1511543Y1568516I203J0D01*
G01X1514363D01*
G02X1514566Y1568313I0J-203D01*
G01Y1567187D01*
G03X1514594Y1567084I200J-1D01*
G02Y1565122I-1642J-981D01*
G03X1514566Y1565019I172J-102D01*
G01Y1562069D01*
G03X1514594Y1561966I200J-1D01*
G02Y1560004I-1642J-981D01*
G03X1514566Y1559901I172J-102D01*
G01Y1558775D01*
G02X1514363Y1558572I-203J0D01*
G01X1511543D01*
G02X1511340Y1558775I0J203D01*
G01Y1559901D01*
G03X1511312Y1560004I-200J1D01*
G02Y1561966I1642J981D01*
G03X1511340Y1562069I-172J102D01*
G01Y1565019D01*
G03X1511312Y1565122I-200J1D01*
G02Y1567084I1642J981D01*
G03X1511340Y1567187I-172J102D01*
G37*
G36*
G01X1528662D02*
Y1568313D01*
G02X1528865Y1568516I203J0D01*
G01X1531685D01*
G02X1531888Y1568313I0J-203D01*
G01Y1567187D01*
G03X1531916Y1567084I200J-1D01*
G02Y1565122I-1642J-981D01*
G03X1531888Y1565019I172J-102D01*
G01Y1562069D01*
G03X1531916Y1561966I200J-1D01*
G02Y1560004I-1642J-981D01*
G03X1531888Y1559901I172J-102D01*
G01Y1558775D01*
G02X1531685Y1558572I-203J0D01*
G01X1528865D01*
G02X1528662Y1558775I0J203D01*
G01Y1559901D01*
G03X1528634Y1560004I-200J1D01*
G02Y1561966I1642J981D01*
G03X1528662Y1562069I-172J102D01*
G01Y1565019D01*
G03X1528634Y1565122I-200J1D01*
G02Y1567084I1642J981D01*
G03X1528662Y1567187I-172J102D01*
G37*
G36*
G01X1138898Y1571518D02*
Y1572644D01*
G02X1139101Y1572846I203J-1D01*
G01X1141921D01*
G02X1142124Y1572644I1J-202D01*
G01Y1571518D01*
G03X1142152Y1571415I200J-1D01*
G02Y1569453I-1642J-981D01*
G03X1142124Y1569350I172J-102D01*
G01Y1566399D01*
G03X1142152Y1566296I200J-1D01*
G02Y1564334I-1642J-981D01*
G03X1142124Y1564231I172J-102D01*
G01Y1563106D01*
G02X1141921Y1562904I-203J1D01*
G01X1139101D01*
G02X1138898Y1563106I-1J202D01*
G01Y1564231D01*
G03X1138870Y1564334I-200J1D01*
G02Y1566296I1642J981D01*
G03X1138898Y1566399I-172J102D01*
G01Y1569350D01*
G03X1138870Y1569453I-200J1D01*
G02Y1571415I1642J981D01*
G03X1138898Y1571518I-172J102D01*
G37*
G36*
G01X1156222D02*
Y1572644D01*
G02X1156424Y1572846I202J0D01*
G01X1159244D01*
G02X1159446Y1572644I0J-202D01*
G01Y1571518D01*
G03X1159474Y1571415I200J-1D01*
G02X1159746Y1570434I-1640J-983D01*
G02X1159474Y1569453I-1912J2D01*
G03X1159446Y1569350I172J-102D01*
G01Y1566399D01*
G03X1159474Y1566296I200J-1D01*
G02X1159746Y1565315I-1640J-983D01*
G02X1159474Y1564334I-1912J2D01*
G03X1159446Y1564231I172J-102D01*
G01Y1563106D01*
G02X1159244Y1562904I-202J0D01*
G01X1156424D01*
G02X1156222Y1563106I0J202D01*
G01Y1564231D01*
G03X1156194Y1564334I-200J1D01*
G02X1155922Y1565315I1640J983D01*
G02X1156194Y1566296I1912J-2D01*
G03X1156222Y1566399I-172J102D01*
G01Y1569350D01*
G03X1156194Y1569453I-200J1D01*
G02X1155922Y1570434I1640J983D01*
G02X1156194Y1571415I1912J-2D01*
G03X1156222Y1571518I-172J102D01*
G37*
G36*
G01X1173544D02*
Y1572644D01*
G02X1173747Y1572846I203J-1D01*
G01X1176567D01*
G02X1176770Y1572644I1J-202D01*
G01Y1571518D01*
G03X1176798Y1571415I200J-1D01*
G02Y1569453I-1642J-981D01*
G03X1176770Y1569350I172J-102D01*
G01Y1566399D01*
G03X1176798Y1566296I200J-1D01*
G02Y1564334I-1642J-981D01*
G03X1176770Y1564231I172J-102D01*
G01Y1563106D01*
G02X1176567Y1562904I-203J1D01*
G01X1173747D01*
G02X1173544Y1563106I-1J202D01*
G01Y1564231D01*
G03X1173516Y1564334I-200J1D01*
G02Y1566296I1642J981D01*
G03X1173544Y1566399I-172J102D01*
G01Y1569350D01*
G03X1173516Y1569453I-200J1D01*
G02Y1571415I1642J981D01*
G03X1173544Y1571518I-172J102D01*
G37*
G36*
G01X1190868D02*
Y1572644D01*
G02X1191070Y1572846I202J0D01*
G01X1193890D01*
G02X1194092Y1572644I0J-202D01*
G01Y1571518D01*
G03X1194120Y1571415I200J-1D01*
G02X1194392Y1570434I-1640J-983D01*
G02X1194120Y1569453I-1912J2D01*
G03X1194092Y1569350I172J-102D01*
G01Y1566399D01*
G03X1194120Y1566296I200J-1D01*
G02X1194392Y1565315I-1640J-983D01*
G02X1194120Y1564334I-1912J2D01*
G03X1194092Y1564231I172J-102D01*
G01Y1563106D01*
G02X1193890Y1562904I-202J0D01*
G01X1191070D01*
G02X1190868Y1563106I0J202D01*
G01Y1564231D01*
G03X1190840Y1564334I-200J1D01*
G02X1190568Y1565315I1640J983D01*
G02X1190840Y1566296I1912J-2D01*
G03X1190868Y1566399I-172J102D01*
G01Y1569350D01*
G03X1190840Y1569453I-200J1D01*
G02X1190568Y1570434I1640J983D01*
G02X1190840Y1571415I1912J-2D01*
G03X1190868Y1571518I-172J102D01*
G37*
G36*
G01X1485356D02*
Y1572644D01*
G02X1485558Y1572846I202J0D01*
G01X1488378D01*
G02X1488580Y1572644I0J-202D01*
G01Y1571518D01*
G03X1488608Y1571415I200J-1D01*
G02X1488880Y1570434I-1640J-983D01*
G02X1488608Y1569453I-1912J2D01*
G03X1488580Y1569350I172J-102D01*
G01Y1566399D01*
G03X1488608Y1566296I200J-1D01*
G02X1488880Y1565315I-1640J-983D01*
G02X1488608Y1564334I-1912J2D01*
G03X1488580Y1564231I172J-102D01*
G01Y1563106D01*
G02X1488378Y1562904I-202J0D01*
G01X1485558D01*
G02X1485356Y1563106I0J202D01*
G01Y1564231D01*
G03X1485328Y1564334I-200J1D01*
G02X1485056Y1565315I1640J983D01*
G02X1485328Y1566296I1912J-2D01*
G03X1485356Y1566399I-172J102D01*
G01Y1569350D01*
G03X1485328Y1569453I-200J1D01*
G02X1485056Y1570434I1640J983D01*
G02X1485328Y1571415I1912J-2D01*
G03X1485356Y1571518I-172J102D01*
G37*
G36*
G01X1502678D02*
Y1572644D01*
G02X1502881Y1572846I203J-1D01*
G01X1505701D01*
G02X1505904Y1572644I1J-202D01*
G01Y1571518D01*
G03X1505932Y1571415I200J-1D01*
G02Y1569453I-1642J-981D01*
G03X1505904Y1569350I172J-102D01*
G01Y1566399D01*
G03X1505932Y1566296I200J-1D01*
G02Y1564334I-1642J-981D01*
G03X1505904Y1564231I172J-102D01*
G01Y1563106D01*
G02X1505701Y1562904I-203J1D01*
G01X1502881D01*
G02X1502678Y1563106I-1J202D01*
G01Y1564231D01*
G03X1502650Y1564334I-200J1D01*
G02Y1566296I1642J981D01*
G03X1502678Y1566399I-172J102D01*
G01Y1569350D01*
G03X1502650Y1569453I-200J1D01*
G02Y1571415I1642J981D01*
G03X1502678Y1571518I-172J102D01*
G37*
G36*
G01X1520002D02*
Y1572644D01*
G02X1520204Y1572846I202J0D01*
G01X1523024D01*
G02X1523226Y1572644I0J-202D01*
G01Y1571518D01*
G03X1523254Y1571415I200J-1D01*
G02X1523526Y1570434I-1640J-983D01*
G02X1523254Y1569453I-1912J2D01*
G03X1523226Y1569350I172J-102D01*
G01Y1566399D01*
G03X1523254Y1566296I200J-1D01*
G02X1523526Y1565315I-1640J-983D01*
G02X1523254Y1564334I-1912J2D01*
G03X1523226Y1564231I172J-102D01*
G01Y1563106D01*
G02X1523024Y1562904I-202J0D01*
G01X1520204D01*
G02X1520002Y1563106I0J202D01*
G01Y1564231D01*
G03X1519974Y1564334I-200J1D01*
G02X1519702Y1565315I1640J983D01*
G02X1519974Y1566296I1912J-2D01*
G03X1520002Y1566399I-172J102D01*
G01Y1569350D01*
G03X1519974Y1569453I-200J1D01*
G02X1519702Y1570434I1640J983D01*
G02X1519974Y1571415I1912J-2D01*
G03X1520002Y1571518I-172J102D01*
G37*
G36*
G01X1537324D02*
Y1572644D01*
G02X1537527Y1572846I203J-1D01*
G01X1540347D01*
G02X1540550Y1572644I1J-202D01*
G01Y1571518D01*
G03X1540578Y1571415I200J-1D01*
G02Y1569453I-1642J-981D01*
G03X1540550Y1569350I172J-102D01*
G01Y1566399D01*
G03X1540578Y1566296I200J-1D01*
G02Y1564334I-1642J-981D01*
G03X1540550Y1564231I172J-102D01*
G01Y1563106D01*
G02X1540347Y1562904I-203J1D01*
G01X1537527D01*
G02X1537324Y1563106I-1J202D01*
G01Y1564231D01*
G03X1537296Y1564334I-200J1D01*
G02Y1566296I1642J981D01*
G03X1537324Y1566399I-172J102D01*
G01Y1569350D01*
G03X1537296Y1569453I-200J1D01*
G02Y1571415I1642J981D01*
G03X1537324Y1571518I-172J102D01*
G37*
G36*
G01X1130238Y1582541D02*
Y1583667D01*
G02X1130440Y1583870I202J1D01*
G01X1133260D01*
G02X1133462Y1583667I-1J-203D01*
G01Y1582541D01*
G03X1133490Y1582438I200J-1D01*
G02X1133762Y1581457I-1640J-983D01*
G02X1133490Y1580476I-1912J2D01*
G03X1133462Y1580373I172J-102D01*
G01Y1577423D01*
G03X1133490Y1577320I200J-1D01*
G02X1133762Y1576339I-1640J-983D01*
G02X1133490Y1575358I-1912J2D01*
G03X1133462Y1575255I172J-102D01*
G01Y1574129D01*
G02X1133260Y1573926I-202J-1D01*
G01X1130440D01*
G02X1130238Y1574129I1J203D01*
G01Y1575255D01*
G03X1130210Y1575358I-200J1D01*
G02X1129938Y1576339I1640J983D01*
G02X1130210Y1577320I1912J-2D01*
G03X1130238Y1577423I-172J102D01*
G01Y1580373D01*
G03X1130210Y1580476I-200J1D01*
G02X1129938Y1581457I1640J983D01*
G02X1130210Y1582438I1912J-2D01*
G03X1130238Y1582541I-172J102D01*
G37*
G36*
G01X1147560D02*
Y1583667D01*
G02X1147763Y1583870I203J0D01*
G01X1150583D01*
G02X1150786Y1583667I0J-203D01*
G01Y1582541D01*
G03X1150814Y1582438I200J-1D01*
G02Y1580476I-1642J-981D01*
G03X1150786Y1580373I172J-102D01*
G01Y1577423D01*
G03X1150814Y1577320I200J-1D01*
G02Y1575358I-1642J-981D01*
G03X1150786Y1575255I172J-102D01*
G01Y1574129D01*
G02X1150583Y1573926I-203J0D01*
G01X1147763D01*
G02X1147560Y1574129I0J203D01*
G01Y1575255D01*
G03X1147532Y1575358I-200J1D01*
G02Y1577320I1642J981D01*
G03X1147560Y1577423I-172J102D01*
G01Y1580373D01*
G03X1147532Y1580476I-200J1D01*
G02Y1582438I1642J981D01*
G03X1147560Y1582541I-172J102D01*
G37*
G36*
G01X1164884D02*
Y1583667D01*
G02X1165086Y1583870I202J1D01*
G01X1167906D01*
G02X1168108Y1583667I-1J-203D01*
G01Y1582541D01*
G03X1168136Y1582438I200J-1D01*
G02X1168408Y1581457I-1640J-983D01*
G02X1168136Y1580476I-1912J2D01*
G03X1168108Y1580373I172J-102D01*
G01Y1577423D01*
G03X1168136Y1577320I200J-1D01*
G02X1168408Y1576339I-1640J-983D01*
G02X1168136Y1575358I-1912J2D01*
G03X1168108Y1575255I172J-102D01*
G01Y1574129D01*
G02X1167906Y1573926I-202J-1D01*
G01X1165086D01*
G02X1164884Y1574129I1J203D01*
G01Y1575255D01*
G03X1164856Y1575358I-200J1D01*
G02X1164584Y1576339I1640J983D01*
G02X1164856Y1577320I1912J-2D01*
G03X1164884Y1577423I-172J102D01*
G01Y1580373D01*
G03X1164856Y1580476I-200J1D01*
G02X1164584Y1581457I1640J983D01*
G02X1164856Y1582438I1912J-2D01*
G03X1164884Y1582541I-172J102D01*
G37*
G36*
G01X1182206D02*
Y1583667D01*
G02X1182408Y1583870I202J1D01*
G01X1185228D01*
G02X1185430Y1583667I-1J-203D01*
G01Y1582541D01*
G03X1185458Y1582438I200J-1D01*
G02X1185730Y1581457I-1640J-983D01*
G02X1185458Y1580476I-1912J2D01*
G03X1185430Y1580373I172J-102D01*
G01Y1577423D01*
G03X1185458Y1577320I200J-1D01*
G02X1185730Y1576339I-1640J-983D01*
G02X1185458Y1575358I-1912J2D01*
G03X1185430Y1575255I172J-102D01*
G01Y1574129D01*
G02X1185228Y1573926I-202J-1D01*
G01X1182408D01*
G02X1182206Y1574129I1J203D01*
G01Y1575255D01*
G03X1182178Y1575358I-200J1D01*
G02X1181906Y1576339I1640J983D01*
G02X1182178Y1577320I1912J-2D01*
G03X1182206Y1577423I-172J102D01*
G01Y1580373D01*
G03X1182178Y1580476I-200J1D01*
G02X1181906Y1581457I1640J983D01*
G02X1182178Y1582438I1912J-2D01*
G03X1182206Y1582541I-172J102D01*
G37*
G36*
G01X1303466D02*
Y1583667D01*
G02X1303669Y1583870I203J0D01*
G01X1306489D01*
G02X1306692Y1583667I0J-203D01*
G01Y1582541D01*
G03X1306720Y1582438I200J-1D01*
G02Y1580476I-1642J-981D01*
G03X1306692Y1580373I172J-102D01*
G01Y1577423D01*
G03X1306720Y1577320I200J-1D01*
G02Y1575358I-1642J-981D01*
G03X1306692Y1575255I172J-102D01*
G01Y1574129D01*
G02X1306489Y1573926I-203J0D01*
G01X1303669D01*
G02X1303466Y1574129I0J203D01*
G01Y1575255D01*
G03X1303438Y1575358I-200J1D01*
G02Y1577320I1642J981D01*
G03X1303466Y1577423I-172J102D01*
G01Y1580373D01*
G03X1303438Y1580476I-200J1D01*
G02Y1582438I1642J981D01*
G03X1303466Y1582541I-172J102D01*
G37*
G36*
G01X1320790D02*
Y1583667D01*
G02X1320992Y1583870I202J1D01*
G01X1323812D01*
G02X1324014Y1583667I-1J-203D01*
G01Y1582541D01*
G03X1324042Y1582438I200J-1D01*
G02X1324314Y1581457I-1640J-983D01*
G02X1324042Y1580476I-1912J2D01*
G03X1324014Y1580373I172J-102D01*
G01Y1577423D01*
G03X1324042Y1577320I200J-1D01*
G02X1324314Y1576339I-1640J-983D01*
G02X1324042Y1575358I-1912J2D01*
G03X1324014Y1575255I172J-102D01*
G01Y1574129D01*
G02X1323812Y1573926I-202J-1D01*
G01X1320992D01*
G02X1320790Y1574129I1J203D01*
G01Y1575255D01*
G03X1320762Y1575358I-200J1D01*
G02X1320490Y1576339I1640J983D01*
G02X1320762Y1577320I1912J-2D01*
G03X1320790Y1577423I-172J102D01*
G01Y1580373D01*
G03X1320762Y1580476I-200J1D01*
G02X1320490Y1581457I1640J983D01*
G02X1320762Y1582438I1912J-2D01*
G03X1320790Y1582541I-172J102D01*
G37*
G36*
G01X1338112D02*
Y1583667D01*
G02X1338315Y1583870I203J0D01*
G01X1341135D01*
G02X1341338Y1583667I0J-203D01*
G01Y1582541D01*
G03X1341366Y1582438I200J-1D01*
G02Y1580476I-1642J-981D01*
G03X1341338Y1580373I172J-102D01*
G01Y1577423D01*
G03X1341366Y1577320I200J-1D01*
G02Y1575358I-1642J-981D01*
G03X1341338Y1575255I172J-102D01*
G01Y1574129D01*
G02X1341135Y1573926I-203J0D01*
G01X1338315D01*
G02X1338112Y1574129I0J203D01*
G01Y1575255D01*
G03X1338084Y1575358I-200J1D01*
G02Y1577320I1642J981D01*
G03X1338112Y1577423I-172J102D01*
G01Y1580373D01*
G03X1338084Y1580476I-200J1D01*
G02Y1582438I1642J981D01*
G03X1338112Y1582541I-172J102D01*
G37*
G36*
G01X1355434D02*
Y1583667D01*
G02X1355637Y1583870I203J0D01*
G01X1358457D01*
G02X1358660Y1583667I0J-203D01*
G01Y1582541D01*
G03X1358688Y1582438I200J-1D01*
G02Y1580476I-1642J-981D01*
G03X1358660Y1580373I172J-102D01*
G01Y1577423D01*
G03X1358688Y1577320I200J-1D01*
G02Y1575358I-1642J-981D01*
G03X1358660Y1575255I172J-102D01*
G01Y1574129D01*
G02X1358457Y1573926I-203J0D01*
G01X1355637D01*
G02X1355434Y1574129I0J203D01*
G01Y1575255D01*
G03X1355406Y1575358I-200J1D01*
G02Y1577320I1642J981D01*
G03X1355434Y1577423I-172J102D01*
G01Y1580373D01*
G03X1355406Y1580476I-200J1D01*
G02Y1582438I1642J981D01*
G03X1355434Y1582541I-172J102D01*
G37*
G36*
G01X1476694D02*
Y1583667D01*
G02X1476897Y1583870I203J0D01*
G01X1479717D01*
G02X1479920Y1583667I0J-203D01*
G01Y1582541D01*
G03X1479948Y1582438I200J-1D01*
G02Y1580476I-1642J-981D01*
G03X1479920Y1580373I172J-102D01*
G01Y1577423D01*
G03X1479948Y1577320I200J-1D01*
G02Y1575358I-1642J-981D01*
G03X1479920Y1575255I172J-102D01*
G01Y1574129D01*
G02X1479717Y1573926I-203J0D01*
G01X1476897D01*
G02X1476694Y1574129I0J203D01*
G01Y1575255D01*
G03X1476666Y1575358I-200J1D01*
G02Y1577320I1642J981D01*
G03X1476694Y1577423I-172J102D01*
G01Y1580373D01*
G03X1476666Y1580476I-200J1D01*
G02Y1582438I1642J981D01*
G03X1476694Y1582541I-172J102D01*
G37*
G36*
G01X1494018D02*
Y1583667D01*
G02X1494220Y1583870I202J1D01*
G01X1497040D01*
G02X1497242Y1583667I-1J-203D01*
G01Y1582541D01*
G03X1497270Y1582438I200J-1D01*
G02X1497542Y1581457I-1640J-983D01*
G02X1497270Y1580476I-1912J2D01*
G03X1497242Y1580373I172J-102D01*
G01Y1577423D01*
G03X1497270Y1577320I200J-1D01*
G02X1497542Y1576339I-1640J-983D01*
G02X1497270Y1575358I-1912J2D01*
G03X1497242Y1575255I172J-102D01*
G01Y1574129D01*
G02X1497040Y1573926I-202J-1D01*
G01X1494220D01*
G02X1494018Y1574129I1J203D01*
G01Y1575255D01*
G03X1493990Y1575358I-200J1D01*
G02X1493718Y1576339I1640J983D01*
G02X1493990Y1577320I1912J-2D01*
G03X1494018Y1577423I-172J102D01*
G01Y1580373D01*
G03X1493990Y1580476I-200J1D01*
G02X1493718Y1581457I1640J983D01*
G02X1493990Y1582438I1912J-2D01*
G03X1494018Y1582541I-172J102D01*
G37*
G36*
G01X1511340D02*
Y1583667D01*
G02X1511543Y1583870I203J0D01*
G01X1514363D01*
G02X1514566Y1583667I0J-203D01*
G01Y1582541D01*
G03X1514594Y1582438I200J-1D01*
G02Y1580476I-1642J-981D01*
G03X1514566Y1580373I172J-102D01*
G01Y1577423D01*
G03X1514594Y1577320I200J-1D01*
G02Y1575358I-1642J-981D01*
G03X1514566Y1575255I172J-102D01*
G01Y1574129D01*
G02X1514363Y1573926I-203J0D01*
G01X1511543D01*
G02X1511340Y1574129I0J203D01*
G01Y1575255D01*
G03X1511312Y1575358I-200J1D01*
G02Y1577320I1642J981D01*
G03X1511340Y1577423I-172J102D01*
G01Y1580373D01*
G03X1511312Y1580476I-200J1D01*
G02Y1582438I1642J981D01*
G03X1511340Y1582541I-172J102D01*
G37*
G36*
G01X1528662D02*
Y1583667D01*
G02X1528865Y1583870I203J0D01*
G01X1531685D01*
G02X1531888Y1583667I0J-203D01*
G01Y1582541D01*
G03X1531916Y1582438I200J-1D01*
G02Y1580476I-1642J-981D01*
G03X1531888Y1580373I172J-102D01*
G01Y1577423D01*
G03X1531916Y1577320I200J-1D01*
G02Y1575358I-1642J-981D01*
G03X1531888Y1575255I172J-102D01*
G01Y1574129D01*
G02X1531685Y1573926I-203J0D01*
G01X1528865D01*
G02X1528662Y1574129I0J203D01*
G01Y1575255D01*
G03X1528634Y1575358I-200J1D01*
G02Y1577320I1642J981D01*
G03X1528662Y1577423I-172J102D01*
G01Y1580373D01*
G03X1528634Y1580476I-200J1D01*
G02Y1582438I1642J981D01*
G03X1528662Y1582541I-172J102D01*
G37*
G36*
G01X1138898Y1586872D02*
Y1587998D01*
G02X1139101Y1588200I203J-1D01*
G01X1141921D01*
G02X1142124Y1587998I1J-202D01*
G01Y1586872D01*
G03X1142152Y1586769I200J-1D01*
G02Y1584807I-1642J-981D01*
G03X1142124Y1584704I172J-102D01*
G01Y1581754D01*
G03X1142152Y1581651I200J-1D01*
G02Y1579689I-1642J-981D01*
G03X1142124Y1579586I172J-102D01*
G01Y1578460D01*
G02X1141921Y1578258I-203J1D01*
G01X1139101D01*
G02X1138898Y1578460I-1J202D01*
G01Y1579586D01*
G03X1138870Y1579689I-200J1D01*
G02Y1581651I1642J981D01*
G03X1138898Y1581754I-172J102D01*
G01Y1584704D01*
G03X1138870Y1584807I-200J1D01*
G02Y1586769I1642J981D01*
G03X1138898Y1586872I-172J102D01*
G37*
G36*
G01X1156222D02*
Y1587998D01*
G02X1156424Y1588200I202J0D01*
G01X1159244D01*
G02X1159446Y1587998I0J-202D01*
G01Y1586872D01*
G03X1159474Y1586769I200J-1D01*
G02X1159746Y1585788I-1640J-983D01*
G02X1159474Y1584807I-1912J2D01*
G03X1159446Y1584704I172J-102D01*
G01Y1581754D01*
G03X1159474Y1581651I200J-1D01*
G02X1159746Y1580670I-1640J-983D01*
G02X1159474Y1579689I-1912J2D01*
G03X1159446Y1579586I172J-102D01*
G01Y1578460D01*
G02X1159244Y1578258I-202J0D01*
G01X1156424D01*
G02X1156222Y1578460I0J202D01*
G01Y1579586D01*
G03X1156194Y1579689I-200J1D01*
G02X1155922Y1580670I1640J983D01*
G02X1156194Y1581651I1912J-2D01*
G03X1156222Y1581754I-172J102D01*
G01Y1584704D01*
G03X1156194Y1584807I-200J1D01*
G02X1155922Y1585788I1640J983D01*
G02X1156194Y1586769I1912J-2D01*
G03X1156222Y1586872I-172J102D01*
G37*
G36*
G01X1173544D02*
Y1587998D01*
G02X1173747Y1588200I203J-1D01*
G01X1176567D01*
G02X1176770Y1587998I1J-202D01*
G01Y1586872D01*
G03X1176798Y1586769I200J-1D01*
G02Y1584807I-1642J-981D01*
G03X1176770Y1584704I172J-102D01*
G01Y1581754D01*
G03X1176798Y1581651I200J-1D01*
G02Y1579689I-1642J-981D01*
G03X1176770Y1579586I172J-102D01*
G01Y1578460D01*
G02X1176567Y1578258I-203J1D01*
G01X1173747D01*
G02X1173544Y1578460I-1J202D01*
G01Y1579586D01*
G03X1173516Y1579689I-200J1D01*
G02Y1581651I1642J981D01*
G03X1173544Y1581754I-172J102D01*
G01Y1584704D01*
G03X1173516Y1584807I-200J1D01*
G02Y1586769I1642J981D01*
G03X1173544Y1586872I-172J102D01*
G37*
G36*
G01X1190868D02*
Y1587998D01*
G02X1191070Y1588200I202J0D01*
G01X1193890D01*
G02X1194092Y1587998I0J-202D01*
G01Y1586872D01*
G03X1194120Y1586769I200J-1D01*
G02X1194392Y1585788I-1640J-983D01*
G02X1194120Y1584807I-1912J2D01*
G03X1194092Y1584704I172J-102D01*
G01Y1581754D01*
G03X1194120Y1581651I200J-1D01*
G02X1194392Y1580670I-1640J-983D01*
G02X1194120Y1579689I-1912J2D01*
G03X1194092Y1579586I172J-102D01*
G01Y1578460D01*
G02X1193890Y1578258I-202J0D01*
G01X1191070D01*
G02X1190868Y1578460I0J202D01*
G01Y1579586D01*
G03X1190840Y1579689I-200J1D01*
G02X1190568Y1580670I1640J983D01*
G02X1190840Y1581651I1912J-2D01*
G03X1190868Y1581754I-172J102D01*
G01Y1584704D01*
G03X1190840Y1584807I-200J1D01*
G02X1190568Y1585788I1640J983D01*
G02X1190840Y1586769I1912J-2D01*
G03X1190868Y1586872I-172J102D01*
G37*
G36*
G01X1312128D02*
Y1587998D01*
G02X1312330Y1588200I202J0D01*
G01X1315150D01*
G02X1315352Y1587998I0J-202D01*
G01Y1586872D01*
G03X1315380Y1586769I200J-1D01*
G02X1315652Y1585788I-1640J-983D01*
G02X1315380Y1584807I-1912J2D01*
G03X1315352Y1584704I172J-102D01*
G01Y1581754D01*
G03X1315380Y1581651I200J-1D01*
G02X1315652Y1580670I-1640J-983D01*
G02X1315380Y1579689I-1912J2D01*
G03X1315352Y1579586I172J-102D01*
G01Y1578460D01*
G02X1315150Y1578258I-202J0D01*
G01X1312330D01*
G02X1312128Y1578460I0J202D01*
G01Y1579586D01*
G03X1312100Y1579689I-200J1D01*
G02X1311828Y1580670I1640J983D01*
G02X1312100Y1581651I1912J-2D01*
G03X1312128Y1581754I-172J102D01*
G01Y1584704D01*
G03X1312100Y1584807I-200J1D01*
G02X1311828Y1585788I1640J983D01*
G02X1312100Y1586769I1912J-2D01*
G03X1312128Y1586872I-172J102D01*
G37*
G36*
G01X1329450D02*
Y1587998D01*
G02X1329653Y1588200I203J-1D01*
G01X1332473D01*
G02X1332676Y1587998I1J-202D01*
G01Y1586872D01*
G03X1332704Y1586769I200J-1D01*
G02Y1584807I-1642J-981D01*
G03X1332676Y1584704I172J-102D01*
G01Y1581754D01*
G03X1332704Y1581651I200J-1D01*
G02Y1579689I-1642J-981D01*
G03X1332676Y1579586I172J-102D01*
G01Y1578460D01*
G02X1332473Y1578258I-203J1D01*
G01X1329653D01*
G02X1329450Y1578460I-1J202D01*
G01Y1579586D01*
G03X1329422Y1579689I-200J1D01*
G02Y1581651I1642J981D01*
G03X1329450Y1581754I-172J102D01*
G01Y1584704D01*
G03X1329422Y1584807I-200J1D01*
G02Y1586769I1642J981D01*
G03X1329450Y1586872I-172J102D01*
G37*
G36*
G01X1346774D02*
Y1587998D01*
G02X1346976Y1588200I202J0D01*
G01X1349796D01*
G02X1349998Y1587998I0J-202D01*
G01Y1586872D01*
G03X1350026Y1586769I200J-1D01*
G02X1350298Y1585788I-1640J-983D01*
G02X1350026Y1584807I-1912J2D01*
G03X1349998Y1584704I172J-102D01*
G01Y1581754D01*
G03X1350026Y1581651I200J-1D01*
G02X1350298Y1580670I-1640J-983D01*
G02X1350026Y1579689I-1912J2D01*
G03X1349998Y1579586I172J-102D01*
G01Y1578460D01*
G02X1349796Y1578258I-202J0D01*
G01X1346976D01*
G02X1346774Y1578460I0J202D01*
G01Y1579586D01*
G03X1346746Y1579689I-200J1D01*
G02X1346474Y1580670I1640J983D01*
G02X1346746Y1581651I1912J-2D01*
G03X1346774Y1581754I-172J102D01*
G01Y1584704D01*
G03X1346746Y1584807I-200J1D01*
G02X1346474Y1585788I1640J983D01*
G02X1346746Y1586769I1912J-2D01*
G03X1346774Y1586872I-172J102D01*
G37*
G36*
G01X1364096D02*
Y1587998D01*
G02X1364299Y1588200I203J-1D01*
G01X1367119D01*
G02X1367322Y1587998I1J-202D01*
G01Y1586872D01*
G03X1367350Y1586769I200J-1D01*
G02Y1584807I-1642J-981D01*
G03X1367322Y1584704I172J-102D01*
G01Y1581754D01*
G03X1367350Y1581651I200J-1D01*
G02Y1579689I-1642J-981D01*
G03X1367322Y1579586I172J-102D01*
G01Y1578460D01*
G02X1367119Y1578258I-203J1D01*
G01X1364299D01*
G02X1364096Y1578460I-1J202D01*
G01Y1579586D01*
G03X1364068Y1579689I-200J1D01*
G02Y1581651I1642J981D01*
G03X1364096Y1581754I-172J102D01*
G01Y1584704D01*
G03X1364068Y1584807I-200J1D01*
G02Y1586769I1642J981D01*
G03X1364096Y1586872I-172J102D01*
G37*
G36*
G01X1485356D02*
Y1587998D01*
G02X1485558Y1588200I202J0D01*
G01X1488378D01*
G02X1488580Y1587998I0J-202D01*
G01Y1586872D01*
G03X1488608Y1586769I200J-1D01*
G02X1488880Y1585788I-1640J-983D01*
G02X1488608Y1584807I-1912J2D01*
G03X1488580Y1584704I172J-102D01*
G01Y1581754D01*
G03X1488608Y1581651I200J-1D01*
G02X1488880Y1580670I-1640J-983D01*
G02X1488608Y1579689I-1912J2D01*
G03X1488580Y1579586I172J-102D01*
G01Y1578460D01*
G02X1488378Y1578258I-202J0D01*
G01X1485558D01*
G02X1485356Y1578460I0J202D01*
G01Y1579586D01*
G03X1485328Y1579689I-200J1D01*
G02X1485056Y1580670I1640J983D01*
G02X1485328Y1581651I1912J-2D01*
G03X1485356Y1581754I-172J102D01*
G01Y1584704D01*
G03X1485328Y1584807I-200J1D01*
G02X1485056Y1585788I1640J983D01*
G02X1485328Y1586769I1912J-2D01*
G03X1485356Y1586872I-172J102D01*
G37*
G36*
G01X1502678D02*
Y1587998D01*
G02X1502881Y1588200I203J-1D01*
G01X1505701D01*
G02X1505904Y1587998I1J-202D01*
G01Y1586872D01*
G03X1505932Y1586769I200J-1D01*
G02Y1584807I-1642J-981D01*
G03X1505904Y1584704I172J-102D01*
G01Y1581754D01*
G03X1505932Y1581651I200J-1D01*
G02Y1579689I-1642J-981D01*
G03X1505904Y1579586I172J-102D01*
G01Y1578460D01*
G02X1505701Y1578258I-203J1D01*
G01X1502881D01*
G02X1502678Y1578460I-1J202D01*
G01Y1579586D01*
G03X1502650Y1579689I-200J1D01*
G02Y1581651I1642J981D01*
G03X1502678Y1581754I-172J102D01*
G01Y1584704D01*
G03X1502650Y1584807I-200J1D01*
G02Y1586769I1642J981D01*
G03X1502678Y1586872I-172J102D01*
G37*
G36*
G01X1520002D02*
Y1587998D01*
G02X1520204Y1588200I202J0D01*
G01X1523024D01*
G02X1523226Y1587998I0J-202D01*
G01Y1586872D01*
G03X1523254Y1586769I200J-1D01*
G02X1523526Y1585788I-1640J-983D01*
G02X1523254Y1584807I-1912J2D01*
G03X1523226Y1584704I172J-102D01*
G01Y1581754D01*
G03X1523254Y1581651I200J-1D01*
G02X1523526Y1580670I-1640J-983D01*
G02X1523254Y1579689I-1912J2D01*
G03X1523226Y1579586I172J-102D01*
G01Y1578460D01*
G02X1523024Y1578258I-202J0D01*
G01X1520204D01*
G02X1520002Y1578460I0J202D01*
G01Y1579586D01*
G03X1519974Y1579689I-200J1D01*
G02X1519702Y1580670I1640J983D01*
G02X1519974Y1581651I1912J-2D01*
G03X1520002Y1581754I-172J102D01*
G01Y1584704D01*
G03X1519974Y1584807I-200J1D01*
G02X1519702Y1585788I1640J983D01*
G02X1519974Y1586769I1912J-2D01*
G03X1520002Y1586872I-172J102D01*
G37*
G36*
G01X1537324D02*
Y1587998D01*
G02X1537527Y1588200I203J-1D01*
G01X1540347D01*
G02X1540550Y1587998I1J-202D01*
G01Y1586872D01*
G03X1540578Y1586769I200J-1D01*
G02Y1584807I-1642J-981D01*
G03X1540550Y1584704I172J-102D01*
G01Y1581754D01*
G03X1540578Y1581651I200J-1D01*
G02Y1579689I-1642J-981D01*
G03X1540550Y1579586I172J-102D01*
G01Y1578460D01*
G02X1540347Y1578258I-203J1D01*
G01X1537527D01*
G02X1537324Y1578460I-1J202D01*
G01Y1579586D01*
G03X1537296Y1579689I-200J1D01*
G02Y1581651I1642J981D01*
G03X1537324Y1581754I-172J102D01*
G01Y1584704D01*
G03X1537296Y1584807I-200J1D01*
G02Y1586769I1642J981D01*
G03X1537324Y1586872I-172J102D01*
G37*
G36*
G01X1130238Y1597895D02*
Y1599021D01*
G02X1130440Y1599224I202J1D01*
G01X1133260D01*
G02X1133462Y1599021I-1J-203D01*
G01Y1597895D01*
G03X1133490Y1597792I200J-1D01*
G02X1133762Y1596811I-1640J-983D01*
G02X1133490Y1595830I-1912J2D01*
G03X1133462Y1595727I172J-102D01*
G01Y1592777D01*
G03X1133490Y1592674I200J-1D01*
G02X1133762Y1591693I-1640J-983D01*
G02X1133490Y1590712I-1912J2D01*
G03X1133462Y1590609I172J-102D01*
G01Y1589483D01*
G02X1133260Y1589280I-202J-1D01*
G01X1130440D01*
G02X1130238Y1589483I1J203D01*
G01Y1590609D01*
G03X1130210Y1590712I-200J1D01*
G02X1129938Y1591693I1640J983D01*
G02X1130210Y1592674I1912J-2D01*
G03X1130238Y1592777I-172J102D01*
G01Y1595727D01*
G03X1130210Y1595830I-200J1D01*
G02X1129938Y1596811I1640J983D01*
G02X1130210Y1597792I1912J-2D01*
G03X1130238Y1597895I-172J102D01*
G37*
G36*
G01X1147560D02*
Y1599021D01*
G02X1147763Y1599224I203J0D01*
G01X1150583D01*
G02X1150786Y1599021I0J-203D01*
G01Y1597895D01*
G03X1150814Y1597792I200J-1D01*
G02Y1595830I-1642J-981D01*
G03X1150786Y1595727I172J-102D01*
G01Y1592777D01*
G03X1150814Y1592674I200J-1D01*
G02Y1590712I-1642J-981D01*
G03X1150786Y1590609I172J-102D01*
G01Y1589483D01*
G02X1150583Y1589280I-203J0D01*
G01X1147763D01*
G02X1147560Y1589483I0J203D01*
G01Y1590609D01*
G03X1147532Y1590712I-200J1D01*
G02Y1592674I1642J981D01*
G03X1147560Y1592777I-172J102D01*
G01Y1595727D01*
G03X1147532Y1595830I-200J1D01*
G02Y1597792I1642J981D01*
G03X1147560Y1597895I-172J102D01*
G37*
G36*
G01X1164884D02*
Y1599021D01*
G02X1165086Y1599224I202J1D01*
G01X1167906D01*
G02X1168108Y1599021I-1J-203D01*
G01Y1597895D01*
G03X1168136Y1597792I200J-1D01*
G02X1168408Y1596811I-1640J-983D01*
G02X1168136Y1595830I-1912J2D01*
G03X1168108Y1595727I172J-102D01*
G01Y1592777D01*
G03X1168136Y1592674I200J-1D01*
G02X1168408Y1591693I-1640J-983D01*
G02X1168136Y1590712I-1912J2D01*
G03X1168108Y1590609I172J-102D01*
G01Y1589483D01*
G02X1167906Y1589280I-202J-1D01*
G01X1165086D01*
G02X1164884Y1589483I1J203D01*
G01Y1590609D01*
G03X1164856Y1590712I-200J1D01*
G02X1164584Y1591693I1640J983D01*
G02X1164856Y1592674I1912J-2D01*
G03X1164884Y1592777I-172J102D01*
G01Y1595727D01*
G03X1164856Y1595830I-200J1D01*
G02X1164584Y1596811I1640J983D01*
G02X1164856Y1597792I1912J-2D01*
G03X1164884Y1597895I-172J102D01*
G37*
G36*
G01X1182206D02*
Y1599021D01*
G02X1182408Y1599224I202J1D01*
G01X1185228D01*
G02X1185430Y1599021I-1J-203D01*
G01Y1597895D01*
G03X1185458Y1597792I200J-1D01*
G02X1185730Y1596811I-1640J-983D01*
G02X1185458Y1595830I-1912J2D01*
G03X1185430Y1595727I172J-102D01*
G01Y1592777D01*
G03X1185458Y1592674I200J-1D01*
G02X1185730Y1591693I-1640J-983D01*
G02X1185458Y1590712I-1912J2D01*
G03X1185430Y1590609I172J-102D01*
G01Y1589483D01*
G02X1185228Y1589280I-202J-1D01*
G01X1182408D01*
G02X1182206Y1589483I1J203D01*
G01Y1590609D01*
G03X1182178Y1590712I-200J1D01*
G02X1181906Y1591693I1640J983D01*
G02X1182178Y1592674I1912J-2D01*
G03X1182206Y1592777I-172J102D01*
G01Y1595727D01*
G03X1182178Y1595830I-200J1D01*
G02X1181906Y1596811I1640J983D01*
G02X1182178Y1597792I1912J-2D01*
G03X1182206Y1597895I-172J102D01*
G37*
G36*
G01X1303466D02*
Y1599021D01*
G02X1303669Y1599224I203J0D01*
G01X1306489D01*
G02X1306692Y1599021I0J-203D01*
G01Y1597895D01*
G03X1306720Y1597792I200J-1D01*
G02Y1595830I-1642J-981D01*
G03X1306692Y1595727I172J-102D01*
G01Y1592777D01*
G03X1306720Y1592674I200J-1D01*
G02Y1590712I-1642J-981D01*
G03X1306692Y1590609I172J-102D01*
G01Y1589483D01*
G02X1306489Y1589280I-203J0D01*
G01X1303669D01*
G02X1303466Y1589483I0J203D01*
G01Y1590609D01*
G03X1303438Y1590712I-200J1D01*
G02Y1592674I1642J981D01*
G03X1303466Y1592777I-172J102D01*
G01Y1595727D01*
G03X1303438Y1595830I-200J1D01*
G02Y1597792I1642J981D01*
G03X1303466Y1597895I-172J102D01*
G37*
G36*
G01X1320790D02*
Y1599021D01*
G02X1320992Y1599224I202J1D01*
G01X1323812D01*
G02X1324014Y1599021I-1J-203D01*
G01Y1597895D01*
G03X1324042Y1597792I200J-1D01*
G02X1324314Y1596811I-1640J-983D01*
G02X1324042Y1595830I-1912J2D01*
G03X1324014Y1595727I172J-102D01*
G01Y1592777D01*
G03X1324042Y1592674I200J-1D01*
G02X1324314Y1591693I-1640J-983D01*
G02X1324042Y1590712I-1912J2D01*
G03X1324014Y1590609I172J-102D01*
G01Y1589483D01*
G02X1323812Y1589280I-202J-1D01*
G01X1320992D01*
G02X1320790Y1589483I1J203D01*
G01Y1590609D01*
G03X1320762Y1590712I-200J1D01*
G02X1320490Y1591693I1640J983D01*
G02X1320762Y1592674I1912J-2D01*
G03X1320790Y1592777I-172J102D01*
G01Y1595727D01*
G03X1320762Y1595830I-200J1D01*
G02X1320490Y1596811I1640J983D01*
G02X1320762Y1597792I1912J-2D01*
G03X1320790Y1597895I-172J102D01*
G37*
G36*
G01X1338112D02*
Y1599021D01*
G02X1338315Y1599224I203J0D01*
G01X1341135D01*
G02X1341338Y1599021I0J-203D01*
G01Y1597895D01*
G03X1341366Y1597792I200J-1D01*
G02Y1595830I-1642J-981D01*
G03X1341338Y1595727I172J-102D01*
G01Y1592777D01*
G03X1341366Y1592674I200J-1D01*
G02Y1590712I-1642J-981D01*
G03X1341338Y1590609I172J-102D01*
G01Y1589483D01*
G02X1341135Y1589280I-203J0D01*
G01X1338315D01*
G02X1338112Y1589483I0J203D01*
G01Y1590609D01*
G03X1338084Y1590712I-200J1D01*
G02Y1592674I1642J981D01*
G03X1338112Y1592777I-172J102D01*
G01Y1595727D01*
G03X1338084Y1595830I-200J1D01*
G02Y1597792I1642J981D01*
G03X1338112Y1597895I-172J102D01*
G37*
G36*
G01X1355434D02*
Y1599021D01*
G02X1355637Y1599224I203J0D01*
G01X1358457D01*
G02X1358660Y1599021I0J-203D01*
G01Y1597895D01*
G03X1358688Y1597792I200J-1D01*
G02Y1595830I-1642J-981D01*
G03X1358660Y1595727I172J-102D01*
G01Y1592777D01*
G03X1358688Y1592674I200J-1D01*
G02Y1590712I-1642J-981D01*
G03X1358660Y1590609I172J-102D01*
G01Y1589483D01*
G02X1358457Y1589280I-203J0D01*
G01X1355637D01*
G02X1355434Y1589483I0J203D01*
G01Y1590609D01*
G03X1355406Y1590712I-200J1D01*
G02Y1592674I1642J981D01*
G03X1355434Y1592777I-172J102D01*
G01Y1595727D01*
G03X1355406Y1595830I-200J1D01*
G02Y1597792I1642J981D01*
G03X1355434Y1597895I-172J102D01*
G37*
G36*
G01X1476694D02*
Y1599021D01*
G02X1476897Y1599224I203J0D01*
G01X1479717D01*
G02X1479920Y1599021I0J-203D01*
G01Y1597895D01*
G03X1479948Y1597792I200J-1D01*
G02Y1595830I-1642J-981D01*
G03X1479920Y1595727I172J-102D01*
G01Y1592777D01*
G03X1479948Y1592674I200J-1D01*
G02Y1590712I-1642J-981D01*
G03X1479920Y1590609I172J-102D01*
G01Y1589483D01*
G02X1479717Y1589280I-203J0D01*
G01X1476897D01*
G02X1476694Y1589483I0J203D01*
G01Y1590609D01*
G03X1476666Y1590712I-200J1D01*
G02Y1592674I1642J981D01*
G03X1476694Y1592777I-172J102D01*
G01Y1595727D01*
G03X1476666Y1595830I-200J1D01*
G02Y1597792I1642J981D01*
G03X1476694Y1597895I-172J102D01*
G37*
G36*
G01X1494018D02*
Y1599021D01*
G02X1494220Y1599224I202J1D01*
G01X1497040D01*
G02X1497242Y1599021I-1J-203D01*
G01Y1597895D01*
G03X1497270Y1597792I200J-1D01*
G02X1497542Y1596811I-1640J-983D01*
G02X1497270Y1595830I-1912J2D01*
G03X1497242Y1595727I172J-102D01*
G01Y1592777D01*
G03X1497270Y1592674I200J-1D01*
G02X1497542Y1591693I-1640J-983D01*
G02X1497270Y1590712I-1912J2D01*
G03X1497242Y1590609I172J-102D01*
G01Y1589483D01*
G02X1497040Y1589280I-202J-1D01*
G01X1494220D01*
G02X1494018Y1589483I1J203D01*
G01Y1590609D01*
G03X1493990Y1590712I-200J1D01*
G02X1493718Y1591693I1640J983D01*
G02X1493990Y1592674I1912J-2D01*
G03X1494018Y1592777I-172J102D01*
G01Y1595727D01*
G03X1493990Y1595830I-200J1D01*
G02X1493718Y1596811I1640J983D01*
G02X1493990Y1597792I1912J-2D01*
G03X1494018Y1597895I-172J102D01*
G37*
G36*
G01X1511340D02*
Y1599021D01*
G02X1511543Y1599224I203J0D01*
G01X1514363D01*
G02X1514566Y1599021I0J-203D01*
G01Y1597895D01*
G03X1514594Y1597792I200J-1D01*
G02Y1595830I-1642J-981D01*
G03X1514566Y1595727I172J-102D01*
G01Y1592777D01*
G03X1514594Y1592674I200J-1D01*
G02Y1590712I-1642J-981D01*
G03X1514566Y1590609I172J-102D01*
G01Y1589483D01*
G02X1514363Y1589280I-203J0D01*
G01X1511543D01*
G02X1511340Y1589483I0J203D01*
G01Y1590609D01*
G03X1511312Y1590712I-200J1D01*
G02Y1592674I1642J981D01*
G03X1511340Y1592777I-172J102D01*
G01Y1595727D01*
G03X1511312Y1595830I-200J1D01*
G02Y1597792I1642J981D01*
G03X1511340Y1597895I-172J102D01*
G37*
G36*
G01X1528662D02*
Y1599021D01*
G02X1528865Y1599224I203J0D01*
G01X1531685D01*
G02X1531888Y1599021I0J-203D01*
G01Y1597895D01*
G03X1531916Y1597792I200J-1D01*
G02Y1595830I-1642J-981D01*
G03X1531888Y1595727I172J-102D01*
G01Y1592777D01*
G03X1531916Y1592674I200J-1D01*
G02Y1590712I-1642J-981D01*
G03X1531888Y1590609I172J-102D01*
G01Y1589483D01*
G02X1531685Y1589280I-203J0D01*
G01X1528865D01*
G02X1528662Y1589483I0J203D01*
G01Y1590609D01*
G03X1528634Y1590712I-200J1D01*
G02Y1592674I1642J981D01*
G03X1528662Y1592777I-172J102D01*
G01Y1595727D01*
G03X1528634Y1595830I-200J1D01*
G02Y1597792I1642J981D01*
G03X1528662Y1597895I-172J102D01*
G37*
G36*
G01X1138898Y1602226D02*
Y1603352D01*
G02X1139101Y1603554I203J-1D01*
G01X1141921D01*
G02X1142124Y1603352I1J-202D01*
G01Y1602226D01*
G03X1142152Y1602123I200J-1D01*
G02Y1600161I-1642J-981D01*
G03X1142124Y1600058I172J-102D01*
G01Y1597108D01*
G03X1142152Y1597005I200J-1D01*
G02Y1595043I-1642J-981D01*
G03X1142124Y1594940I172J-102D01*
G01Y1593814D01*
G02X1141921Y1593612I-203J1D01*
G01X1139101D01*
G02X1138898Y1593814I-1J202D01*
G01Y1594940D01*
G03X1138870Y1595043I-200J1D01*
G02Y1597005I1642J981D01*
G03X1138898Y1597108I-172J102D01*
G01Y1600058D01*
G03X1138870Y1600161I-200J1D01*
G02Y1602123I1642J981D01*
G03X1138898Y1602226I-172J102D01*
G37*
G36*
G01X1156222D02*
Y1603352D01*
G02X1156424Y1603554I202J0D01*
G01X1159244D01*
G02X1159446Y1603352I0J-202D01*
G01Y1602226D01*
G03X1159474Y1602123I200J-1D01*
G02X1159746Y1601142I-1640J-983D01*
G02X1159474Y1600161I-1912J2D01*
G03X1159446Y1600058I172J-102D01*
G01Y1597108D01*
G03X1159474Y1597005I200J-1D01*
G02X1159746Y1596024I-1640J-983D01*
G02X1159474Y1595043I-1912J2D01*
G03X1159446Y1594940I172J-102D01*
G01Y1593814D01*
G02X1159244Y1593612I-202J0D01*
G01X1156424D01*
G02X1156222Y1593814I0J202D01*
G01Y1594940D01*
G03X1156194Y1595043I-200J1D01*
G02X1155922Y1596024I1640J983D01*
G02X1156194Y1597005I1912J-2D01*
G03X1156222Y1597108I-172J102D01*
G01Y1600058D01*
G03X1156194Y1600161I-200J1D01*
G02X1155922Y1601142I1640J983D01*
G02X1156194Y1602123I1912J-2D01*
G03X1156222Y1602226I-172J102D01*
G37*
G36*
G01X1173544D02*
Y1603352D01*
G02X1173747Y1603554I203J-1D01*
G01X1176567D01*
G02X1176770Y1603352I1J-202D01*
G01Y1602226D01*
G03X1176798Y1602123I200J-1D01*
G02Y1600161I-1642J-981D01*
G03X1176770Y1600058I172J-102D01*
G01Y1597108D01*
G03X1176798Y1597005I200J-1D01*
G02Y1595043I-1642J-981D01*
G03X1176770Y1594940I172J-102D01*
G01Y1593814D01*
G02X1176567Y1593612I-203J1D01*
G01X1173747D01*
G02X1173544Y1593814I-1J202D01*
G01Y1594940D01*
G03X1173516Y1595043I-200J1D01*
G02Y1597005I1642J981D01*
G03X1173544Y1597108I-172J102D01*
G01Y1600058D01*
G03X1173516Y1600161I-200J1D01*
G02Y1602123I1642J981D01*
G03X1173544Y1602226I-172J102D01*
G37*
G36*
G01X1190868D02*
Y1603352D01*
G02X1191070Y1603554I202J0D01*
G01X1193890D01*
G02X1194092Y1603352I0J-202D01*
G01Y1602226D01*
G03X1194120Y1602123I200J-1D01*
G02X1194392Y1601142I-1640J-983D01*
G02X1194120Y1600161I-1912J2D01*
G03X1194092Y1600058I172J-102D01*
G01Y1597108D01*
G03X1194120Y1597005I200J-1D01*
G02X1194392Y1596024I-1640J-983D01*
G02X1194120Y1595043I-1912J2D01*
G03X1194092Y1594940I172J-102D01*
G01Y1593814D01*
G02X1193890Y1593612I-202J0D01*
G01X1191070D01*
G02X1190868Y1593814I0J202D01*
G01Y1594940D01*
G03X1190840Y1595043I-200J1D01*
G02X1190568Y1596024I1640J983D01*
G02X1190840Y1597005I1912J-2D01*
G03X1190868Y1597108I-172J102D01*
G01Y1600058D01*
G03X1190840Y1600161I-200J1D01*
G02X1190568Y1601142I1640J983D01*
G02X1190840Y1602123I1912J-2D01*
G03X1190868Y1602226I-172J102D01*
G37*
G36*
G01X1312128D02*
Y1603352D01*
G02X1312330Y1603554I202J0D01*
G01X1315150D01*
G02X1315352Y1603352I0J-202D01*
G01Y1602226D01*
G03X1315380Y1602123I200J-1D01*
G02X1315652Y1601142I-1640J-983D01*
G02X1315380Y1600161I-1912J2D01*
G03X1315352Y1600058I172J-102D01*
G01Y1597108D01*
G03X1315380Y1597005I200J-1D01*
G02X1315652Y1596024I-1640J-983D01*
G02X1315380Y1595043I-1912J2D01*
G03X1315352Y1594940I172J-102D01*
G01Y1593814D01*
G02X1315150Y1593612I-202J0D01*
G01X1312330D01*
G02X1312128Y1593814I0J202D01*
G01Y1594940D01*
G03X1312100Y1595043I-200J1D01*
G02X1311828Y1596024I1640J983D01*
G02X1312100Y1597005I1912J-2D01*
G03X1312128Y1597108I-172J102D01*
G01Y1600058D01*
G03X1312100Y1600161I-200J1D01*
G02X1311828Y1601142I1640J983D01*
G02X1312100Y1602123I1912J-2D01*
G03X1312128Y1602226I-172J102D01*
G37*
G36*
G01X1329450D02*
Y1603352D01*
G02X1329653Y1603554I203J-1D01*
G01X1332473D01*
G02X1332676Y1603352I1J-202D01*
G01Y1602226D01*
G03X1332704Y1602123I200J-1D01*
G02Y1600161I-1642J-981D01*
G03X1332676Y1600058I172J-102D01*
G01Y1597108D01*
G03X1332704Y1597005I200J-1D01*
G02Y1595043I-1642J-981D01*
G03X1332676Y1594940I172J-102D01*
G01Y1593814D01*
G02X1332473Y1593612I-203J1D01*
G01X1329653D01*
G02X1329450Y1593814I-1J202D01*
G01Y1594940D01*
G03X1329422Y1595043I-200J1D01*
G02Y1597005I1642J981D01*
G03X1329450Y1597108I-172J102D01*
G01Y1600058D01*
G03X1329422Y1600161I-200J1D01*
G02Y1602123I1642J981D01*
G03X1329450Y1602226I-172J102D01*
G37*
G36*
G01X1346774D02*
Y1603352D01*
G02X1346976Y1603554I202J0D01*
G01X1349796D01*
G02X1349998Y1603352I0J-202D01*
G01Y1602226D01*
G03X1350026Y1602123I200J-1D01*
G02X1350298Y1601142I-1640J-983D01*
G02X1350026Y1600161I-1912J2D01*
G03X1349998Y1600058I172J-102D01*
G01Y1597108D01*
G03X1350026Y1597005I200J-1D01*
G02X1350298Y1596024I-1640J-983D01*
G02X1350026Y1595043I-1912J2D01*
G03X1349998Y1594940I172J-102D01*
G01Y1593814D01*
G02X1349796Y1593612I-202J0D01*
G01X1346976D01*
G02X1346774Y1593814I0J202D01*
G01Y1594940D01*
G03X1346746Y1595043I-200J1D01*
G02X1346474Y1596024I1640J983D01*
G02X1346746Y1597005I1912J-2D01*
G03X1346774Y1597108I-172J102D01*
G01Y1600058D01*
G03X1346746Y1600161I-200J1D01*
G02X1346474Y1601142I1640J983D01*
G02X1346746Y1602123I1912J-2D01*
G03X1346774Y1602226I-172J102D01*
G37*
G36*
G01X1364096D02*
Y1603352D01*
G02X1364299Y1603554I203J-1D01*
G01X1367119D01*
G02X1367322Y1603352I1J-202D01*
G01Y1602226D01*
G03X1367350Y1602123I200J-1D01*
G02Y1600161I-1642J-981D01*
G03X1367322Y1600058I172J-102D01*
G01Y1597108D01*
G03X1367350Y1597005I200J-1D01*
G02Y1595043I-1642J-981D01*
G03X1367322Y1594940I172J-102D01*
G01Y1593814D01*
G02X1367119Y1593612I-203J1D01*
G01X1364299D01*
G02X1364096Y1593814I-1J202D01*
G01Y1594940D01*
G03X1364068Y1595043I-200J1D01*
G02Y1597005I1642J981D01*
G03X1364096Y1597108I-172J102D01*
G01Y1600058D01*
G03X1364068Y1600161I-200J1D01*
G02Y1602123I1642J981D01*
G03X1364096Y1602226I-172J102D01*
G37*
G36*
G01X1485356D02*
Y1603352D01*
G02X1485558Y1603554I202J0D01*
G01X1488378D01*
G02X1488580Y1603352I0J-202D01*
G01Y1602226D01*
G03X1488608Y1602123I200J-1D01*
G02X1488880Y1601142I-1640J-983D01*
G02X1488608Y1600161I-1912J2D01*
G03X1488580Y1600058I172J-102D01*
G01Y1597108D01*
G03X1488608Y1597005I200J-1D01*
G02X1488880Y1596024I-1640J-983D01*
G02X1488608Y1595043I-1912J2D01*
G03X1488580Y1594940I172J-102D01*
G01Y1593814D01*
G02X1488378Y1593612I-202J0D01*
G01X1485558D01*
G02X1485356Y1593814I0J202D01*
G01Y1594940D01*
G03X1485328Y1595043I-200J1D01*
G02X1485056Y1596024I1640J983D01*
G02X1485328Y1597005I1912J-2D01*
G03X1485356Y1597108I-172J102D01*
G01Y1600058D01*
G03X1485328Y1600161I-200J1D01*
G02X1485056Y1601142I1640J983D01*
G02X1485328Y1602123I1912J-2D01*
G03X1485356Y1602226I-172J102D01*
G37*
G36*
G01X1502678D02*
Y1603352D01*
G02X1502881Y1603554I203J-1D01*
G01X1505701D01*
G02X1505904Y1603352I1J-202D01*
G01Y1602226D01*
G03X1505932Y1602123I200J-1D01*
G02Y1600161I-1642J-981D01*
G03X1505904Y1600058I172J-102D01*
G01Y1597108D01*
G03X1505932Y1597005I200J-1D01*
G02Y1595043I-1642J-981D01*
G03X1505904Y1594940I172J-102D01*
G01Y1593814D01*
G02X1505701Y1593612I-203J1D01*
G01X1502881D01*
G02X1502678Y1593814I-1J202D01*
G01Y1594940D01*
G03X1502650Y1595043I-200J1D01*
G02Y1597005I1642J981D01*
G03X1502678Y1597108I-172J102D01*
G01Y1600058D01*
G03X1502650Y1600161I-200J1D01*
G02Y1602123I1642J981D01*
G03X1502678Y1602226I-172J102D01*
G37*
G36*
G01X1520002D02*
Y1603352D01*
G02X1520204Y1603554I202J0D01*
G01X1523024D01*
G02X1523226Y1603352I0J-202D01*
G01Y1602226D01*
G03X1523254Y1602123I200J-1D01*
G02X1523526Y1601142I-1640J-983D01*
G02X1523254Y1600161I-1912J2D01*
G03X1523226Y1600058I172J-102D01*
G01Y1597108D01*
G03X1523254Y1597005I200J-1D01*
G02X1523526Y1596024I-1640J-983D01*
G02X1523254Y1595043I-1912J2D01*
G03X1523226Y1594940I172J-102D01*
G01Y1593814D01*
G02X1523024Y1593612I-202J0D01*
G01X1520204D01*
G02X1520002Y1593814I0J202D01*
G01Y1594940D01*
G03X1519974Y1595043I-200J1D01*
G02X1519702Y1596024I1640J983D01*
G02X1519974Y1597005I1912J-2D01*
G03X1520002Y1597108I-172J102D01*
G01Y1600058D01*
G03X1519974Y1600161I-200J1D01*
G02X1519702Y1601142I1640J983D01*
G02X1519974Y1602123I1912J-2D01*
G03X1520002Y1602226I-172J102D01*
G37*
G36*
G01X1537324D02*
Y1603352D01*
G02X1537527Y1603554I203J-1D01*
G01X1540347D01*
G02X1540550Y1603352I1J-202D01*
G01Y1602226D01*
G03X1540578Y1602123I200J-1D01*
G02Y1600161I-1642J-981D01*
G03X1540550Y1600058I172J-102D01*
G01Y1597108D01*
G03X1540578Y1597005I200J-1D01*
G02Y1595043I-1642J-981D01*
G03X1540550Y1594940I172J-102D01*
G01Y1593814D01*
G02X1540347Y1593612I-203J1D01*
G01X1537527D01*
G02X1537324Y1593814I-1J202D01*
G01Y1594940D01*
G03X1537296Y1595043I-200J1D01*
G02Y1597005I1642J981D01*
G03X1537324Y1597108I-172J102D01*
G01Y1600058D01*
G03X1537296Y1600161I-200J1D01*
G02Y1602123I1642J981D01*
G03X1537324Y1602226I-172J102D01*
G37*
G36*
G01X1130238Y1613250D02*
Y1614376D01*
G02X1130440Y1614578I202J0D01*
G01X1133260D01*
G02X1133462Y1614376I0J-202D01*
G01Y1613250D01*
G03X1133490Y1613147I200J-1D01*
G02X1133762Y1612166I-1640J-983D01*
G02X1133490Y1611185I-1912J2D01*
G03X1133462Y1611082I172J-102D01*
G01Y1608132D01*
G03X1133490Y1608029I200J-1D01*
G02X1133762Y1607048I-1640J-983D01*
G02X1133490Y1606067I-1912J2D01*
G03X1133462Y1605964I172J-102D01*
G01Y1604838D01*
G02X1133260Y1604636I-202J0D01*
G01X1130440D01*
G02X1130238Y1604838I0J202D01*
G01Y1605964D01*
G03X1130210Y1606067I-200J1D01*
G02X1129938Y1607048I1640J983D01*
G02X1130210Y1608029I1912J-2D01*
G03X1130238Y1608132I-172J102D01*
G01Y1611082D01*
G03X1130210Y1611185I-200J1D01*
G02X1129938Y1612166I1640J983D01*
G02X1130210Y1613147I1912J-2D01*
G03X1130238Y1613250I-172J102D01*
G37*
G36*
G01X1147560D02*
Y1614376D01*
G02X1147763Y1614578I203J-1D01*
G01X1150583D01*
G02X1150786Y1614376I1J-202D01*
G01Y1613250D01*
G03X1150814Y1613147I200J-1D01*
G02Y1611185I-1642J-981D01*
G03X1150786Y1611082I172J-102D01*
G01Y1608132D01*
G03X1150814Y1608029I200J-1D01*
G02Y1606067I-1642J-981D01*
G03X1150786Y1605964I172J-102D01*
G01Y1604838D01*
G02X1150583Y1604636I-203J1D01*
G01X1147763D01*
G02X1147560Y1604838I-1J202D01*
G01Y1605964D01*
G03X1147532Y1606067I-200J1D01*
G02Y1608029I1642J981D01*
G03X1147560Y1608132I-172J102D01*
G01Y1611082D01*
G03X1147532Y1611185I-200J1D01*
G02Y1613147I1642J981D01*
G03X1147560Y1613250I-172J102D01*
G37*
G36*
G01X1164884D02*
Y1614376D01*
G02X1165086Y1614578I202J0D01*
G01X1167906D01*
G02X1168108Y1614376I0J-202D01*
G01Y1613250D01*
G03X1168136Y1613147I200J-1D01*
G02X1168408Y1612166I-1640J-983D01*
G02X1168136Y1611185I-1912J2D01*
G03X1168108Y1611082I172J-102D01*
G01Y1608132D01*
G03X1168136Y1608029I200J-1D01*
G02X1168408Y1607048I-1640J-983D01*
G02X1168136Y1606067I-1912J2D01*
G03X1168108Y1605964I172J-102D01*
G01Y1604838D01*
G02X1167906Y1604636I-202J0D01*
G01X1165086D01*
G02X1164884Y1604838I0J202D01*
G01Y1605964D01*
G03X1164856Y1606067I-200J1D01*
G02X1164584Y1607048I1640J983D01*
G02X1164856Y1608029I1912J-2D01*
G03X1164884Y1608132I-172J102D01*
G01Y1611082D01*
G03X1164856Y1611185I-200J1D01*
G02X1164584Y1612166I1640J983D01*
G02X1164856Y1613147I1912J-2D01*
G03X1164884Y1613250I-172J102D01*
G37*
G36*
G01X1182206D02*
Y1614376D01*
G02X1182408Y1614578I202J0D01*
G01X1185228D01*
G02X1185430Y1614376I0J-202D01*
G01Y1613250D01*
G03X1185458Y1613147I200J-1D01*
G02X1185730Y1612166I-1640J-983D01*
G02X1185458Y1611185I-1912J2D01*
G03X1185430Y1611082I172J-102D01*
G01Y1608132D01*
G03X1185458Y1608029I200J-1D01*
G02X1185730Y1607048I-1640J-983D01*
G02X1185458Y1606067I-1912J2D01*
G03X1185430Y1605964I172J-102D01*
G01Y1604838D01*
G02X1185228Y1604636I-202J0D01*
G01X1182408D01*
G02X1182206Y1604838I0J202D01*
G01Y1605964D01*
G03X1182178Y1606067I-200J1D01*
G02X1181906Y1607048I1640J983D01*
G02X1182178Y1608029I1912J-2D01*
G03X1182206Y1608132I-172J102D01*
G01Y1611082D01*
G03X1182178Y1611185I-200J1D01*
G02X1181906Y1612166I1640J983D01*
G02X1182178Y1613147I1912J-2D01*
G03X1182206Y1613250I-172J102D01*
G37*
G36*
G01X1303466D02*
Y1614376D01*
G02X1303669Y1614578I203J-1D01*
G01X1306489D01*
G02X1306692Y1614376I1J-202D01*
G01Y1613250D01*
G03X1306720Y1613147I200J-1D01*
G02Y1611185I-1642J-981D01*
G03X1306692Y1611082I172J-102D01*
G01Y1608132D01*
G03X1306720Y1608029I200J-1D01*
G02Y1606067I-1642J-981D01*
G03X1306692Y1605964I172J-102D01*
G01Y1604838D01*
G02X1306489Y1604636I-203J1D01*
G01X1303669D01*
G02X1303466Y1604838I-1J202D01*
G01Y1605964D01*
G03X1303438Y1606067I-200J1D01*
G02Y1608029I1642J981D01*
G03X1303466Y1608132I-172J102D01*
G01Y1611082D01*
G03X1303438Y1611185I-200J1D01*
G02Y1613147I1642J981D01*
G03X1303466Y1613250I-172J102D01*
G37*
G36*
G01X1320790D02*
Y1614376D01*
G02X1320992Y1614578I202J0D01*
G01X1323812D01*
G02X1324014Y1614376I0J-202D01*
G01Y1613250D01*
G03X1324042Y1613147I200J-1D01*
G02X1324314Y1612166I-1640J-983D01*
G02X1324042Y1611185I-1912J2D01*
G03X1324014Y1611082I172J-102D01*
G01Y1608132D01*
G03X1324042Y1608029I200J-1D01*
G02X1324314Y1607048I-1640J-983D01*
G02X1324042Y1606067I-1912J2D01*
G03X1324014Y1605964I172J-102D01*
G01Y1604838D01*
G02X1323812Y1604636I-202J0D01*
G01X1320992D01*
G02X1320790Y1604838I0J202D01*
G01Y1605964D01*
G03X1320762Y1606067I-200J1D01*
G02X1320490Y1607048I1640J983D01*
G02X1320762Y1608029I1912J-2D01*
G03X1320790Y1608132I-172J102D01*
G01Y1611082D01*
G03X1320762Y1611185I-200J1D01*
G02X1320490Y1612166I1640J983D01*
G02X1320762Y1613147I1912J-2D01*
G03X1320790Y1613250I-172J102D01*
G37*
G36*
G01X1338112D02*
Y1614376D01*
G02X1338315Y1614578I203J-1D01*
G01X1341135D01*
G02X1341338Y1614376I1J-202D01*
G01Y1613250D01*
G03X1341366Y1613147I200J-1D01*
G02Y1611185I-1642J-981D01*
G03X1341338Y1611082I172J-102D01*
G01Y1608132D01*
G03X1341366Y1608029I200J-1D01*
G02Y1606067I-1642J-981D01*
G03X1341338Y1605964I172J-102D01*
G01Y1604838D01*
G02X1341135Y1604636I-203J1D01*
G01X1338315D01*
G02X1338112Y1604838I-1J202D01*
G01Y1605964D01*
G03X1338084Y1606067I-200J1D01*
G02Y1608029I1642J981D01*
G03X1338112Y1608132I-172J102D01*
G01Y1611082D01*
G03X1338084Y1611185I-200J1D01*
G02Y1613147I1642J981D01*
G03X1338112Y1613250I-172J102D01*
G37*
G36*
G01X1355434D02*
Y1614376D01*
G02X1355637Y1614578I203J-1D01*
G01X1358457D01*
G02X1358660Y1614376I1J-202D01*
G01Y1613250D01*
G03X1358688Y1613147I200J-1D01*
G02Y1611185I-1642J-981D01*
G03X1358660Y1611082I172J-102D01*
G01Y1608132D01*
G03X1358688Y1608029I200J-1D01*
G02Y1606067I-1642J-981D01*
G03X1358660Y1605964I172J-102D01*
G01Y1604838D01*
G02X1358457Y1604636I-203J1D01*
G01X1355637D01*
G02X1355434Y1604838I-1J202D01*
G01Y1605964D01*
G03X1355406Y1606067I-200J1D01*
G02Y1608029I1642J981D01*
G03X1355434Y1608132I-172J102D01*
G01Y1611082D01*
G03X1355406Y1611185I-200J1D01*
G02Y1613147I1642J981D01*
G03X1355434Y1613250I-172J102D01*
G37*
G36*
G01X1476694D02*
Y1614376D01*
G02X1476897Y1614578I203J-1D01*
G01X1479717D01*
G02X1479920Y1614376I1J-202D01*
G01Y1613250D01*
G03X1479948Y1613147I200J-1D01*
G02Y1611185I-1642J-981D01*
G03X1479920Y1611082I172J-102D01*
G01Y1608132D01*
G03X1479948Y1608029I200J-1D01*
G02Y1606067I-1642J-981D01*
G03X1479920Y1605964I172J-102D01*
G01Y1604838D01*
G02X1479717Y1604636I-203J1D01*
G01X1476897D01*
G02X1476694Y1604838I-1J202D01*
G01Y1605964D01*
G03X1476666Y1606067I-200J1D01*
G02Y1608029I1642J981D01*
G03X1476694Y1608132I-172J102D01*
G01Y1611082D01*
G03X1476666Y1611185I-200J1D01*
G02Y1613147I1642J981D01*
G03X1476694Y1613250I-172J102D01*
G37*
G36*
G01X1494018D02*
Y1614376D01*
G02X1494220Y1614578I202J0D01*
G01X1497040D01*
G02X1497242Y1614376I0J-202D01*
G01Y1613250D01*
G03X1497270Y1613147I200J-1D01*
G02X1497542Y1612166I-1640J-983D01*
G02X1497270Y1611185I-1912J2D01*
G03X1497242Y1611082I172J-102D01*
G01Y1608132D01*
G03X1497270Y1608029I200J-1D01*
G02X1497542Y1607048I-1640J-983D01*
G02X1497270Y1606067I-1912J2D01*
G03X1497242Y1605964I172J-102D01*
G01Y1604838D01*
G02X1497040Y1604636I-202J0D01*
G01X1494220D01*
G02X1494018Y1604838I0J202D01*
G01Y1605964D01*
G03X1493990Y1606067I-200J1D01*
G02X1493718Y1607048I1640J983D01*
G02X1493990Y1608029I1912J-2D01*
G03X1494018Y1608132I-172J102D01*
G01Y1611082D01*
G03X1493990Y1611185I-200J1D01*
G02X1493718Y1612166I1640J983D01*
G02X1493990Y1613147I1912J-2D01*
G03X1494018Y1613250I-172J102D01*
G37*
G36*
G01X1511340D02*
Y1614376D01*
G02X1511543Y1614578I203J-1D01*
G01X1514363D01*
G02X1514566Y1614376I1J-202D01*
G01Y1613250D01*
G03X1514594Y1613147I200J-1D01*
G02Y1611185I-1642J-981D01*
G03X1514566Y1611082I172J-102D01*
G01Y1608132D01*
G03X1514594Y1608029I200J-1D01*
G02Y1606067I-1642J-981D01*
G03X1514566Y1605964I172J-102D01*
G01Y1604838D01*
G02X1514363Y1604636I-203J1D01*
G01X1511543D01*
G02X1511340Y1604838I-1J202D01*
G01Y1605964D01*
G03X1511312Y1606067I-200J1D01*
G02Y1608029I1642J981D01*
G03X1511340Y1608132I-172J102D01*
G01Y1611082D01*
G03X1511312Y1611185I-200J1D01*
G02Y1613147I1642J981D01*
G03X1511340Y1613250I-172J102D01*
G37*
G36*
G01X1528662D02*
Y1614376D01*
G02X1528865Y1614578I203J-1D01*
G01X1531685D01*
G02X1531888Y1614376I1J-202D01*
G01Y1613250D01*
G03X1531916Y1613147I200J-1D01*
G02Y1611185I-1642J-981D01*
G03X1531888Y1611082I172J-102D01*
G01Y1608132D01*
G03X1531916Y1608029I200J-1D01*
G02Y1606067I-1642J-981D01*
G03X1531888Y1605964I172J-102D01*
G01Y1604838D01*
G02X1531685Y1604636I-203J1D01*
G01X1528865D01*
G02X1528662Y1604838I-1J202D01*
G01Y1605964D01*
G03X1528634Y1606067I-200J1D01*
G02Y1608029I1642J981D01*
G03X1528662Y1608132I-172J102D01*
G01Y1611082D01*
G03X1528634Y1611185I-200J1D01*
G02Y1613147I1642J981D01*
G03X1528662Y1613250I-172J102D01*
G37*
G36*
G01X1138898Y1617580D02*
Y1618706D01*
G02X1139101Y1618908I203J-1D01*
G01X1141921D01*
G02X1142124Y1618706I1J-202D01*
G01Y1617580D01*
G03X1142152Y1617477I200J-1D01*
G02Y1615515I-1642J-981D01*
G03X1142124Y1615412I172J-102D01*
G01Y1612462D01*
G03X1142152Y1612359I200J-1D01*
G02Y1610397I-1642J-981D01*
G03X1142124Y1610294I172J-102D01*
G01Y1609168D01*
G02X1141921Y1608966I-203J1D01*
G01X1139101D01*
G02X1138898Y1609168I-1J202D01*
G01Y1610294D01*
G03X1138870Y1610397I-200J1D01*
G02Y1612359I1642J981D01*
G03X1138898Y1612462I-172J102D01*
G01Y1615412D01*
G03X1138870Y1615515I-200J1D01*
G02Y1617477I1642J981D01*
G03X1138898Y1617580I-172J102D01*
G37*
G36*
G01X1156222D02*
Y1618706D01*
G02X1156424Y1618908I202J0D01*
G01X1159244D01*
G02X1159446Y1618706I0J-202D01*
G01Y1617580D01*
G03X1159474Y1617477I200J-1D01*
G02X1159746Y1616496I-1640J-983D01*
G02X1159474Y1615515I-1912J2D01*
G03X1159446Y1615412I172J-102D01*
G01Y1612462D01*
G03X1159474Y1612359I200J-1D01*
G02X1159746Y1611378I-1640J-983D01*
G02X1159474Y1610397I-1912J2D01*
G03X1159446Y1610294I172J-102D01*
G01Y1609168D01*
G02X1159244Y1608966I-202J0D01*
G01X1156424D01*
G02X1156222Y1609168I0J202D01*
G01Y1610294D01*
G03X1156194Y1610397I-200J1D01*
G02X1155922Y1611378I1640J983D01*
G02X1156194Y1612359I1912J-2D01*
G03X1156222Y1612462I-172J102D01*
G01Y1615412D01*
G03X1156194Y1615515I-200J1D01*
G02X1155922Y1616496I1640J983D01*
G02X1156194Y1617477I1912J-2D01*
G03X1156222Y1617580I-172J102D01*
G37*
G36*
G01X1173544D02*
Y1618706D01*
G02X1173747Y1618908I203J-1D01*
G01X1176567D01*
G02X1176770Y1618706I1J-202D01*
G01Y1617580D01*
G03X1176798Y1617477I200J-1D01*
G02Y1615515I-1642J-981D01*
G03X1176770Y1615412I172J-102D01*
G01Y1612462D01*
G03X1176798Y1612359I200J-1D01*
G02Y1610397I-1642J-981D01*
G03X1176770Y1610294I172J-102D01*
G01Y1609168D01*
G02X1176567Y1608966I-203J1D01*
G01X1173747D01*
G02X1173544Y1609168I-1J202D01*
G01Y1610294D01*
G03X1173516Y1610397I-200J1D01*
G02Y1612359I1642J981D01*
G03X1173544Y1612462I-172J102D01*
G01Y1615412D01*
G03X1173516Y1615515I-200J1D01*
G02Y1617477I1642J981D01*
G03X1173544Y1617580I-172J102D01*
G37*
G36*
G01X1190868D02*
Y1618706D01*
G02X1191070Y1618908I202J0D01*
G01X1193890D01*
G02X1194092Y1618706I0J-202D01*
G01Y1617580D01*
G03X1194120Y1617477I200J-1D01*
G02X1194392Y1616496I-1640J-983D01*
G02X1194120Y1615515I-1912J2D01*
G03X1194092Y1615412I172J-102D01*
G01Y1612462D01*
G03X1194120Y1612359I200J-1D01*
G02X1194392Y1611378I-1640J-983D01*
G02X1194120Y1610397I-1912J2D01*
G03X1194092Y1610294I172J-102D01*
G01Y1609168D01*
G02X1193890Y1608966I-202J0D01*
G01X1191070D01*
G02X1190868Y1609168I0J202D01*
G01Y1610294D01*
G03X1190840Y1610397I-200J1D01*
G02X1190568Y1611378I1640J983D01*
G02X1190840Y1612359I1912J-2D01*
G03X1190868Y1612462I-172J102D01*
G01Y1615412D01*
G03X1190840Y1615515I-200J1D01*
G02X1190568Y1616496I1640J983D01*
G02X1190840Y1617477I1912J-2D01*
G03X1190868Y1617580I-172J102D01*
G37*
G36*
G01X1312128D02*
Y1618706D01*
G02X1312330Y1618908I202J0D01*
G01X1315150D01*
G02X1315352Y1618706I0J-202D01*
G01Y1617580D01*
G03X1315380Y1617477I200J-1D01*
G02X1315652Y1616496I-1640J-983D01*
G02X1315380Y1615515I-1912J2D01*
G03X1315352Y1615412I172J-102D01*
G01Y1612462D01*
G03X1315380Y1612359I200J-1D01*
G02X1315652Y1611378I-1640J-983D01*
G02X1315380Y1610397I-1912J2D01*
G03X1315352Y1610294I172J-102D01*
G01Y1609168D01*
G02X1315150Y1608966I-202J0D01*
G01X1312330D01*
G02X1312128Y1609168I0J202D01*
G01Y1610294D01*
G03X1312100Y1610397I-200J1D01*
G02X1311828Y1611378I1640J983D01*
G02X1312100Y1612359I1912J-2D01*
G03X1312128Y1612462I-172J102D01*
G01Y1615412D01*
G03X1312100Y1615515I-200J1D01*
G02X1311828Y1616496I1640J983D01*
G02X1312100Y1617477I1912J-2D01*
G03X1312128Y1617580I-172J102D01*
G37*
G36*
G01X1329450D02*
Y1618706D01*
G02X1329653Y1618908I203J-1D01*
G01X1332473D01*
G02X1332676Y1618706I1J-202D01*
G01Y1617580D01*
G03X1332704Y1617477I200J-1D01*
G02Y1615515I-1642J-981D01*
G03X1332676Y1615412I172J-102D01*
G01Y1612462D01*
G03X1332704Y1612359I200J-1D01*
G02Y1610397I-1642J-981D01*
G03X1332676Y1610294I172J-102D01*
G01Y1609168D01*
G02X1332473Y1608966I-203J1D01*
G01X1329653D01*
G02X1329450Y1609168I-1J202D01*
G01Y1610294D01*
G03X1329422Y1610397I-200J1D01*
G02Y1612359I1642J981D01*
G03X1329450Y1612462I-172J102D01*
G01Y1615412D01*
G03X1329422Y1615515I-200J1D01*
G02Y1617477I1642J981D01*
G03X1329450Y1617580I-172J102D01*
G37*
G36*
G01X1346774D02*
Y1618706D01*
G02X1346976Y1618908I202J0D01*
G01X1349796D01*
G02X1349998Y1618706I0J-202D01*
G01Y1617580D01*
G03X1350026Y1617477I200J-1D01*
G02X1350298Y1616496I-1640J-983D01*
G02X1350026Y1615515I-1912J2D01*
G03X1349998Y1615412I172J-102D01*
G01Y1612462D01*
G03X1350026Y1612359I200J-1D01*
G02X1350298Y1611378I-1640J-983D01*
G02X1350026Y1610397I-1912J2D01*
G03X1349998Y1610294I172J-102D01*
G01Y1609168D01*
G02X1349796Y1608966I-202J0D01*
G01X1346976D01*
G02X1346774Y1609168I0J202D01*
G01Y1610294D01*
G03X1346746Y1610397I-200J1D01*
G02X1346474Y1611378I1640J983D01*
G02X1346746Y1612359I1912J-2D01*
G03X1346774Y1612462I-172J102D01*
G01Y1615412D01*
G03X1346746Y1615515I-200J1D01*
G02X1346474Y1616496I1640J983D01*
G02X1346746Y1617477I1912J-2D01*
G03X1346774Y1617580I-172J102D01*
G37*
G36*
G01X1364096D02*
Y1618706D01*
G02X1364299Y1618908I203J-1D01*
G01X1367119D01*
G02X1367322Y1618706I1J-202D01*
G01Y1617580D01*
G03X1367350Y1617477I200J-1D01*
G02Y1615515I-1642J-981D01*
G03X1367322Y1615412I172J-102D01*
G01Y1612462D01*
G03X1367350Y1612359I200J-1D01*
G02Y1610397I-1642J-981D01*
G03X1367322Y1610294I172J-102D01*
G01Y1609168D01*
G02X1367119Y1608966I-203J1D01*
G01X1364299D01*
G02X1364096Y1609168I-1J202D01*
G01Y1610294D01*
G03X1364068Y1610397I-200J1D01*
G02Y1612359I1642J981D01*
G03X1364096Y1612462I-172J102D01*
G01Y1615412D01*
G03X1364068Y1615515I-200J1D01*
G02Y1617477I1642J981D01*
G03X1364096Y1617580I-172J102D01*
G37*
G36*
G01X1485356D02*
Y1618706D01*
G02X1485558Y1618908I202J0D01*
G01X1488378D01*
G02X1488580Y1618706I0J-202D01*
G01Y1617580D01*
G03X1488608Y1617477I200J-1D01*
G02X1488880Y1616496I-1640J-983D01*
G02X1488608Y1615515I-1912J2D01*
G03X1488580Y1615412I172J-102D01*
G01Y1612462D01*
G03X1488608Y1612359I200J-1D01*
G02X1488880Y1611378I-1640J-983D01*
G02X1488608Y1610397I-1912J2D01*
G03X1488580Y1610294I172J-102D01*
G01Y1609168D01*
G02X1488378Y1608966I-202J0D01*
G01X1485558D01*
G02X1485356Y1609168I0J202D01*
G01Y1610294D01*
G03X1485328Y1610397I-200J1D01*
G02X1485056Y1611378I1640J983D01*
G02X1485328Y1612359I1912J-2D01*
G03X1485356Y1612462I-172J102D01*
G01Y1615412D01*
G03X1485328Y1615515I-200J1D01*
G02X1485056Y1616496I1640J983D01*
G02X1485328Y1617477I1912J-2D01*
G03X1485356Y1617580I-172J102D01*
G37*
G36*
G01X1502678D02*
Y1618706D01*
G02X1502881Y1618908I203J-1D01*
G01X1505701D01*
G02X1505904Y1618706I1J-202D01*
G01Y1617580D01*
G03X1505932Y1617477I200J-1D01*
G02Y1615515I-1642J-981D01*
G03X1505904Y1615412I172J-102D01*
G01Y1612462D01*
G03X1505932Y1612359I200J-1D01*
G02Y1610397I-1642J-981D01*
G03X1505904Y1610294I172J-102D01*
G01Y1609168D01*
G02X1505701Y1608966I-203J1D01*
G01X1502881D01*
G02X1502678Y1609168I-1J202D01*
G01Y1610294D01*
G03X1502650Y1610397I-200J1D01*
G02Y1612359I1642J981D01*
G03X1502678Y1612462I-172J102D01*
G01Y1615412D01*
G03X1502650Y1615515I-200J1D01*
G02Y1617477I1642J981D01*
G03X1502678Y1617580I-172J102D01*
G37*
G36*
G01X1520002D02*
Y1618706D01*
G02X1520204Y1618908I202J0D01*
G01X1523024D01*
G02X1523226Y1618706I0J-202D01*
G01Y1617580D01*
G03X1523254Y1617477I200J-1D01*
G02X1523526Y1616496I-1640J-983D01*
G02X1523254Y1615515I-1912J2D01*
G03X1523226Y1615412I172J-102D01*
G01Y1612462D01*
G03X1523254Y1612359I200J-1D01*
G02X1523526Y1611378I-1640J-983D01*
G02X1523254Y1610397I-1912J2D01*
G03X1523226Y1610294I172J-102D01*
G01Y1609168D01*
G02X1523024Y1608966I-202J0D01*
G01X1520204D01*
G02X1520002Y1609168I0J202D01*
G01Y1610294D01*
G03X1519974Y1610397I-200J1D01*
G02X1519702Y1611378I1640J983D01*
G02X1519974Y1612359I1912J-2D01*
G03X1520002Y1612462I-172J102D01*
G01Y1615412D01*
G03X1519974Y1615515I-200J1D01*
G02X1519702Y1616496I1640J983D01*
G02X1519974Y1617477I1912J-2D01*
G03X1520002Y1617580I-172J102D01*
G37*
G36*
G01X1537324D02*
Y1618706D01*
G02X1537527Y1618908I203J-1D01*
G01X1540347D01*
G02X1540550Y1618706I1J-202D01*
G01Y1617580D01*
G03X1540578Y1617477I200J-1D01*
G02Y1615515I-1642J-981D01*
G03X1540550Y1615412I172J-102D01*
G01Y1612462D01*
G03X1540578Y1612359I200J-1D01*
G02Y1610397I-1642J-981D01*
G03X1540550Y1610294I172J-102D01*
G01Y1609168D01*
G02X1540347Y1608966I-203J1D01*
G01X1537527D01*
G02X1537324Y1609168I-1J202D01*
G01Y1610294D01*
G03X1537296Y1610397I-200J1D01*
G02Y1612359I1642J981D01*
G03X1537324Y1612462I-172J102D01*
G01Y1615412D01*
G03X1537296Y1615515I-200J1D01*
G02Y1617477I1642J981D01*
G03X1537324Y1617580I-172J102D01*
G37*
G36*
G01X1257594Y1538501D02*
G02X1257976Y1539423I1306J-1D01*
G01X1265589Y1547036D01*
G02X1266511Y1547418I923J-924D01*
G01X1284487D01*
G03X1284629Y1547477I0J200D01*
G01X1291147Y1553995D01*
G03X1291206Y1554137I-141J142D01*
G01Y1618715D01*
G02X1291588Y1619637I1306J-1D01*
G01X1301875Y1629924D01*
G02X1302797Y1630306I923J-924D01*
G01X1350451D01*
G02X1351373Y1629924I-1J-1306D01*
G01X1356924Y1624373D01*
G03X1357063Y1624314I142J141D01*
G01X1357064D01*
G02X1358959Y1622402I-17J-1912D01*
G02X1357047Y1620490I-1912J0D01*
G02X1355135Y1622385I0J1912D01*
G01Y1622386D01*
G03X1355076Y1622525I-200J-3D01*
G01X1349967Y1627635D01*
G03X1349825Y1627694I-142J-141D01*
G01X1336764D01*
G03X1336579Y1627570I0J-200D01*
G01X1336555Y1627514D01*
X1336579Y1627396D01*
X1339602Y1624373D01*
G03X1339741Y1624314I142J141D01*
G01X1339742D01*
G02X1341637Y1622402I-17J-1912D01*
G02X1339725Y1620490I-1912J0D01*
G02X1337813Y1622385I0J1912D01*
G01Y1622386D01*
G03X1337754Y1622525I-200J-3D01*
G01X1334338Y1625941D01*
G03X1334196Y1626000I-142J-141D01*
G01X1321134D01*
G03X1320949Y1625877I0J-200D01*
G01X1320926Y1625821D01*
X1320949Y1625703D01*
X1322279Y1624373D01*
G03X1322418Y1624314I142J141D01*
G01X1322419D01*
G02X1324314Y1622402I-17J-1912D01*
G02X1322402Y1620490I-1912J0D01*
G02X1320490Y1622385I0J1912D01*
G01Y1622386D01*
G03X1320431Y1622525I-200J-3D01*
G01X1319145Y1623811D01*
G03X1319003Y1623870I-142J-141D01*
G01X1307129D01*
G03X1306959Y1623774I1J-200D01*
G01X1306753Y1623437D01*
X1306750Y1623333D01*
X1306775Y1623286D01*
G02X1306991Y1622404I-1696J-883D01*
G01Y1622402D01*
G02X1305096Y1620490I-1912J0D01*
G01X1305095D01*
G03X1304956Y1620431I3J-200D01*
G01X1299067Y1614543D01*
G03X1299008Y1614401I141J-142D01*
G01Y1550100D01*
G02X1298626Y1549178I-1306J1D01*
G01X1287858Y1538410D01*
G02X1286936Y1538028I-923J924D01*
G01X1267975D01*
G03X1267882Y1538005I0J-200D01*
G02X1267183Y1537832I-700J1329D01*
G02X1265934Y1538500I0J1502D01*
G01X1265909Y1538537D01*
X1265833Y1538583D01*
X1265480Y1538618D01*
G03X1265319Y1538560I-19J-199D01*
G01X1264257Y1537498D01*
G03X1264198Y1537356I141J-142D01*
G01Y1536124D01*
G03X1264219Y1536035I200J0D01*
G01X1264220Y1536033D01*
G02X1264393Y1535334I-1329J-700D01*
G02X1263164Y1533857I-1502J0D01*
G03X1263009Y1533720I36J-197D01*
G01X1262904Y1533381D01*
G03X1262953Y1533181I191J-59D01*
G01X1263435Y1532699D01*
G03X1263577Y1532640I142J141D01*
G01X1266541D01*
G03X1266634Y1532663I0J200D01*
G02X1267333Y1532836I700J-1329D01*
G02Y1529832I0J-1502D01*
G02X1266634Y1530005I1J1502D01*
G03X1266541Y1530028I-93J-177D01*
G01X1264581D01*
G03X1264430Y1529959I0J-200D01*
G01X1264232Y1529731D01*
G03X1264185Y1529574I151J-131D01*
G01Y1529573D01*
G02X1264198Y1529394I-1294J-184D01*
G01Y1528124D01*
G03X1264219Y1528035I200J0D01*
G01X1264220Y1528033D01*
G02X1264393Y1527334I-1329J-700D01*
G02X1261389I-1502J0D01*
G02X1261561Y1528031I1502J-1D01*
G03X1261563Y1528035I-178J91D01*
G01X1261574Y1528056D01*
X1261584Y1528100D01*
Y1528770D01*
G03X1261525Y1528912I-200J0D01*
G01X1257976Y1532461D01*
G02X1257594Y1533383I924J923D01*
G01Y1538501D01*
G37*
G36*
G01X1222599Y1611577D02*
X1210364Y1623811D01*
G03X1210222Y1623870I-142J-141D01*
G01X1203191D01*
G03X1203021Y1623774I1J-200D01*
G01X1202815Y1623437D01*
X1202812Y1623333D01*
X1202837Y1623286D01*
G02X1203053Y1622404I-1696J-883D01*
G01Y1622402D01*
G02X1199229I-1912J0D01*
G01Y1622404D01*
G02X1199445Y1623286I1912J-1D01*
G01X1199470Y1623333D01*
X1199467Y1623437D01*
X1199261Y1623774D01*
G03X1199091Y1623870I-171J-104D01*
G01X1187217D01*
G03X1187075Y1623811I0J-200D01*
G01X1185789Y1622525D01*
G03X1185730Y1622386I141J-142D01*
G01Y1622385D01*
G02X1183818Y1620490I-1912J17D01*
G02X1181906Y1622402I0J1912D01*
G02X1183801Y1624314I1912J0D01*
G01X1183802D01*
G03X1183941Y1624373I-3J200D01*
G01X1184927Y1625359D01*
G03X1184971Y1625577I-141J142D01*
G01X1184948Y1625633D01*
X1184848Y1625700D01*
X1171725D01*
G03X1171583Y1625641I0J-200D01*
G01X1168467Y1622525D01*
G03X1168408Y1622386I141J-142D01*
G01Y1622385D01*
G02X1166496Y1620490I-1912J17D01*
G02X1164584Y1622402I0J1912D01*
G02X1166479Y1624314I1912J0D01*
G01X1166480D01*
G03X1166619Y1624373I-3J200D01*
G01X1169535Y1627289D01*
G03X1169579Y1627507I-141J142D01*
G01X1169556Y1627563D01*
X1169456Y1627630D01*
X1156332D01*
G03X1156190Y1627571I0J-200D01*
G01X1151144Y1622525D01*
G03X1151085Y1622386I141J-142D01*
G01Y1622385D01*
G02X1149173Y1620490I-1912J17D01*
G02X1147261Y1622402I0J1912D01*
G02X1149156Y1624314I1912J0D01*
G01X1149157D01*
G03X1149296Y1624373I-3J200D01*
G01X1154276Y1629353D01*
G03X1154319Y1629570I-142J141D01*
G01X1154296Y1629627D01*
X1154195Y1629694D01*
X1141072D01*
G03X1140930Y1629635I0J-200D01*
G01X1133821Y1622525D01*
G03X1133762Y1622386I141J-142D01*
G01Y1622385D01*
G02X1131850Y1620490I-1912J17D01*
G02X1129938Y1622402I0J1912D01*
G02X1131833Y1624314I1912J0D01*
G01X1131834D01*
G03X1131973Y1624373I-3J200D01*
G01X1139524Y1631924D01*
G02X1140446Y1632306I923J-924D01*
G01X1213402D01*
G02X1214324Y1631924I-1J-1306D01*
G01X1230169Y1616079D01*
G02X1230552Y1615155I-923J-924D01*
G01Y1552879D01*
G03X1230611Y1552737I200J0D01*
G01X1242648Y1540699D01*
G03X1242790Y1540640I142J141D01*
G01X1253483D01*
G03X1253576Y1540663I0J200D01*
G02X1254275Y1540836I700J-1329D01*
G02Y1537832I0J-1502D01*
G02X1253576Y1538005I1J1502D01*
G03X1253483Y1538028I-93J-177D01*
G01X1247059D01*
G03X1246874Y1537904I0J-200D01*
G03X1246917Y1537687I185J-76D01*
G01X1247904Y1536699D01*
G03X1248046Y1536640I142J141D01*
G01X1249642D01*
G03X1249735Y1536663I0J200D01*
G02X1250434Y1536836I700J-1329D01*
G02Y1533832I0J-1502D01*
G02X1249735Y1534005I1J1502D01*
G03X1249642Y1534028I-93J-177D01*
G01X1248640D01*
G03X1248455Y1533904I0J-200D01*
G03X1248498Y1533687I185J-76D01*
G01X1249485Y1532699D01*
G03X1249627Y1532640I142J141D01*
G01X1253483D01*
G03X1253576Y1532663I0J200D01*
G02X1254275Y1532836I700J-1329D01*
G02Y1529832I0J-1502D01*
G02X1253576Y1530005I1J1502D01*
G03X1253483Y1530028I-93J-177D01*
G01X1250002D01*
G03X1249817Y1529904I0J-200D01*
G01X1249793Y1529848D01*
X1249817Y1529730D01*
X1250259Y1529288D01*
G03X1250339Y1529239I142J141D01*
G01X1250340D01*
G02X1251396Y1527805I-446J-1434D01*
G02X1249894Y1526303I-1502J0D01*
G02X1248460Y1527358I0J1502D01*
G01Y1527360D01*
G03X1248411Y1527440I-190J-62D01*
G01X1243088Y1532763D01*
G03X1242946Y1532822I-142J-141D01*
G01X1239070D01*
G02X1238146Y1533205I0J1306D01*
G01X1223040Y1548311D01*
G02X1222658Y1549233I924J923D01*
G01Y1611435D01*
G03X1222599Y1611577I-200J0D01*
G37*
G36*
G01X1049510Y1223444D02*
G02X1049103Y1224472I1095J1028D01*
G02X1052107I1502J0D01*
G02X1051167Y1223079I-1502J0D01*
G03X1051025Y1222435I150J-371D01*
G02X1051432Y1221407I-1095J-1028D01*
G02X1048428I-1502J0D01*
G02X1049368Y1222800I1502J0D01*
G03X1049510Y1223444I-150J371D01*
G37*
G36*
G01X1048775Y1349375D02*
G02X1047991Y1350694I718J1319D01*
G02X1050995I1502J0D01*
G02X1050351Y1349461I-1502J0D01*
G03X1050388Y1348781I228J-329D01*
G02X1051172Y1347462I-718J-1319D01*
G02X1048168I-1502J0D01*
G02X1048812Y1348695I1502J0D01*
G03X1048775Y1349375I-228J329D01*
G37*
G36*
G01X1092696Y1598471D02*
X1092306Y1598400D01*
X1092234Y1598348D01*
X1092212Y1598309D01*
G02X1090904Y1597545I-1308J738D01*
G02Y1600549I0J1502D01*
G02X1091865Y1600201I0J-1501D01*
G01X1091900Y1600172D01*
X1091986Y1600150D01*
X1092376Y1600221D01*
X1092448Y1600273D01*
X1092470Y1600312D01*
G02X1093778Y1601076I1308J-738D01*
G02Y1598072I0J-1502D01*
G02X1092817Y1598420I0J1501D01*
G01X1092782Y1598449D01*
X1092696Y1598471D01*
G37*
G36*
G01X1092482Y1581529D02*
G02X1092180Y1582433I1200J903D01*
G02X1095184I1502J0D01*
G02X1093970Y1580959I-1502J0D01*
G03X1093727Y1580326I76J-392D01*
G02X1094029Y1579422I-1200J-903D01*
G02X1091025I-1502J0D01*
G02X1092239Y1580896I1502J0D01*
G03X1092482Y1581529I-76J392D01*
G37*
G36*
G01X1012434Y185330D02*
X1012569Y185710D01*
X1012559Y185800D01*
X1012535Y185839D01*
G02X1012310Y186629I1277J791D01*
G02X1015314I1502J0D01*
G02X1014311Y185212I-1502J0D01*
G01X1014267Y185197D01*
X1014204Y185133D01*
X1014069Y184753D01*
X1014079Y184663D01*
X1014103Y184624D01*
G02X1014328Y183834I-1277J-791D01*
G02X1011324I-1502J0D01*
G02X1012327Y185251I1502J0D01*
G01X1012371Y185266D01*
X1012434Y185330D01*
G37*
G36*
G01X1001453Y818566D02*
X1001062Y818567D01*
X1000985Y818532D01*
X1000955Y818499D01*
G02X999825Y817986I-1130J988D01*
G02Y820990I0J1502D01*
G02X1000964Y820467I0J-1502D01*
G01X1000993Y820433D01*
X1001071Y820397D01*
X1001462Y820396D01*
X1001539Y820431D01*
X1001569Y820464D01*
G02X1002699Y820977I1130J-988D01*
G02Y817973I0J-1502D01*
G02X1001560Y818496I0J1502D01*
G01X1001531Y818530D01*
X1001453Y818566D01*
G37*
G36*
G01X1001797Y833266D02*
X1001459D01*
X1001391Y833240D01*
X1001363Y833216D01*
G02X1000369Y832840I-994J1126D01*
G02Y835844I0J1502D01*
G02X1001363Y835468I0J-1502D01*
G01X1001391Y835444D01*
X1001459Y835418D01*
X1001797D01*
X1001865Y835444D01*
X1001893Y835468D01*
G02X1002887Y835844I994J-1126D01*
G02Y832840I0J-1502D01*
G02X1001893Y833216I0J1502D01*
G01X1001865Y833240D01*
X1001797Y833266D01*
G37*
G36*
G01X1010013Y842930D02*
X1010035Y843280D01*
X1010011Y843353D01*
X1009987Y843382D01*
G02X1009642Y844340I1158J958D01*
G02X1012646I1502J0D01*
G02X1012169Y843242I-1502J0D01*
G01X1012141Y843216D01*
X1012108Y843147D01*
X1012086Y842797D01*
X1012110Y842724D01*
X1012134Y842695D01*
G02X1012479Y841737I-1158J-958D01*
G02X1009475I-1502J0D01*
G02X1009952Y842835I1502J0D01*
G01X1009980Y842861D01*
X1010013Y842930D01*
G37*
G36*
G01X1004761Y876201D02*
Y876517D01*
G03X1004684Y876674I-200J-1D01*
G02X1004105Y877859I923J1185D01*
G02X1007109I1502J0D01*
G02X1006530Y876674I-1502J0D01*
G03X1006453Y876517I123J-158D01*
G01Y876201D01*
G03X1006530Y876044I200J1D01*
G02X1007109Y874859I-923J-1185D01*
G02X1004105I-1502J0D01*
G02X1004684Y876044I1502J0D01*
G03X1004761Y876201I-123J158D01*
G37*
G36*
G01X989558Y896156D02*
X989219Y896034D01*
X989161Y895982D01*
X989144Y895946D01*
G02X987790Y895094I-1354J650D01*
G02Y898098I0J1502D01*
G02X988418Y897960I-1J-1502D01*
G01X988455Y897944D01*
X988532Y897940D01*
X988871Y898062D01*
X988929Y898114D01*
X988946Y898150D01*
G02X990300Y899002I1354J-650D01*
G02Y895998I0J-1502D01*
G02X989672Y896136I1J1502D01*
G01X989635Y896152D01*
X989558Y896156D01*
G37*
G36*
G01X1003070Y764711D02*
G02X1002488Y765899I920J1187D01*
G02X1005492I1502J0D01*
G02X1004553Y764507I-1501J0D01*
G03X1004459Y763820I151J-371D01*
G02X1005041Y762632I-920J-1187D01*
G02X1002037I-1502J0D01*
G02X1002976Y764024I1501J0D01*
G03X1003070Y764711I-151J371D01*
G37*
G36*
G01X1013568Y812038D02*
X1013513Y812050D01*
G02X1012319Y813520I308J1470D01*
G02X1015323I1502J0D01*
G02X1014887Y812462I-1502J0D01*
G01X1014848Y812423D01*
X1014822Y812317D01*
X1014955Y811874D01*
X1015034Y811801D01*
X1015089Y811789D01*
G02X1016283Y810319I-308J-1470D01*
G02X1016067Y809543I-1502J0D01*
G01X1016043Y809504D01*
X1016035Y809414D01*
X1016173Y809035D01*
X1016238Y808972D01*
X1016281Y808958D01*
G02X1017302Y807535I-481J-1423D01*
G02X1014298I-1502J0D01*
G02X1014514Y808311I1502J0D01*
G01X1014538Y808350D01*
X1014546Y808440D01*
X1014408Y808819D01*
X1014343Y808882D01*
X1014300Y808896D01*
G02X1013279Y810319I481J1423D01*
G02X1013715Y811377I1502J0D01*
G01X1013754Y811416D01*
X1013780Y811522D01*
X1013647Y811965D01*
X1013568Y812038D01*
G37*
G36*
G01X996335Y887602D02*
G02X995133Y887001I-1202J901D01*
G02Y890005I0J1502D01*
G02X996442Y889239I0J-1501D01*
G03X997111Y889196I349J196D01*
G02X998313Y889797I1202J-901D01*
G02Y886793I0J-1502D01*
G02X997004Y887559I0J1501D01*
G03X996335Y887602I-349J-196D01*
G37*
G36*
G01X1036584Y298557D02*
G02X1036566Y298791I1484J232D01*
G01Y298810D01*
G02X1038068Y300291I1502J-21D01*
G02X1039570Y298789I0J-1502D01*
G02X1038941Y297567I-1502J0D01*
G03X1038862Y297448I116J-163D01*
G01X1038836Y297328D01*
G03X1038857Y297186I195J-44D01*
G02X1039094Y296293I-1566J-894D01*
G02X1037291Y294490I-1803J0D01*
G01X1033891D01*
G02X1032088Y296293I0J1803D01*
G02X1032325Y297185I1803J-1D01*
G03X1032346Y297328I-174J99D01*
G01X1032319Y297447D01*
G03X1032240Y297566I-195J-44D01*
G02X1031610Y298789I872J1223D01*
G02X1033112Y300291I1502J0D01*
G02X1034614Y298810I0J-1502D01*
G01Y298791D01*
G02X1034596Y298557I-1502J-2D01*
G01X1034589Y298514D01*
X1034613Y298430D01*
X1034839Y298165D01*
G03X1034991Y298096I151J131D01*
G01X1036189D01*
G03X1036341Y298165I1J200D01*
G01X1036567Y298430D01*
X1036591Y298514D01*
X1036584Y298557D01*
G37*
G36*
G01X1028174Y288283D02*
G02X1027216Y287938I-958J1158D01*
G02Y290942I0J1502D01*
G02X1028602Y290019I0J-1502D01*
G03X1029226Y289866I369J155D01*
G02X1030184Y290211I958J-1158D01*
G02Y287207I0J-1502D01*
G02X1028798Y288130I0J1502D01*
G03X1028174Y288283I-369J-155D01*
G37*
G36*
G01X1279538Y292294D02*
G02Y295298I0J1502D01*
G02X1280525Y294928I0J-1501D01*
G01X1280526D01*
Y294927D01*
G03X1280656Y294879I130J152D01*
G01X1280920D01*
G03X1281050Y294927I0J200D01*
G01X1281051Y294928D01*
G02X1282038Y295298I987J-1131D01*
G02Y292294I0J-1502D01*
G02X1281051Y292664I0J1501D01*
G01X1281050D01*
Y292665D01*
G03X1280920Y292713I-130J-152D01*
G01X1280656D01*
G03X1280526Y292665I0J-200D01*
G01X1280525Y292664D01*
G02X1279538Y292294I-987J1131D01*
G37*
G36*
G01X1177176D02*
G02Y295298I0J1502D01*
G02X1178163Y294928I0J-1501D01*
G01X1178164D01*
Y294927D01*
G03X1178294Y294879I130J152D01*
G01X1178558D01*
G03X1178688Y294927I0J200D01*
G01X1178689Y294928D01*
G02X1179676Y295298I987J-1131D01*
G02Y292294I0J-1502D01*
G02X1178689Y292664I0J1501D01*
G01X1178688D01*
Y292665D01*
G03X1178558Y292713I-130J-152D01*
G01X1178294D01*
G03X1178164Y292665I0J-200D01*
G01X1178163Y292664D01*
G02X1177176Y292294I-987J1131D01*
G37*
G36*
G01X1074814D02*
G02Y295298I0J1502D01*
G02X1075801Y294928I0J-1501D01*
G01X1075802D01*
Y294927D01*
G03X1075932Y294879I130J152D01*
G01X1076196D01*
G03X1076326Y294927I0J200D01*
G01X1076327Y294928D01*
G02X1077314Y295298I987J-1131D01*
G02Y292294I0J-1502D01*
G02X1076327Y292664I0J1501D01*
G01X1076326D01*
Y292665D01*
G03X1076196Y292713I-130J-152D01*
G01X1075932D01*
G03X1075802Y292665I0J-200D01*
G01X1075801Y292664D01*
G02X1074814Y292294I-987J1131D01*
G37*
G36*
G01X1209835Y292098D02*
Y292392D01*
G03X1209770Y292539I-200J-1D01*
G02X1209285Y293645I1019J1106D01*
G02X1210787Y295147I1502J0D01*
G02X1211774Y294777I0J-1501D01*
G01X1211775D01*
Y294776D01*
G03X1211905Y294728I130J152D01*
G01X1212169D01*
G03X1212299Y294776I0J200D01*
G01X1212300Y294777D01*
G02X1213287Y295147I987J-1131D01*
G02X1214789Y293645I0J-1502D01*
G02X1214304Y292539I-1504J0D01*
G03X1214239Y292392I135J-148D01*
G01Y292098D01*
G03X1214304Y291951I200J1D01*
G02X1214789Y290845I-1019J-1106D01*
G02X1214419Y289858I-1501J0D01*
G01Y289857D01*
X1214418D01*
G03X1214370Y289727I152J-130D01*
G01Y289463D01*
G03X1214418Y289333I200J0D01*
G01X1214419Y289332D01*
G02X1214789Y288345I-1131J-987D01*
G02X1213287Y286843I-1502J0D01*
G02X1212300Y287213I0J1501D01*
G01X1212299D01*
Y287214D01*
G03X1212169Y287262I-130J-152D01*
G01X1211905D01*
G03X1211775Y287214I0J-200D01*
G01X1211774Y287213D01*
G02X1210787Y286843I-987J1131D01*
G02X1209285Y288345I0J1502D01*
G02X1209655Y289332I1501J0D01*
G01Y289333D01*
X1209656D01*
G03X1209704Y289463I-152J130D01*
G01Y289727D01*
G03X1209656Y289857I-200J0D01*
G01X1209655Y289858D01*
G02X1209285Y290845I1131J987D01*
G02X1209770Y291951I1504J0D01*
G03X1209835Y292098I-135J148D01*
G37*
G36*
G01X1107473D02*
Y292392D01*
G03X1107408Y292539I-200J-1D01*
G02X1106923Y293645I1019J1106D01*
G02X1108425Y295147I1502J0D01*
G02X1109412Y294777I0J-1501D01*
G01X1109413D01*
Y294776D01*
G03X1109543Y294728I130J152D01*
G01X1109807D01*
G03X1109937Y294776I0J200D01*
G01X1109938Y294777D01*
G02X1110925Y295147I987J-1131D01*
G02X1112427Y293645I0J-1502D01*
G02X1111942Y292539I-1504J0D01*
G03X1111877Y292392I135J-148D01*
G01Y292098D01*
G03X1111942Y291951I200J1D01*
G02X1112427Y290845I-1019J-1106D01*
G02X1112057Y289858I-1501J0D01*
G01Y289857D01*
X1112056D01*
G03X1112008Y289727I152J-130D01*
G01Y289463D01*
G03X1112056Y289333I200J0D01*
G01X1112057Y289332D01*
G02X1112427Y288345I-1131J-987D01*
G02X1110925Y286843I-1502J0D01*
G02X1109938Y287213I0J1501D01*
G01X1109937D01*
Y287214D01*
G03X1109807Y287262I-130J-152D01*
G01X1109543D01*
G03X1109413Y287214I0J-200D01*
G01X1109412Y287213D01*
G02X1108425Y286843I-987J1131D01*
G02X1106923Y288345I0J1502D01*
G02X1107293Y289332I1501J0D01*
G01Y289333D01*
X1107294D01*
G03X1107342Y289463I-152J130D01*
G01Y289727D01*
G03X1107294Y289857I-200J0D01*
G01X1107293Y289858D01*
G02X1106923Y290845I1131J987D01*
G02X1107408Y291951I1504J0D01*
G03X1107473Y292098I-135J148D01*
G37*
G36*
G01X1005111D02*
Y292392D01*
G03X1005046Y292539I-200J-1D01*
G02X1004561Y293645I1019J1106D01*
G02X1006063Y295147I1502J0D01*
G02X1007050Y294777I0J-1501D01*
G01X1007051D01*
Y294776D01*
G03X1007181Y294728I130J152D01*
G01X1007445D01*
G03X1007575Y294776I0J200D01*
G01X1007576Y294777D01*
G02X1008563Y295147I987J-1131D01*
G02X1010065Y293645I0J-1502D01*
G02X1009580Y292539I-1504J0D01*
G03X1009515Y292392I135J-148D01*
G01Y292098D01*
G03X1009580Y291951I200J1D01*
G02X1010065Y290845I-1019J-1106D01*
G02X1009695Y289858I-1501J0D01*
G01Y289857D01*
X1009694D01*
G03X1009646Y289727I152J-130D01*
G01Y289463D01*
G03X1009694Y289333I200J0D01*
G01X1009695Y289332D01*
G02X1010065Y288345I-1131J-987D01*
G02X1008563Y286843I-1502J0D01*
G02X1007576Y287213I0J1501D01*
G01X1007575D01*
Y287214D01*
G03X1007445Y287262I-130J-152D01*
G01X1007181D01*
G03X1007051Y287214I0J-200D01*
G01X1007050Y287213D01*
G02X1006063Y286843I-987J1131D01*
G02X1004561Y288345I0J1502D01*
G02X1004931Y289332I1501J0D01*
G01Y289333D01*
X1004932D01*
G03X1004980Y289463I-152J130D01*
G01Y289727D01*
G03X1004932Y289857I-200J0D01*
G01X1004931Y289858D01*
G02X1004561Y290845I1131J987D01*
G02X1005046Y291951I1504J0D01*
G03X1005111Y292098I-135J148D01*
G37*
G36*
G01X1290052Y289692D02*
G02X1291158Y289207I0J-1504D01*
G03X1291305Y289142I148J135D01*
G01X1291599D01*
G03X1291746Y289207I-1J200D01*
G02X1292852Y289692I1106J-1019D01*
G02X1294354Y288190I0J-1502D01*
G02X1293984Y287203I-1501J0D01*
G01Y287202D01*
X1293983D01*
G03X1293935Y287072I152J-130D01*
G01Y286808D01*
G03X1293983Y286678I200J0D01*
G01X1293984Y286677D01*
G02X1294354Y285690I-1131J-987D01*
G02X1292852Y284188I-1502J0D01*
G02X1291746Y284673I0J1504D01*
G03X1291599Y284738I-148J-135D01*
G01X1291305D01*
G03X1291158Y284673I1J-200D01*
G02X1290052Y284188I-1106J1019D01*
G02X1289065Y284558I0J1501D01*
G01X1289064D01*
Y284559D01*
G03X1288934Y284607I-130J-152D01*
G01X1288670D01*
G03X1288540Y284559I0J-200D01*
G01X1288539Y284558D01*
G02X1287552Y284188I-987J1131D01*
G02X1286050Y285690I0J1502D01*
G02X1286420Y286677I1501J0D01*
G01Y286678D01*
X1286421D01*
G03X1286469Y286808I-152J130D01*
G01Y287072D01*
G03X1286421Y287202I-200J0D01*
G01X1286420Y287203D01*
G02X1286050Y288190I1131J987D01*
G02X1287552Y289692I1502J0D01*
G02X1288539Y289322I0J-1501D01*
G01X1288540D01*
Y289321D01*
G03X1288670Y289273I130J152D01*
G01X1288934D01*
G03X1289064Y289321I0J200D01*
G01X1289065Y289322D01*
G02X1290052Y289692I987J-1131D01*
G37*
G36*
G01X1187690D02*
G02X1188796Y289207I0J-1504D01*
G03X1188943Y289142I148J135D01*
G01X1189237D01*
G03X1189384Y289207I-1J200D01*
G02X1190490Y289692I1106J-1019D01*
G02X1191992Y288190I0J-1502D01*
G02X1191622Y287203I-1501J0D01*
G01Y287202D01*
X1191621D01*
G03X1191573Y287072I152J-130D01*
G01Y286808D01*
G03X1191621Y286678I200J0D01*
G01X1191622Y286677D01*
G02X1191992Y285690I-1131J-987D01*
G02X1190490Y284188I-1502J0D01*
G02X1189384Y284673I0J1504D01*
G03X1189237Y284738I-148J-135D01*
G01X1188943D01*
G03X1188796Y284673I1J-200D01*
G02X1187690Y284188I-1106J1019D01*
G02X1186703Y284558I0J1501D01*
G01X1186702D01*
Y284559D01*
G03X1186572Y284607I-130J-152D01*
G01X1186308D01*
G03X1186178Y284559I0J-200D01*
G01X1186177Y284558D01*
G02X1185190Y284188I-987J1131D01*
G02X1183688Y285690I0J1502D01*
G02X1184058Y286677I1501J0D01*
G01Y286678D01*
X1184059D01*
G03X1184107Y286808I-152J130D01*
G01Y287072D01*
G03X1184059Y287202I-200J0D01*
G01X1184058Y287203D01*
G02X1183688Y288190I1131J987D01*
G02X1185190Y289692I1502J0D01*
G02X1186177Y289322I0J-1501D01*
G01X1186178D01*
Y289321D01*
G03X1186308Y289273I130J152D01*
G01X1186572D01*
G03X1186702Y289321I0J200D01*
G01X1186703Y289322D01*
G02X1187690Y289692I987J-1131D01*
G37*
G36*
G01X1085328D02*
G02X1086434Y289207I0J-1504D01*
G03X1086581Y289142I148J135D01*
G01X1086875D01*
G03X1087022Y289207I-1J200D01*
G02X1088128Y289692I1106J-1019D01*
G02X1089630Y288190I0J-1502D01*
G02X1089260Y287203I-1501J0D01*
G01Y287202D01*
X1089259D01*
G03X1089211Y287072I152J-130D01*
G01Y286808D01*
G03X1089259Y286678I200J0D01*
G01X1089260Y286677D01*
G02X1089630Y285690I-1131J-987D01*
G02X1088128Y284188I-1502J0D01*
G02X1087022Y284673I0J1504D01*
G03X1086875Y284738I-148J-135D01*
G01X1086581D01*
G03X1086434Y284673I1J-200D01*
G02X1085328Y284188I-1106J1019D01*
G02X1084341Y284558I0J1501D01*
G01X1084340D01*
Y284559D01*
G03X1084210Y284607I-130J-152D01*
G01X1083946D01*
G03X1083816Y284559I0J-200D01*
G01X1083815Y284558D01*
G02X1082828Y284188I-987J1131D01*
G02X1081326Y285690I0J1502D01*
G02X1081696Y286677I1501J0D01*
G01Y286678D01*
X1081697D01*
G03X1081745Y286808I-152J130D01*
G01Y287072D01*
G03X1081697Y287202I-200J0D01*
G01X1081696Y287203D01*
G02X1081326Y288190I1131J987D01*
G02X1082828Y289692I1502J0D01*
G02X1083815Y289322I0J-1501D01*
G01X1083816D01*
Y289321D01*
G03X1083946Y289273I130J152D01*
G01X1084210D01*
G03X1084340Y289321I0J200D01*
G01X1084341Y289322D01*
G02X1085328Y289692I987J-1131D01*
G37*
G36*
G01X1238055Y302337D02*
G02Y305341I0J1502D01*
G02X1239266Y304728I0J-1503D01*
G03X1239928Y304753I323J236D01*
G02X1241205Y305464I1277J-791D01*
G02Y302460I0J-1502D01*
G02X1239994Y303073I0J1503D01*
G03X1239332Y303048I-323J-236D01*
G02X1238055Y302337I-1277J791D01*
G37*
G36*
G01X1264167Y302729D02*
G02X1264089Y302252I-1502J1D01*
G01X1264073Y302206D01*
X1264088Y302111D01*
X1264336Y301768D01*
X1264422Y301725D01*
X1264481D01*
G02X1264942Y301653I2J-1502D01*
G01X1264990Y301637D01*
X1265087Y301655D01*
X1265388Y301890D01*
G03X1265464Y302061I-124J157D01*
G02X1265460Y302167I1498J110D01*
G02X1266962Y300665I1502J0D01*
G01X1266959D01*
G02X1266501Y300737I1J1502D01*
G01X1266453Y300753D01*
X1266356Y300735D01*
X1266055Y300500D01*
G03X1265979Y300329I124J-157D01*
G02X1265983Y300223I-1498J-110D01*
G02X1262979I-1502J0D01*
G01Y300224D01*
G02X1263057Y300701I1502J-1D01*
G01X1263073Y300747D01*
X1263058Y300842D01*
X1262810Y301185D01*
X1262724Y301228D01*
X1262665D01*
G02X1264167Y302730I0J1502D01*
G01Y302729D01*
G37*
G36*
G01X1258925Y322573D02*
G02Y325577I0J1502D01*
G02X1260169Y324917I0J-1502D01*
G03X1260831I331J224D01*
G02X1262075Y325577I1244J-842D01*
G02Y322573I0J-1502D01*
G02X1260831Y323233I0J1502D01*
G03X1260169I-331J-224D01*
G02X1258925Y322573I-1244J842D01*
G37*
G36*
G01X1266106Y321044D02*
X1266104D01*
G03X1265911Y321010I-66J-188D01*
G01X1265602Y320758D01*
X1265565Y320661D01*
X1265573Y320608D01*
G02X1265590Y320383I-1485J-225D01*
G01Y320382D01*
G02X1264088Y318880I-1502J0D01*
G02X1263653Y318945I2J1502D01*
G01X1263652D01*
G03X1263463Y318904I-57J-191D01*
G01X1263168Y318646D01*
X1263134Y318549D01*
X1263142Y318498D01*
G02X1263161Y318258I-1483J-238D01*
G02X1261659Y319760I-1502J0D01*
G02X1262094Y319695I-2J-1502D01*
G01X1262095D01*
G03X1262284Y319736I57J191D01*
G01X1262579Y319994D01*
X1262613Y320091D01*
X1262605Y320142D01*
G02X1262586Y320382I1483J238D01*
G02X1264088Y321884I1502J0D01*
G02X1264598Y321794I-2J-1502D01*
G01X1264600D01*
G03X1264793Y321828I66J188D01*
G01X1265102Y322080D01*
X1265139Y322177D01*
X1265131Y322230D01*
G02X1265114Y322455I1485J225D01*
G01Y322456D01*
G02X1266616Y320954I1502J0D01*
G02X1266106Y321044I2J1502D01*
G37*
G36*
G01X1261998Y336000D02*
G02X1265002I1502J0D01*
G02X1264735Y335145I-1502J0D01*
G01X1264710Y335109D01*
X1264695Y335024D01*
X1264780Y334689D01*
G03X1264885Y334559I194J49D01*
G02X1265717Y333215I-670J-1344D01*
G02X1264270Y331714I-1502J0D01*
G01X1264269D01*
G03X1264110Y331625I7J-200D01*
G01X1263903Y331316D01*
X1263892Y331221D01*
X1263909Y331176D01*
G02X1264002Y330656I-1409J-520D01*
G01Y330655D01*
G02X1262500Y329153I-1502J0D01*
G02X1261505Y329530I0J1502D01*
G01X1261469Y329562D01*
X1261376Y329586D01*
X1260967Y329496D01*
X1260893Y329437D01*
X1260874Y329393D01*
G02X1259500Y328498I-1374J607D01*
G02Y331502I0J1502D01*
G02X1260495Y331125I0J-1502D01*
G01X1260531Y331093D01*
X1260624Y331069D01*
X1261033Y331159D01*
X1261107Y331218D01*
X1261126Y331262D01*
G02X1262445Y332156I1374J-607D01*
G01X1262446D01*
G03X1262605Y332245I-7J200D01*
G01X1262812Y332554D01*
X1262823Y332649D01*
X1262806Y332694D01*
G02X1262713Y333214I1409J520D01*
G01Y333215D01*
G02X1262980Y334070I1502J0D01*
G01X1263005Y334106D01*
X1263020Y334191D01*
X1262935Y334526D01*
G03X1262830Y334656I-194J-49D01*
G02X1261998Y336000I670J1344D01*
G37*
G36*
G01X1257131Y338988D02*
X1257132Y338987D01*
G02X1257502Y338000I-1131J-987D01*
G02X1254498I-1502J0D01*
G02X1254868Y338987I1501J0D01*
G01Y338988D01*
X1254869D01*
G03X1254917Y339118I-152J130D01*
G01Y339382D01*
G03X1254869Y339512I-200J0D01*
G01X1254868Y339513D01*
G02X1254498Y340500I1131J987D01*
G02X1257502I1502J0D01*
G02X1257132Y339513I-1501J0D01*
G01Y339512D01*
X1257131D01*
G03X1257083Y339382I152J-130D01*
G01Y339118D01*
G03X1257131Y338988I200J0D01*
G37*
G36*
G01X1303314Y329531D02*
X1303312D01*
X1303277Y329523D01*
X1303217Y329485D01*
X1303015Y329216D01*
X1302995Y329146D01*
X1302998Y329110D01*
G02X1303002Y329000I-1498J-110D01*
G02X1302962Y328654I-1502J-2D01*
G01Y328653D01*
G03X1302989Y328498I195J-46D01*
G01X1303147Y328255D01*
G03X1303277Y328168I167J109D01*
G02X1304502Y326692I-277J-1476D01*
G02X1301498I-1502J0D01*
G01Y326695D01*
G02X1301538Y327038I1502J-1D01*
G01Y327039D01*
G03X1301511Y327194I-195J46D01*
G01X1301353Y327437D01*
G03X1301223Y327524I-167J-109D01*
G02X1299998Y329000I277J1476D01*
G02X1301186Y330469I1502J0D01*
G01X1301188D01*
X1301223Y330477D01*
X1301283Y330515D01*
X1301485Y330784D01*
X1301505Y330854D01*
X1301502Y330890D01*
G02X1301498Y330999I1498J110D01*
G01Y331000D01*
G02X1304502I1502J0D01*
G02X1303314Y329531I-1502J0D01*
G37*
G36*
G01X1290998Y335000D02*
G02X1294002I1502J0D01*
G02X1293408Y333804I-1501J0D01*
G03X1293457Y333135I242J-319D01*
G02X1294233Y331820I-726J-1315D01*
G02X1291229I-1502J0D01*
G02X1291823Y333016I1501J0D01*
G03X1291774Y333685I-242J319D01*
G02X1290998Y335000I726J1315D01*
G37*
G36*
G01X1300400Y343073D02*
G02Y346077I0J1502D01*
G02X1301623Y345447I0J-1502D01*
G03X1301743Y345368I163J116D01*
G01X1301861Y345341D01*
G03X1302004Y345363I43J195D01*
G02X1302893Y345598I890J-1568D01*
G01X1302896D01*
G02X1304698Y343796I0J-1802D01*
G01Y340396D01*
G02X1302896Y338594I-1802J0D01*
G01X1302894D01*
G02X1302003Y338830I1J1802D01*
G03X1301860Y338852I-100J-173D01*
G01X1301742Y338825D01*
G03X1301622Y338746I43J-195D01*
G02X1300400Y338117I-1222J873D01*
G02Y341121I0J1502D01*
G02X1300632Y341103I0J-1502D01*
G03X1300793Y341149I31J198D01*
G01X1301024Y341346D01*
G03X1301094Y341498I-130J152D01*
G01Y342696D01*
G03X1301024Y342848I-200J0D01*
G01X1300793Y343045D01*
G03X1300632Y343091I-130J-152D01*
G02X1300400Y343073I-232J1484D01*
G37*
G36*
G01X1313451Y319096D02*
G03X1313581Y319144I0J200D01*
G01X1313582Y319145D01*
G02X1314569Y319515I987J-1131D01*
G02Y316511I0J-1502D01*
G02X1313582Y316881I0J1501D01*
G01X1313581D01*
Y316882D01*
G03X1313451Y316930I-130J-152D01*
G01X1313187D01*
G03X1313057Y316882I0J-200D01*
G01X1313056Y316881D01*
G02X1312069Y316511I-987J1131D01*
G02Y319515I0J1502D01*
G02X1313056Y319145I0J-1501D01*
G01X1313057D01*
Y319144D01*
G03X1313187Y319096I130J152D01*
G01X1313451D01*
G37*
G36*
G01X1308410Y369397D02*
G02Y372401I0J1502D01*
G02X1309578Y371843I0J-1501D01*
G01X1309605Y371809D01*
X1309683Y371770D01*
X1310073Y371758D01*
X1310152Y371790D01*
X1310182Y371823D01*
G02X1311283Y372303I1101J-1023D01*
G02Y369299I0J-1502D01*
G02X1310115Y369857I0J1501D01*
G01X1310088Y369891D01*
X1310010Y369930D01*
X1309620Y369942D01*
X1309541Y369910D01*
X1309511Y369877D01*
G02X1308410Y369397I-1101J1023D01*
G37*
G36*
G01X1038256Y147959D02*
X1038235Y147998D01*
G02X1038052Y148717I1319J719D01*
G02X1041056I1502J0D01*
G02X1040051Y147300I-1501J0D01*
G01X1040009Y147285D01*
X1039946Y147224D01*
X1039805Y146857D01*
X1039811Y146770D01*
X1039832Y146731D01*
G02X1040015Y146012I-1319J-719D01*
G02X1039355Y144768I-1502J0D01*
G03X1039267Y144603I112J-166D01*
G01Y144271D01*
G03X1039355Y144106I200J1D01*
G02X1040000Y143074I-842J-1244D01*
G01X1040005Y143037D01*
X1040039Y142974D01*
X1040297Y142754D01*
X1040363Y142729D01*
X1040401Y142730D01*
X1040419D01*
G02Y139726I0J-1502D01*
G02X1038932Y141016I0J1502D01*
G01X1038927Y141053D01*
X1038893Y141116D01*
X1038635Y141336D01*
X1038569Y141361D01*
X1038531Y141360D01*
X1038513D01*
G02X1037011Y142862I0J1502D01*
G02X1037671Y144106I1502J0D01*
G03X1037759Y144271I-112J166D01*
G01Y144603D01*
G03X1037671Y144768I-200J-1D01*
G02X1037011Y146012I842J1244D01*
G02X1038016Y147429I1501J0D01*
G01X1038058Y147444D01*
X1038121Y147505D01*
X1038262Y147872D01*
X1038256Y147959D01*
G37*
G36*
G01X1038114Y110018D02*
X1038430D01*
G03X1038587Y110095I-1J200D01*
G02X1039772Y110674I1185J-923D01*
G02X1041274Y109172I0J-1502D01*
G02X1040310Y107770I-1502J0D01*
G01X1040270Y107754D01*
X1040210Y107693D01*
X1040075Y107331D01*
X1040081Y107245D01*
X1040102Y107207D01*
G02X1040281Y106495I-1323J-711D01*
G02X1037277I-1502J0D01*
G02X1037415Y107123I1502J-1D01*
G01X1037438Y107173D01*
X1037426Y107283D01*
X1037149Y107653D01*
X1037047Y107694D01*
X1036993Y107686D01*
G02X1036772Y107670I-219J1486D01*
G02Y110674I0J1502D01*
G02X1037957Y110095I0J-1502D01*
G03X1038114Y110018I158J123D01*
G37*
G36*
G01X1050881Y105329D02*
X1050841Y105360D01*
G02X1050240Y106561I901J1202D01*
G02X1053244I1502J0D01*
G02X1052518Y105275I-1502J0D01*
G01X1052475Y105249D01*
X1052424Y105164D01*
X1052402Y104732D01*
X1052444Y104643D01*
X1052484Y104612D01*
G02X1053039Y103779I-901J-1202D01*
G01X1053051Y103731D01*
X1053117Y103658D01*
X1053520Y103509D01*
X1053616Y103522D01*
X1053657Y103550D01*
G02X1054523Y103825I866J-1226D01*
G02Y100821I0J-1502D01*
G02X1053067Y101955I0J1502D01*
G01X1053055Y102003D01*
X1052989Y102076D01*
X1052586Y102225D01*
X1052490Y102212D01*
X1052449Y102184D01*
G02X1051583Y101909I-866J1226D01*
G02X1050081Y103411I0J1502D01*
G02X1050807Y104697I1502J0D01*
G01X1050850Y104723D01*
X1050901Y104808D01*
X1050923Y105240D01*
X1050881Y105329D01*
G37*
G36*
G01X1107152Y102731D02*
G02X1106860Y103621I1210J890D01*
G02X1109864I1502J0D01*
G02X1108639Y102145I-1502J0D01*
G03X1108390Y101515I73J-393D01*
G02X1108682Y100625I-1210J-890D01*
G02X1105678I-1502J0D01*
G02X1106903Y102101I1502J0D01*
G03X1107152Y102731I-73J393D01*
G37*
G36*
G01X1071580Y101849D02*
G02X1070997Y103037I919J1188D01*
G02X1074001I1502J0D01*
G02X1073345Y101796I-1502J0D01*
G03X1073325Y101149I225J-331D01*
G02X1073908Y99961I-919J-1188D01*
G02X1070904I-1502J0D01*
G02X1071560Y101202I1502J0D01*
G03X1071580Y101849I-225J331D01*
G37*
G36*
G01X1066093Y91453D02*
G02X1065539Y91347I-554J1395D01*
G02X1067041Y92849I0J1502D01*
G02X1066995Y92481I-1502J1D01*
G03X1067531Y92011I388J-98D01*
G02X1068085Y92117I554J-1395D01*
G02X1066583Y90615I0J-1502D01*
G02X1066629Y90983I1502J-1D01*
G03X1066093Y91453I-388J98D01*
G37*
G36*
G01X1116932Y90701D02*
G02X1116262Y91951I831J1250D01*
G02X1119266I1502J0D01*
G02X1118616Y90714I-1502J0D01*
G03X1118621Y90051I227J-330D01*
G02X1119291Y88801I-831J-1250D01*
G02X1116287I-1502J0D01*
G02X1116937Y90038I1502J0D01*
G03X1116932Y90701I-227J330D01*
G37*
G36*
G01X1028341Y217133D02*
X1028047D01*
G03X1027900Y217068I1J-200D01*
G02X1026794Y216583I-1105J1017D01*
G02Y219587I0J1502D01*
G02X1027900Y219102I1J-1502D01*
G03X1028047Y219037I148J135D01*
G01X1028341D01*
G03X1028488Y219102I-1J200D01*
G02X1029594Y219587I1105J-1017D01*
G02Y216583I0J-1502D01*
G02X1028488Y217068I-1J1502D01*
G03X1028341Y217133I-148J-135D01*
G37*
G36*
G01X1034521Y205755D02*
X1034185D01*
X1034118Y205730D01*
X1034090Y205706D01*
G02X1033103Y205336I-987J1131D01*
G02Y208340I0J1502D01*
G02X1034090Y207970I0J-1501D01*
G01X1034118Y207946D01*
X1034185Y207921D01*
X1034521D01*
X1034588Y207946D01*
X1034616Y207970D01*
G02X1035603Y208340I987J-1131D01*
G02Y205336I0J-1502D01*
G02X1034616Y205706I0J1501D01*
G01X1034588Y205730D01*
X1034521Y205755D01*
G37*
G36*
G01X1028333Y202310D02*
X1027997D01*
X1027930Y202285D01*
X1027902Y202261D01*
G02X1026915Y201891I-987J1131D01*
G02Y204895I0J1502D01*
G02X1027902Y204525I0J-1501D01*
G01X1027930Y204501D01*
X1027997Y204476D01*
X1028333D01*
X1028400Y204501D01*
X1028428Y204525D01*
G02X1029415Y204895I987J-1131D01*
G02X1030912Y203517I0J-1502D01*
G01X1030915Y203474D01*
X1030956Y203400D01*
X1031263Y203168D01*
X1031344Y203149D01*
X1031387Y203157D01*
G02X1031674Y203185I289J-1474D01*
G02X1033176Y201683I0J-1502D01*
G02X1032691Y200577I-1502J-1D01*
G03X1032626Y200430I135J-148D01*
G01Y200136D01*
G03X1032691Y199989I200J1D01*
G02X1033176Y198883I-1017J-1105D01*
G02X1030172I-1502J0D01*
G02X1030657Y199989I1502J1D01*
G03X1030722Y200136I-135J148D01*
G01Y200430D01*
G03X1030657Y200577I-200J-1D01*
G02X1030177Y201559I1017J1105D01*
G01X1030174Y201602D01*
X1030133Y201676D01*
X1029826Y201908D01*
X1029745Y201927D01*
X1029702Y201919D01*
G02X1029415Y201891I-289J1474D01*
G02X1028428Y202261I0J1501D01*
G01X1028400Y202285D01*
X1028333Y202310D01*
G37*
G36*
G01X1030637Y196259D02*
X1030973D01*
X1031040Y196284D01*
X1031068Y196308D01*
G02X1032055Y196678I987J-1131D01*
G02X1033161Y196193I1J-1502D01*
G03X1033308Y196128I148J135D01*
G01X1033602D01*
G03X1033749Y196193I-1J200D01*
G02X1034855Y196678I1105J-1017D01*
G02Y193674I0J-1502D01*
G02X1033749Y194159I-1J1502D01*
G03X1033602Y194224I-148J-135D01*
G01X1033308D01*
G03X1033161Y194159I1J-200D01*
G02X1032055Y193674I-1105J1017D01*
G02X1031068Y194044I0J1501D01*
G01X1031040Y194068D01*
X1030973Y194093D01*
X1030637D01*
X1030570Y194068D01*
X1030542Y194044D01*
G02X1028568I-987J1131D01*
G01X1028540Y194068D01*
X1028473Y194093D01*
X1028137D01*
X1028070Y194068D01*
X1028042Y194044D01*
G02X1027055Y193674I-987J1131D01*
G02Y196678I0J1502D01*
G02X1028042Y196308I0J-1501D01*
G01X1028070Y196284D01*
X1028137Y196259D01*
X1028473D01*
X1028540Y196284D01*
X1028568Y196308D01*
G02X1030542I987J-1131D01*
G01X1030570Y196284D01*
X1030637Y196259D01*
G37*
G36*
G01X1045472Y137670D02*
X1045788Y137881D01*
X1045833Y137950D01*
X1045840Y137992D01*
G02X1047323Y139259I1483J-234D01*
G02Y136255I0J-1502D01*
G02X1047055Y136279I-1J1502D01*
G03X1046889Y136234I-36J-197D01*
G01X1046793Y136151D01*
G03X1046724Y135991I131J-151D01*
G02X1046726Y135915I-1801J-85D01*
G01Y132515D01*
G02X1046724Y132436I-1803J6D01*
G03X1046793Y132276I200J-9D01*
G01X1046889Y132193D01*
G03X1047055Y132148I130J152D01*
G02X1047323Y132172I267J-1478D01*
G02X1048310Y131802I0J-1501D01*
G01X1048338Y131778D01*
X1048405Y131753D01*
X1048741D01*
X1048808Y131778D01*
X1048836Y131802D01*
G02X1049823Y132172I987J-1131D01*
G02X1051306Y130905I0J-1501D01*
G01X1051313Y130863D01*
X1051358Y130794D01*
X1051674Y130583D01*
X1051755Y130569D01*
X1051796Y130579D01*
G02X1052223Y130630I426J-1751D01*
G02X1052571Y130597I5J-1802D01*
G01X1052611Y130589D01*
X1052689Y130605D01*
X1052993Y130814D01*
X1053035Y130881D01*
X1053042Y130922D01*
G02X1054523Y132172I1481J-252D01*
G02Y129168I0J-1502D01*
G02X1054342Y129179I0J1502D01*
G03X1054184Y129128I-23J-199D01*
G01X1054090Y129043D01*
G03X1054024Y128888I134J-149D01*
G02X1054026Y128828I-1800J-90D01*
G01Y125428D01*
G02X1054024Y125365I-1802J26D01*
G03X1054090Y125210I200J-6D01*
G01X1054184Y125125D01*
G03X1054342Y125074I135J148D01*
G02X1054523Y125085I181J-1491D01*
G02Y122081I0J-1502D01*
G02X1053042Y123333I0J1502D01*
G01X1053035Y123374D01*
X1052992Y123441D01*
X1052689Y123651D01*
X1052611Y123667D01*
X1052570Y123659D01*
G02X1052223Y123626I-343J1769D01*
G02X1051797Y123677I0J1802D01*
G01X1051755Y123687D01*
X1051674Y123672D01*
X1051358Y123462D01*
X1051313Y123392D01*
X1051307Y123350D01*
G02X1049823Y122081I-1484J233D01*
G02X1048835Y122451I-1J1502D01*
G01X1048808Y122476D01*
X1048741Y122501D01*
X1048404D01*
X1048338Y122476D01*
X1048310Y122452D01*
G02X1047323Y122082I-987J1131D01*
G02X1047055Y122106I-1J1502D01*
G03X1046889Y122061I-36J-197D01*
G01X1046793Y121978D01*
G03X1046724Y121818I131J-151D01*
G02X1046726Y121742I-1801J-85D01*
G01Y118342D01*
G02X1046724Y118263I-1803J6D01*
G03X1046793Y118103I200J-9D01*
G01X1046889Y118020D01*
G03X1047055Y117975I130J152D01*
G02X1047323Y117999I267J-1478D01*
G02X1048310Y117629I0J-1501D01*
G01X1048338Y117605D01*
X1048405Y117580D01*
X1048741D01*
X1048808Y117605D01*
X1048836Y117629D01*
G02X1049823Y117999I987J-1131D01*
G02X1051306Y116732I0J-1501D01*
G01X1051313Y116690D01*
X1051358Y116621D01*
X1051674Y116410D01*
X1051755Y116396D01*
X1051796Y116406D01*
G02X1052223Y116458I430J-1751D01*
G02X1052571Y116424I0J-1803D01*
G01X1052611Y116416D01*
X1052689Y116432D01*
X1052993Y116641D01*
X1053035Y116708D01*
X1053042Y116749D01*
G02X1054523Y117998I1481J-254D01*
G02Y114994I0J-1502D01*
G02X1054342Y115005I0J1502D01*
G03X1054184Y114954I-23J-199D01*
G01X1054090Y114869D01*
G03X1054025Y114714I135J-148D01*
G02X1054026Y114655I-1802J-60D01*
G01Y111255D01*
G02X1054024Y111192I-1802J26D01*
G03X1054090Y111037I200J-6D01*
G01X1054184Y110952D01*
G03X1054342Y110901I135J148D01*
G02X1054523Y110912I181J-1491D01*
G02Y107908I0J-1502D01*
G02X1053042Y109160I0J1502D01*
G01X1053035Y109201D01*
X1052992Y109268D01*
X1052689Y109478D01*
X1052611Y109494D01*
X1052570Y109486D01*
G02X1052223Y109452I-348J1769D01*
G02X1051797Y109504I4J1803D01*
G01X1051755Y109514D01*
X1051674Y109499D01*
X1051358Y109289D01*
X1051313Y109219D01*
X1051307Y109177D01*
G02X1049823Y107908I-1484J233D01*
G02Y110912I0J1502D01*
G02X1050091Y110888I1J-1502D01*
G03X1050257Y110933I36J197D01*
G01X1050353Y111016D01*
G03X1050422Y111176I-131J151D01*
G02X1050420Y111255I1801J85D01*
G01Y114655D01*
G02X1050422Y114731I1803J-9D01*
G03X1050353Y114891I-200J9D01*
G01X1050257Y114974D01*
G03X1050091Y115019I-130J-152D01*
G02X1049823Y114995I-267J1478D01*
G02X1048836Y115365I0J1501D01*
G01X1048808Y115389D01*
X1048741Y115414D01*
X1048405D01*
X1048338Y115389D01*
X1048310Y115365D01*
G02X1047323Y114995I-987J1131D01*
G02X1045839Y116264I0J1502D01*
G01X1045833Y116306D01*
X1045788Y116376D01*
X1045472Y116586D01*
X1045391Y116601D01*
X1045349Y116591D01*
G02X1044923Y116540I-426J1751D01*
G02X1044497Y116591I0J1802D01*
G01X1044455Y116601D01*
X1044374Y116586D01*
X1044058Y116376D01*
X1044013Y116306D01*
X1044007Y116264D01*
G02X1042523Y114995I-1484J233D01*
G02Y117999I0J1502D01*
G02X1042791Y117975I1J-1502D01*
G03X1042957Y118020I36J197D01*
G01X1043053Y118103D01*
G03X1043122Y118263I-131J151D01*
G02X1043120Y118342I1801J85D01*
G01Y121742D01*
G02X1043122Y121818I1803J-9D01*
G03X1043053Y121978I-200J9D01*
G01X1042957Y122061D01*
G03X1042791Y122106I-130J-152D01*
G02X1042523Y122082I-267J1478D01*
G02Y125086I0J1502D01*
G02X1044006Y123819I0J-1501D01*
G01X1044013Y123777D01*
X1044058Y123708D01*
X1044374Y123497D01*
X1044455Y123483D01*
X1044496Y123493D01*
G02X1044923Y123544I426J-1751D01*
G02X1045350Y123493I1J-1802D01*
G01X1045391Y123483D01*
X1045472Y123497D01*
X1045788Y123708D01*
X1045833Y123777D01*
X1045840Y123819D01*
G02X1047323Y125086I1483J-234D01*
G02X1048311Y124716I1J-1502D01*
G01X1048338Y124691D01*
X1048405Y124666D01*
X1048742D01*
X1048808Y124691D01*
X1048836Y124715D01*
G02X1049823Y125085I987J-1131D01*
G02X1050091Y125061I1J-1502D01*
G03X1050257Y125106I36J197D01*
G01X1050353Y125189D01*
G03X1050422Y125349I-131J151D01*
G02X1050420Y125428I1801J85D01*
G01Y128828D01*
G02X1050422Y128904I1803J-9D01*
G03X1050353Y129064I-200J9D01*
G01X1050257Y129147D01*
G03X1050091Y129192I-130J-152D01*
G02X1049823Y129168I-267J1478D01*
G02X1048836Y129538I0J1501D01*
G01X1048808Y129562D01*
X1048741Y129587D01*
X1048405D01*
X1048338Y129562D01*
X1048310Y129538D01*
G02X1047323Y129168I-987J1131D01*
G02X1045839Y130437I0J1502D01*
G01X1045833Y130479D01*
X1045788Y130549D01*
X1045472Y130759D01*
X1045391Y130774D01*
X1045349Y130764D01*
G02X1044923Y130712I-430J1751D01*
G02X1044497Y130764I4J1803D01*
G01X1044455Y130774D01*
X1044374Y130759D01*
X1044058Y130549D01*
X1044013Y130479D01*
X1044007Y130437D01*
G02X1042523Y129168I-1484J233D01*
G02Y132172I0J1502D01*
G02X1042791Y132148I1J-1502D01*
G03X1042957Y132193I36J197D01*
G01X1043053Y132276D01*
G03X1043122Y132436I-131J151D01*
G02X1043120Y132515I1801J85D01*
G01Y135915D01*
G02X1043122Y135991I1803J-9D01*
G03X1043053Y136151I-200J9D01*
G01X1042957Y136234D01*
G03X1042791Y136279I-130J-152D01*
G02X1042523Y136255I-267J1478D01*
G02Y139259I0J1502D01*
G02X1044006Y137992I0J-1501D01*
G01X1044013Y137950D01*
X1044058Y137881D01*
X1044374Y137670D01*
X1044455Y137656D01*
X1044496Y137666D01*
G02X1044923Y137718I430J-1751D01*
G02X1045350Y137666I-3J-1803D01*
G01X1045391Y137656D01*
X1045472Y137670D01*
G37*
G36*
G01X1061943Y84108D02*
Y84460D01*
X1061915Y84529D01*
X1061889Y84557D01*
G02X1061483Y85584I1096J1027D01*
G02X1064487I1502J0D01*
G02X1064081Y84557I-1502J0D01*
G01X1064055Y84529D01*
X1064027Y84460D01*
Y84108D01*
X1064055Y84039D01*
X1064081Y84011D01*
G02Y81957I-1096J-1027D01*
G01X1064055Y81929D01*
X1064027Y81860D01*
Y81508D01*
X1064055Y81439D01*
X1064081Y81411D01*
G02Y79357I-1096J-1027D01*
G01X1064055Y79329D01*
X1064027Y79260D01*
Y78908D01*
X1064055Y78839D01*
X1064081Y78811D01*
G02Y76757I-1096J-1027D01*
G01X1064055Y76729D01*
X1064027Y76660D01*
Y76308D01*
X1064055Y76239D01*
X1064081Y76211D01*
G02X1064487Y75184I-1096J-1027D01*
G02X1061483I-1502J0D01*
G02X1061889Y76211I1502J0D01*
G01X1061915Y76239D01*
X1061943Y76308D01*
Y76660D01*
X1061915Y76729D01*
X1061889Y76757D01*
G02Y78811I1096J1027D01*
G01X1061915Y78839D01*
X1061943Y78908D01*
Y79260D01*
X1061915Y79329D01*
X1061889Y79357D01*
G02Y81411I1096J1027D01*
G01X1061915Y81439D01*
X1061943Y81508D01*
Y81860D01*
X1061915Y81929D01*
X1061889Y81957D01*
G02Y84011I1096J1027D01*
G01X1061915Y84039D01*
X1061943Y84108D01*
G37*
G36*
G01X1080278Y83717D02*
Y84069D01*
X1080250Y84138D01*
X1080224Y84166D01*
G02X1079818Y85193I1096J1027D01*
G02X1082822I1502J0D01*
G02X1082416Y84166I-1502J0D01*
G01X1082390Y84138D01*
X1082362Y84069D01*
Y83717D01*
X1082390Y83648D01*
X1082416Y83620D01*
G02Y81566I-1096J-1027D01*
G01X1082390Y81538D01*
X1082362Y81469D01*
Y81117D01*
X1082390Y81048D01*
X1082416Y81020D01*
G02Y78966I-1096J-1027D01*
G01X1082390Y78938D01*
X1082362Y78869D01*
Y78517D01*
X1082390Y78448D01*
X1082416Y78420D01*
G02Y76366I-1096J-1027D01*
G01X1082390Y76338D01*
X1082362Y76269D01*
Y75917D01*
X1082390Y75848D01*
X1082416Y75820D01*
G02X1082822Y74793I-1096J-1027D01*
G02X1079818I-1502J0D01*
G02X1080224Y75820I1502J0D01*
G01X1080250Y75848D01*
X1080278Y75917D01*
Y76269D01*
X1080250Y76338D01*
X1080224Y76366D01*
G02Y78420I1096J1027D01*
G01X1080250Y78448D01*
X1080278Y78517D01*
Y78869D01*
X1080250Y78938D01*
X1080224Y78966D01*
G02Y81020I1096J1027D01*
G01X1080250Y81048D01*
X1080278Y81117D01*
Y81469D01*
X1080250Y81538D01*
X1080224Y81566D01*
G02Y83620I1096J1027D01*
G01X1080250Y83648D01*
X1080278Y83717D01*
G37*
G36*
G01X1104707Y75446D02*
X1104335Y75386D01*
X1104266Y75341D01*
X1104242Y75306D01*
G02X1102993Y74638I-1249J834D01*
G02Y77642I0J1502D01*
G02X1103914Y77327I1J-1502D01*
G01X1103947Y77301D01*
X1104027Y77281D01*
X1104399Y77341D01*
X1104468Y77386D01*
X1104492Y77421D01*
G02X1105741Y78089I1249J-834D01*
G02Y75085I0J-1502D01*
G02X1104820Y75400I-1J1502D01*
G01X1104787Y75426D01*
X1104707Y75446D01*
G37*
G36*
G01X1036563Y236121D02*
G02X1039567I1502J0D01*
G02X1038917Y234884I-1502J0D01*
G03X1038923Y234222I227J-329D01*
G02X1039593Y232971I-833J-1251D01*
G02X1036589I-1502J0D01*
G02X1037239Y234208I1502J0D01*
G03X1037233Y234870I-227J329D01*
G02X1036563Y236121I833J1251D01*
G37*
G36*
G01X1034605Y221970D02*
G02X1037609I1502J0D01*
G02X1037239Y220983I-1501J0D01*
G01X1037215Y220955D01*
X1037190Y220888D01*
Y220552D01*
X1037215Y220485D01*
X1037239Y220457D01*
G02Y218483I-1131J-987D01*
G01X1037215Y218455D01*
X1037190Y218388D01*
Y218052D01*
X1037215Y217985D01*
X1037239Y217957D01*
G02X1037609Y216970I-1131J-987D01*
G02X1036107Y215468I-1502J0D01*
G02X1035252Y215735I0J1502D01*
G01X1035218Y215759D01*
X1035137Y215775D01*
X1034770Y215696D01*
X1034703Y215648D01*
X1034682Y215612D01*
G02X1033394Y214883I-1288J773D01*
G02Y217887I0J1502D01*
G02X1034249Y217620I0J-1502D01*
G01X1034283Y217596D01*
X1034364Y217580D01*
X1034731Y217659D01*
X1034798Y217707D01*
X1034819Y217743D01*
G02X1034975Y217957I1287J-774D01*
G01X1034999Y217985D01*
X1035024Y218052D01*
Y218388D01*
X1034999Y218455D01*
X1034975Y218483D01*
G02Y220457I1131J987D01*
G01X1034999Y220485D01*
X1035024Y220552D01*
Y220888D01*
X1034999Y220955D01*
X1034975Y220983D01*
G02X1034605Y221970I1131J987D01*
G37*
G36*
G01X1092303Y223294D02*
Y223630D01*
X1092278Y223697D01*
X1092254Y223725D01*
G02X1091884Y224712I1131J987D01*
G02X1094888I1502J0D01*
G02X1094518Y223725I-1501J0D01*
G01X1094494Y223697D01*
X1094469Y223630D01*
Y223294D01*
X1094494Y223227D01*
X1094518Y223199D01*
G02X1094888Y222212I-1131J-987D01*
G02X1091884I-1502J0D01*
G02X1092254Y223199I1501J0D01*
G01X1092278Y223227D01*
X1092303Y223294D01*
G37*
G36*
G01X1086978Y225189D02*
X1086684D01*
G03X1086537Y225124I1J-200D01*
G02X1085431Y224639I-1105J1017D01*
G02Y227643I0J1502D01*
G02X1086537Y227158I1J-1502D01*
G03X1086684Y227093I148J135D01*
G01X1086978D01*
G03X1087125Y227158I-1J200D01*
G02X1088231Y227643I1105J-1017D01*
G02Y224639I0J-1502D01*
G02X1087125Y225124I-1J1502D01*
G03X1086978Y225189I-148J-135D01*
G37*
G36*
G01X1070185Y229808D02*
Y230144D01*
X1070160Y230211D01*
X1070136Y230239D01*
G02X1069766Y231226I1131J987D01*
G02X1072770I1502J0D01*
G02X1072400Y230239I-1501J0D01*
G01X1072376Y230211D01*
X1072351Y230144D01*
Y229808D01*
X1072376Y229741D01*
X1072400Y229713D01*
G02Y227739I-1131J-987D01*
G01X1072376Y227711D01*
X1072351Y227644D01*
Y227308D01*
X1072376Y227241D01*
X1072400Y227213D01*
G02Y225239I-1131J-987D01*
G01X1072376Y225211D01*
X1072351Y225144D01*
Y224808D01*
X1072376Y224741D01*
X1072400Y224713D01*
G02X1072770Y223726I-1131J-987D01*
G02X1069766I-1502J0D01*
G02X1070136Y224713I1501J0D01*
G01X1070160Y224741D01*
X1070185Y224808D01*
Y225144D01*
X1070160Y225211D01*
X1070136Y225239D01*
G02Y227213I1131J987D01*
G01X1070160Y227241D01*
X1070185Y227308D01*
Y227644D01*
X1070160Y227711D01*
X1070136Y227739D01*
G02Y229713I1131J987D01*
G01X1070160Y229741D01*
X1070185Y229808D01*
G37*
G36*
G01X1080641Y230043D02*
Y230379D01*
X1080616Y230446D01*
X1080592Y230474D01*
G02X1080222Y231461I1131J987D01*
G02X1083226I1502J0D01*
G02X1082856Y230474I-1501J0D01*
G01X1082832Y230446D01*
X1082807Y230379D01*
Y230043D01*
X1082832Y229976D01*
X1082856Y229948D01*
G02Y227974I-1131J-987D01*
G01X1082832Y227946D01*
X1082807Y227879D01*
Y227543D01*
X1082832Y227476D01*
X1082856Y227448D01*
G02X1083226Y226461I-1131J-987D01*
G02X1082741Y225355I-1502J-1D01*
G03X1082676Y225208I135J-148D01*
G01Y224914D01*
G03X1082741Y224767I200J1D01*
G02X1083226Y223661I-1017J-1105D01*
G02X1080222I-1502J0D01*
G02X1080707Y224767I1502J1D01*
G03X1080772Y224914I-135J148D01*
G01Y225208D01*
G03X1080707Y225355I-200J-1D01*
G02X1080222Y226461I1017J1105D01*
G02X1080592Y227448I1501J0D01*
G01X1080616Y227476D01*
X1080641Y227543D01*
Y227879D01*
X1080616Y227946D01*
X1080592Y227974D01*
G02Y229948I1131J987D01*
G01X1080616Y229976D01*
X1080641Y230043D01*
G37*
G36*
G01X1088610Y230368D02*
Y230704D01*
X1088585Y230771D01*
X1088561Y230799D01*
G02X1088191Y231786I1131J987D01*
G02X1091195I1502J0D01*
G02X1090825Y230799I-1501J0D01*
G01X1090801Y230771D01*
X1090776Y230704D01*
Y230368D01*
X1090801Y230301D01*
X1090825Y230273D01*
G02X1091195Y229286I-1131J-987D01*
G02X1088191I-1502J0D01*
G02X1088561Y230273I1501J0D01*
G01X1088585Y230301D01*
X1088610Y230368D01*
G37*
G36*
G01X1086756Y237694D02*
X1087092D01*
X1087159Y237719D01*
X1087187Y237743D01*
G02X1089161I987J-1131D01*
G01X1089189Y237719D01*
X1089256Y237694D01*
X1089592D01*
X1089659Y237719D01*
X1089687Y237743D01*
G02X1090674Y238113I987J-1131D01*
G02Y235109I0J-1502D01*
G02X1089687Y235479I0J1501D01*
G01X1089659Y235503D01*
X1089592Y235528D01*
X1089256D01*
X1089189Y235503D01*
X1089161Y235479D01*
G02X1087187I-987J1131D01*
G01X1087159Y235503D01*
X1087092Y235528D01*
X1086756D01*
X1086689Y235503D01*
X1086661Y235479D01*
G02X1085674Y235109I-987J1131D01*
G02Y238113I0J1502D01*
G02X1086661Y237743I0J-1501D01*
G01X1086689Y237719D01*
X1086756Y237694D01*
G37*
G36*
G01X1086458Y249974D02*
X1086794D01*
X1086861Y249999D01*
X1086889Y250023D01*
G02X1088863I987J-1131D01*
G01X1088891Y249999D01*
X1088958Y249974D01*
X1089294D01*
X1089361Y249999D01*
X1089389Y250023D01*
G02X1090376Y250393I987J-1131D01*
G02Y247389I0J-1502D01*
G02X1089389Y247759I0J1501D01*
G01X1089361Y247783D01*
X1089294Y247808D01*
X1088958D01*
X1088891Y247783D01*
X1088863Y247759D01*
G02X1086889I-987J1131D01*
G01X1086861Y247783D01*
X1086794Y247808D01*
X1086458D01*
X1086391Y247783D01*
X1086363Y247759D01*
G02X1085376Y247389I-987J1131D01*
G02Y250393I0J1502D01*
G02X1086363Y250023I0J-1501D01*
G01X1086391Y249999D01*
X1086458Y249974D01*
G37*
G36*
G01X1090753Y190705D02*
G02X1090105Y191941I855J1236D01*
G02X1093109I1502J0D01*
G02X1092356Y190639I-1502J0D01*
G03X1092328Y189963I199J-347D01*
G02X1092976Y188727I-855J-1236D01*
G02X1089972I-1502J0D01*
G02X1090725Y190029I1502J0D01*
G03X1090753Y190705I-199J347D01*
G37*
G36*
G01X1114796Y185330D02*
X1114931Y185710D01*
X1114921Y185800D01*
X1114897Y185839D01*
G02X1114672Y186629I1277J791D01*
G02X1117676I1502J0D01*
G02X1116673Y185212I-1502J0D01*
G01X1116629Y185197D01*
X1116566Y185133D01*
X1116431Y184753D01*
X1116441Y184663D01*
X1116465Y184624D01*
G02X1116690Y183834I-1277J-791D01*
G02X1113686I-1502J0D01*
G02X1114689Y185251I1502J0D01*
G01X1114733Y185266D01*
X1114796Y185330D01*
G37*
G36*
G01X1140618Y147959D02*
X1140597Y147998D01*
G02X1140414Y148717I1319J719D01*
G02X1143418I1502J0D01*
G02X1142413Y147300I-1501J0D01*
G01X1142371Y147285D01*
X1142308Y147224D01*
X1142167Y146857D01*
X1142173Y146770D01*
X1142194Y146731D01*
G02X1142377Y146012I-1319J-719D01*
G02X1141717Y144768I-1502J0D01*
G03X1141629Y144603I112J-166D01*
G01Y144271D01*
G03X1141717Y144106I200J1D01*
G02X1142362Y143074I-842J-1244D01*
G01X1142367Y143037D01*
X1142401Y142974D01*
X1142659Y142754D01*
X1142725Y142729D01*
X1142763Y142730D01*
X1142781D01*
G02Y139726I0J-1502D01*
G02X1141294Y141016I0J1502D01*
G01X1141289Y141053D01*
X1141255Y141116D01*
X1140997Y141336D01*
X1140931Y141361D01*
X1140893Y141360D01*
X1140875D01*
G02X1139373Y142862I0J1502D01*
G02X1140033Y144106I1502J0D01*
G03X1140121Y144271I-112J166D01*
G01Y144603D01*
G03X1140033Y144768I-200J-1D01*
G02X1139373Y146012I842J1244D01*
G02X1140378Y147429I1501J0D01*
G01X1140420Y147444D01*
X1140483Y147505D01*
X1140624Y147872D01*
X1140618Y147959D01*
G37*
G36*
G01X1140476Y110018D02*
X1140792D01*
G03X1140949Y110095I-1J200D01*
G02X1142134Y110674I1185J-923D01*
G02X1143636Y109172I0J-1502D01*
G02X1142672Y107770I-1502J0D01*
G01X1142632Y107754D01*
X1142572Y107693D01*
X1142437Y107331D01*
X1142443Y107245D01*
X1142464Y107207D01*
G02X1142643Y106495I-1323J-711D01*
G02X1139639I-1502J0D01*
G02X1139777Y107123I1502J-1D01*
G01X1139800Y107173D01*
X1139788Y107283D01*
X1139511Y107653D01*
X1139409Y107694D01*
X1139355Y107686D01*
G02X1139134Y107670I-219J1486D01*
G02Y110674I0J1502D01*
G02X1140319Y110095I0J-1502D01*
G03X1140476Y110018I158J123D01*
G37*
G36*
G01X1153243Y105329D02*
X1153203Y105360D01*
G02X1152602Y106561I901J1202D01*
G02X1155606I1502J0D01*
G02X1154880Y105275I-1502J0D01*
G01X1154837Y105249D01*
X1154786Y105164D01*
X1154764Y104732D01*
X1154806Y104643D01*
X1154846Y104612D01*
G02X1155401Y103779I-901J-1202D01*
G01X1155413Y103731D01*
X1155479Y103658D01*
X1155882Y103509D01*
X1155978Y103522D01*
X1156019Y103550D01*
G02X1156885Y103825I866J-1226D01*
G02Y100821I0J-1502D01*
G02X1155429Y101955I0J1502D01*
G01X1155417Y102003D01*
X1155351Y102076D01*
X1154948Y102225D01*
X1154852Y102212D01*
X1154811Y102184D01*
G02X1153945Y101909I-866J1226D01*
G02X1152443Y103411I0J1502D01*
G02X1153169Y104697I1502J0D01*
G01X1153212Y104723D01*
X1153263Y104808D01*
X1153285Y105240D01*
X1153243Y105329D01*
G37*
G36*
G01X1209514Y102731D02*
G02X1209222Y103621I1210J890D01*
G02X1212226I1502J0D01*
G02X1211001Y102145I-1502J0D01*
G03X1210752Y101515I73J-393D01*
G02X1211044Y100625I-1210J-890D01*
G02X1208040I-1502J0D01*
G02X1209265Y102101I1502J0D01*
G03X1209514Y102731I-73J393D01*
G37*
G36*
G01X1173942Y101849D02*
G02X1173359Y103037I919J1188D01*
G02X1176363I1502J0D01*
G02X1175707Y101796I-1502J0D01*
G03X1175687Y101149I225J-331D01*
G02X1176270Y99961I-919J-1188D01*
G02X1173266I-1502J0D01*
G02X1173922Y101202I1502J0D01*
G03X1173942Y101849I-225J331D01*
G37*
G36*
G01X1166278Y92469D02*
G02X1166254Y92734I1478J267D01*
G02X1167756Y91232I1502J0D01*
G02X1167165Y91353I0J1502D01*
G03X1166613Y90915I-158J-367D01*
G02X1166637Y90650I-1478J-267D01*
G02X1165135Y92152I-1502J0D01*
G02X1165726Y92031I0J-1502D01*
G03X1166278Y92469I158J367D01*
G37*
G36*
G01X1219294Y90701D02*
G02X1218624Y91951I831J1250D01*
G02X1221628I1502J0D01*
G02X1220978Y90714I-1502J0D01*
G03X1220983Y90051I227J-330D01*
G02X1221653Y88801I-831J-1250D01*
G02X1218649I-1502J0D01*
G02X1219299Y90038I1502J0D01*
G03X1219294Y90701I-227J330D01*
G37*
G36*
G01X1130703Y217133D02*
X1130409D01*
G03X1130262Y217068I1J-200D01*
G02X1129156Y216583I-1105J1017D01*
G02Y219587I0J1502D01*
G02X1130262Y219102I1J-1502D01*
G03X1130409Y219037I148J135D01*
G01X1130703D01*
G03X1130850Y219102I-1J200D01*
G02X1131956Y219587I1105J-1017D01*
G02Y216583I0J-1502D01*
G02X1130850Y217068I-1J1502D01*
G03X1130703Y217133I-148J-135D01*
G37*
G36*
G01X1136883Y205755D02*
X1136547D01*
X1136480Y205730D01*
X1136452Y205706D01*
G02X1135465Y205336I-987J1131D01*
G02Y208340I0J1502D01*
G02X1136452Y207970I0J-1501D01*
G01X1136480Y207946D01*
X1136547Y207921D01*
X1136883D01*
X1136950Y207946D01*
X1136978Y207970D01*
G02X1137965Y208340I987J-1131D01*
G02Y205336I0J-1502D01*
G02X1136978Y205706I0J1501D01*
G01X1136950Y205730D01*
X1136883Y205755D01*
G37*
G36*
G01X1130695Y202310D02*
X1130359D01*
X1130292Y202285D01*
X1130264Y202261D01*
G02X1129277Y201891I-987J1131D01*
G02Y204895I0J1502D01*
G02X1130264Y204525I0J-1501D01*
G01X1130292Y204501D01*
X1130359Y204476D01*
X1130695D01*
X1130762Y204501D01*
X1130790Y204525D01*
G02X1131777Y204895I987J-1131D01*
G02X1133274Y203517I0J-1502D01*
G01X1133277Y203474D01*
X1133318Y203400D01*
X1133625Y203168D01*
X1133706Y203149D01*
X1133749Y203157D01*
G02X1134036Y203185I289J-1474D01*
G02X1135538Y201683I0J-1502D01*
G02X1135053Y200577I-1502J-1D01*
G03X1134988Y200430I135J-148D01*
G01Y200136D01*
G03X1135053Y199989I200J1D01*
G02X1135538Y198883I-1017J-1105D01*
G02X1132534I-1502J0D01*
G02X1133019Y199989I1502J1D01*
G03X1133084Y200136I-135J148D01*
G01Y200430D01*
G03X1133019Y200577I-200J-1D01*
G02X1132539Y201559I1017J1105D01*
G01X1132536Y201602D01*
X1132495Y201676D01*
X1132188Y201908D01*
X1132107Y201927D01*
X1132064Y201919D01*
G02X1131777Y201891I-289J1474D01*
G02X1130790Y202261I0J1501D01*
G01X1130762Y202285D01*
X1130695Y202310D01*
G37*
G36*
G01X1132999Y196259D02*
X1133335D01*
X1133402Y196284D01*
X1133430Y196308D01*
G02X1134417Y196678I987J-1131D01*
G02X1135523Y196193I1J-1502D01*
G03X1135670Y196128I148J135D01*
G01X1135964D01*
G03X1136111Y196193I-1J200D01*
G02X1137217Y196678I1105J-1017D01*
G02Y193674I0J-1502D01*
G02X1136111Y194159I-1J1502D01*
G03X1135964Y194224I-148J-135D01*
G01X1135670D01*
G03X1135523Y194159I1J-200D01*
G02X1134417Y193674I-1105J1017D01*
G02X1133430Y194044I0J1501D01*
G01X1133402Y194068D01*
X1133335Y194093D01*
X1132999D01*
X1132932Y194068D01*
X1132904Y194044D01*
G02X1130930I-987J1131D01*
G01X1130902Y194068D01*
X1130835Y194093D01*
X1130499D01*
X1130432Y194068D01*
X1130404Y194044D01*
G02X1129417Y193674I-987J1131D01*
G02Y196678I0J1502D01*
G02X1130404Y196308I0J-1501D01*
G01X1130432Y196284D01*
X1130499Y196259D01*
X1130835D01*
X1130902Y196284D01*
X1130930Y196308D01*
G02X1132904I987J-1131D01*
G01X1132932Y196284D01*
X1132999Y196259D01*
G37*
G36*
G01X1147834Y137670D02*
X1148150Y137881D01*
X1148195Y137950D01*
X1148202Y137992D01*
G02X1149685Y139259I1483J-234D01*
G02Y136255I0J-1502D01*
G02X1149417Y136279I-1J1502D01*
G03X1149251Y136234I-36J-197D01*
G01X1149155Y136151D01*
G03X1149086Y135991I131J-151D01*
G02X1149088Y135915I-1801J-85D01*
G01Y132515D01*
G02X1149086Y132436I-1803J6D01*
G03X1149155Y132276I200J-9D01*
G01X1149251Y132193D01*
G03X1149417Y132148I130J152D01*
G02X1149685Y132172I267J-1478D01*
G02X1150672Y131802I0J-1501D01*
G01X1150700Y131778D01*
X1150767Y131753D01*
X1151103D01*
X1151170Y131778D01*
X1151198Y131802D01*
G02X1152185Y132172I987J-1131D01*
G02X1153668Y130905I0J-1501D01*
G01X1153675Y130863D01*
X1153720Y130794D01*
X1154036Y130583D01*
X1154117Y130569D01*
X1154158Y130579D01*
G02X1154585Y130630I426J-1751D01*
G02X1154933Y130597I5J-1802D01*
G01X1154973Y130589D01*
X1155051Y130605D01*
X1155355Y130814D01*
X1155397Y130881D01*
X1155404Y130922D01*
G02X1156885Y132172I1481J-252D01*
G02Y129168I0J-1502D01*
G02X1156704Y129179I0J1502D01*
G03X1156546Y129128I-23J-199D01*
G01X1156452Y129043D01*
G03X1156386Y128888I134J-149D01*
G02X1156388Y128828I-1800J-90D01*
G01Y125428D01*
G02X1156386Y125365I-1802J26D01*
G03X1156452Y125210I200J-6D01*
G01X1156546Y125125D01*
G03X1156704Y125074I135J148D01*
G02X1156885Y125085I181J-1491D01*
G02Y122081I0J-1502D01*
G02X1155404Y123333I0J1502D01*
G01X1155397Y123374D01*
X1155354Y123441D01*
X1155051Y123651D01*
X1154973Y123667D01*
X1154932Y123659D01*
G02X1154585Y123626I-343J1769D01*
G02X1154159Y123677I0J1802D01*
G01X1154117Y123687D01*
X1154036Y123672D01*
X1153720Y123462D01*
X1153675Y123392D01*
X1153669Y123350D01*
G02X1152185Y122081I-1484J233D01*
G02X1151197Y122451I-1J1502D01*
G01X1151170Y122476D01*
X1151103Y122501D01*
X1150766D01*
X1150700Y122476D01*
X1150672Y122452D01*
G02X1149685Y122082I-987J1131D01*
G02X1149417Y122106I-1J1502D01*
G03X1149251Y122061I-36J-197D01*
G01X1149155Y121978D01*
G03X1149086Y121818I131J-151D01*
G02X1149088Y121742I-1801J-85D01*
G01Y118342D01*
G02X1149086Y118263I-1803J6D01*
G03X1149155Y118103I200J-9D01*
G01X1149251Y118020D01*
G03X1149417Y117975I130J152D01*
G02X1149685Y117999I267J-1478D01*
G02X1150672Y117629I0J-1501D01*
G01X1150700Y117605D01*
X1150767Y117580D01*
X1151103D01*
X1151170Y117605D01*
X1151198Y117629D01*
G02X1152185Y117999I987J-1131D01*
G02X1153668Y116732I0J-1501D01*
G01X1153675Y116690D01*
X1153720Y116621D01*
X1154036Y116410D01*
X1154117Y116396D01*
X1154158Y116406D01*
G02X1154585Y116458I430J-1751D01*
G02X1154933Y116424I0J-1803D01*
G01X1154973Y116416D01*
X1155051Y116432D01*
X1155355Y116641D01*
X1155397Y116708D01*
X1155404Y116749D01*
G02X1156885Y117998I1481J-254D01*
G02Y114994I0J-1502D01*
G02X1156704Y115005I0J1502D01*
G03X1156546Y114954I-23J-199D01*
G01X1156452Y114869D01*
G03X1156387Y114714I135J-148D01*
G02X1156388Y114655I-1802J-60D01*
G01Y111255D01*
G02X1156386Y111192I-1802J26D01*
G03X1156452Y111037I200J-6D01*
G01X1156546Y110952D01*
G03X1156704Y110901I135J148D01*
G02X1156885Y110912I181J-1491D01*
G02Y107908I0J-1502D01*
G02X1155404Y109160I0J1502D01*
G01X1155397Y109201D01*
X1155354Y109268D01*
X1155051Y109478D01*
X1154973Y109494D01*
X1154932Y109486D01*
G02X1154585Y109452I-348J1769D01*
G02X1154159Y109504I4J1803D01*
G01X1154117Y109514D01*
X1154036Y109499D01*
X1153720Y109289D01*
X1153675Y109219D01*
X1153669Y109177D01*
G02X1152185Y107908I-1484J233D01*
G02Y110912I0J1502D01*
G02X1152453Y110888I1J-1502D01*
G03X1152619Y110933I36J197D01*
G01X1152715Y111016D01*
G03X1152784Y111176I-131J151D01*
G02X1152782Y111255I1801J85D01*
G01Y114655D01*
G02X1152784Y114731I1803J-9D01*
G03X1152715Y114891I-200J9D01*
G01X1152619Y114974D01*
G03X1152453Y115019I-130J-152D01*
G02X1152185Y114995I-267J1478D01*
G02X1151198Y115365I0J1501D01*
G01X1151170Y115389D01*
X1151103Y115414D01*
X1150767D01*
X1150700Y115389D01*
X1150672Y115365D01*
G02X1149685Y114995I-987J1131D01*
G02X1148201Y116264I0J1502D01*
G01X1148195Y116306D01*
X1148150Y116376D01*
X1147834Y116586D01*
X1147753Y116601D01*
X1147711Y116591D01*
G02X1147285Y116540I-426J1751D01*
G02X1146859Y116591I0J1802D01*
G01X1146817Y116601D01*
X1146736Y116586D01*
X1146420Y116376D01*
X1146375Y116306D01*
X1146369Y116264D01*
G02X1144885Y114995I-1484J233D01*
G02Y117999I0J1502D01*
G02X1145153Y117975I1J-1502D01*
G03X1145319Y118020I36J197D01*
G01X1145415Y118103D01*
G03X1145484Y118263I-131J151D01*
G02X1145482Y118342I1801J85D01*
G01Y121742D01*
G02X1145484Y121818I1803J-9D01*
G03X1145415Y121978I-200J9D01*
G01X1145319Y122061D01*
G03X1145153Y122106I-130J-152D01*
G02X1144885Y122082I-267J1478D01*
G02Y125086I0J1502D01*
G02X1146368Y123819I0J-1501D01*
G01X1146375Y123777D01*
X1146420Y123708D01*
X1146736Y123497D01*
X1146817Y123483D01*
X1146858Y123493D01*
G02X1147285Y123544I426J-1751D01*
G02X1147712Y123493I1J-1802D01*
G01X1147753Y123483D01*
X1147834Y123497D01*
X1148150Y123708D01*
X1148195Y123777D01*
X1148202Y123819D01*
G02X1149685Y125086I1483J-234D01*
G02X1150673Y124716I1J-1502D01*
G01X1150700Y124691D01*
X1150767Y124666D01*
X1151104D01*
X1151170Y124691D01*
X1151198Y124715D01*
G02X1152185Y125085I987J-1131D01*
G02X1152453Y125061I1J-1502D01*
G03X1152619Y125106I36J197D01*
G01X1152715Y125189D01*
G03X1152784Y125349I-131J151D01*
G02X1152782Y125428I1801J85D01*
G01Y128828D01*
G02X1152784Y128904I1803J-9D01*
G03X1152715Y129064I-200J9D01*
G01X1152619Y129147D01*
G03X1152453Y129192I-130J-152D01*
G02X1152185Y129168I-267J1478D01*
G02X1151198Y129538I0J1501D01*
G01X1151170Y129562D01*
X1151103Y129587D01*
X1150767D01*
X1150700Y129562D01*
X1150672Y129538D01*
G02X1149685Y129168I-987J1131D01*
G02X1148201Y130437I0J1502D01*
G01X1148195Y130479D01*
X1148150Y130549D01*
X1147834Y130759D01*
X1147753Y130774D01*
X1147711Y130764D01*
G02X1147285Y130712I-430J1751D01*
G02X1146859Y130764I4J1803D01*
G01X1146817Y130774D01*
X1146736Y130759D01*
X1146420Y130549D01*
X1146375Y130479D01*
X1146369Y130437D01*
G02X1144885Y129168I-1484J233D01*
G02Y132172I0J1502D01*
G02X1145153Y132148I1J-1502D01*
G03X1145319Y132193I36J197D01*
G01X1145415Y132276D01*
G03X1145484Y132436I-131J151D01*
G02X1145482Y132515I1801J85D01*
G01Y135915D01*
G02X1145484Y135991I1803J-9D01*
G03X1145415Y136151I-200J9D01*
G01X1145319Y136234D01*
G03X1145153Y136279I-130J-152D01*
G02X1144885Y136255I-267J1478D01*
G02Y139259I0J1502D01*
G02X1146368Y137992I0J-1501D01*
G01X1146375Y137950D01*
X1146420Y137881D01*
X1146736Y137670D01*
X1146817Y137656D01*
X1146858Y137666D01*
G02X1147285Y137718I430J-1751D01*
G02X1147712Y137666I-3J-1803D01*
G01X1147753Y137656D01*
X1147834Y137670D01*
G37*
G36*
G01X1164305Y84108D02*
Y84460D01*
X1164277Y84529D01*
X1164251Y84557D01*
G02X1163845Y85584I1096J1027D01*
G02X1166849I1502J0D01*
G02X1166443Y84557I-1502J0D01*
G01X1166417Y84529D01*
X1166389Y84460D01*
Y84108D01*
X1166417Y84039D01*
X1166443Y84011D01*
G02Y81957I-1096J-1027D01*
G01X1166417Y81929D01*
X1166389Y81860D01*
Y81508D01*
X1166417Y81439D01*
X1166443Y81411D01*
G02Y79357I-1096J-1027D01*
G01X1166417Y79329D01*
X1166389Y79260D01*
Y78908D01*
X1166417Y78839D01*
X1166443Y78811D01*
G02Y76757I-1096J-1027D01*
G01X1166417Y76729D01*
X1166389Y76660D01*
Y76308D01*
X1166417Y76239D01*
X1166443Y76211D01*
G02X1166849Y75184I-1096J-1027D01*
G02X1163845I-1502J0D01*
G02X1164251Y76211I1502J0D01*
G01X1164277Y76239D01*
X1164305Y76308D01*
Y76660D01*
X1164277Y76729D01*
X1164251Y76757D01*
G02Y78811I1096J1027D01*
G01X1164277Y78839D01*
X1164305Y78908D01*
Y79260D01*
X1164277Y79329D01*
X1164251Y79357D01*
G02Y81411I1096J1027D01*
G01X1164277Y81439D01*
X1164305Y81508D01*
Y81860D01*
X1164277Y81929D01*
X1164251Y81957D01*
G02Y84011I1096J1027D01*
G01X1164277Y84039D01*
X1164305Y84108D01*
G37*
G36*
G01X1182640Y83717D02*
Y84069D01*
X1182612Y84138D01*
X1182586Y84166D01*
G02X1182180Y85193I1096J1027D01*
G02X1185184I1502J0D01*
G02X1184778Y84166I-1502J0D01*
G01X1184752Y84138D01*
X1184724Y84069D01*
Y83717D01*
X1184752Y83648D01*
X1184778Y83620D01*
G02Y81566I-1096J-1027D01*
G01X1184752Y81538D01*
X1184724Y81469D01*
Y81117D01*
X1184752Y81048D01*
X1184778Y81020D01*
G02Y78966I-1096J-1027D01*
G01X1184752Y78938D01*
X1184724Y78869D01*
Y78517D01*
X1184752Y78448D01*
X1184778Y78420D01*
G02Y76366I-1096J-1027D01*
G01X1184752Y76338D01*
X1184724Y76269D01*
Y75917D01*
X1184752Y75848D01*
X1184778Y75820D01*
G02X1185184Y74793I-1096J-1027D01*
G02X1182180I-1502J0D01*
G02X1182586Y75820I1502J0D01*
G01X1182612Y75848D01*
X1182640Y75917D01*
Y76269D01*
X1182612Y76338D01*
X1182586Y76366D01*
G02Y78420I1096J1027D01*
G01X1182612Y78448D01*
X1182640Y78517D01*
Y78869D01*
X1182612Y78938D01*
X1182586Y78966D01*
G02Y81020I1096J1027D01*
G01X1182612Y81048D01*
X1182640Y81117D01*
Y81469D01*
X1182612Y81538D01*
X1182586Y81566D01*
G02Y83620I1096J1027D01*
G01X1182612Y83648D01*
X1182640Y83717D01*
G37*
G36*
G01X1207069Y75446D02*
X1206697Y75386D01*
X1206628Y75341D01*
X1206604Y75306D01*
G02X1205355Y74638I-1249J834D01*
G02Y77642I0J1502D01*
G02X1206276Y77327I1J-1502D01*
G01X1206309Y77301D01*
X1206389Y77281D01*
X1206761Y77341D01*
X1206830Y77386D01*
X1206854Y77421D01*
G02X1208103Y78089I1249J-834D01*
G02Y75085I0J-1502D01*
G02X1207182Y75400I-1J1502D01*
G01X1207149Y75426D01*
X1207069Y75446D01*
G37*
G36*
G01X1138925Y236121D02*
G02X1141929I1502J0D01*
G02X1141279Y234884I-1502J0D01*
G03X1141285Y234222I227J-329D01*
G02X1141955Y232971I-833J-1251D01*
G02X1138951I-1502J0D01*
G02X1139601Y234208I1502J0D01*
G03X1139595Y234870I-227J329D01*
G02X1138925Y236121I833J1251D01*
G37*
G36*
G01X1136967Y221970D02*
G02X1139971I1502J0D01*
G02X1139601Y220983I-1501J0D01*
G01X1139577Y220955D01*
X1139552Y220888D01*
Y220552D01*
X1139577Y220485D01*
X1139601Y220457D01*
G02Y218483I-1131J-987D01*
G01X1139577Y218455D01*
X1139552Y218388D01*
Y218052D01*
X1139577Y217985D01*
X1139601Y217957D01*
G02X1139971Y216970I-1131J-987D01*
G02X1138469Y215468I-1502J0D01*
G02X1137614Y215735I0J1502D01*
G01X1137580Y215759D01*
X1137499Y215775D01*
X1137132Y215696D01*
X1137065Y215648D01*
X1137044Y215612D01*
G02X1135756Y214883I-1288J773D01*
G02Y217887I0J1502D01*
G02X1136611Y217620I0J-1502D01*
G01X1136645Y217596D01*
X1136726Y217580D01*
X1137093Y217659D01*
X1137160Y217707D01*
X1137181Y217743D01*
G02X1137337Y217957I1287J-774D01*
G01X1137361Y217985D01*
X1137386Y218052D01*
Y218388D01*
X1137361Y218455D01*
X1137337Y218483D01*
G02Y220457I1131J987D01*
G01X1137361Y220485D01*
X1137386Y220552D01*
Y220888D01*
X1137361Y220955D01*
X1137337Y220983D01*
G02X1136967Y221970I1131J987D01*
G37*
G36*
G01X1194665Y223294D02*
Y223630D01*
X1194640Y223697D01*
X1194616Y223725D01*
G02X1194246Y224712I1131J987D01*
G02X1197250I1502J0D01*
G02X1196880Y223725I-1501J0D01*
G01X1196856Y223697D01*
X1196831Y223630D01*
Y223294D01*
X1196856Y223227D01*
X1196880Y223199D01*
G02X1197250Y222212I-1131J-987D01*
G02X1194246I-1502J0D01*
G02X1194616Y223199I1501J0D01*
G01X1194640Y223227D01*
X1194665Y223294D01*
G37*
G36*
G01X1189340Y225189D02*
X1189046D01*
G03X1188899Y225124I1J-200D01*
G02X1187793Y224639I-1105J1017D01*
G02Y227643I0J1502D01*
G02X1188899Y227158I1J-1502D01*
G03X1189046Y227093I148J135D01*
G01X1189340D01*
G03X1189487Y227158I-1J200D01*
G02X1190593Y227643I1105J-1017D01*
G02Y224639I0J-1502D01*
G02X1189487Y225124I-1J1502D01*
G03X1189340Y225189I-148J-135D01*
G37*
G36*
G01X1172547Y229808D02*
Y230144D01*
X1172522Y230211D01*
X1172498Y230239D01*
G02X1172128Y231226I1131J987D01*
G02X1175132I1502J0D01*
G02X1174762Y230239I-1501J0D01*
G01X1174738Y230211D01*
X1174713Y230144D01*
Y229808D01*
X1174738Y229741D01*
X1174762Y229713D01*
G02Y227739I-1131J-987D01*
G01X1174738Y227711D01*
X1174713Y227644D01*
Y227308D01*
X1174738Y227241D01*
X1174762Y227213D01*
G02Y225239I-1131J-987D01*
G01X1174738Y225211D01*
X1174713Y225144D01*
Y224808D01*
X1174738Y224741D01*
X1174762Y224713D01*
G02X1175132Y223726I-1131J-987D01*
G02X1172128I-1502J0D01*
G02X1172498Y224713I1501J0D01*
G01X1172522Y224741D01*
X1172547Y224808D01*
Y225144D01*
X1172522Y225211D01*
X1172498Y225239D01*
G02Y227213I1131J987D01*
G01X1172522Y227241D01*
X1172547Y227308D01*
Y227644D01*
X1172522Y227711D01*
X1172498Y227739D01*
G02Y229713I1131J987D01*
G01X1172522Y229741D01*
X1172547Y229808D01*
G37*
G36*
G01X1183003Y230043D02*
Y230379D01*
X1182978Y230446D01*
X1182954Y230474D01*
G02X1182584Y231461I1131J987D01*
G02X1185588I1502J0D01*
G02X1185218Y230474I-1501J0D01*
G01X1185194Y230446D01*
X1185169Y230379D01*
Y230043D01*
X1185194Y229976D01*
X1185218Y229948D01*
G02Y227974I-1131J-987D01*
G01X1185194Y227946D01*
X1185169Y227879D01*
Y227543D01*
X1185194Y227476D01*
X1185218Y227448D01*
G02X1185588Y226461I-1131J-987D01*
G02X1185103Y225355I-1502J-1D01*
G03X1185038Y225208I135J-148D01*
G01Y224914D01*
G03X1185103Y224767I200J1D01*
G02X1185588Y223661I-1017J-1105D01*
G02X1182584I-1502J0D01*
G02X1183069Y224767I1502J1D01*
G03X1183134Y224914I-135J148D01*
G01Y225208D01*
G03X1183069Y225355I-200J-1D01*
G02X1182584Y226461I1017J1105D01*
G02X1182954Y227448I1501J0D01*
G01X1182978Y227476D01*
X1183003Y227543D01*
Y227879D01*
X1182978Y227946D01*
X1182954Y227974D01*
G02Y229948I1131J987D01*
G01X1182978Y229976D01*
X1183003Y230043D01*
G37*
G36*
G01X1190972Y230368D02*
Y230704D01*
X1190947Y230771D01*
X1190923Y230799D01*
G02X1190553Y231786I1131J987D01*
G02X1193557I1502J0D01*
G02X1193187Y230799I-1501J0D01*
G01X1193163Y230771D01*
X1193138Y230704D01*
Y230368D01*
X1193163Y230301D01*
X1193187Y230273D01*
G02X1193557Y229286I-1131J-987D01*
G02X1190553I-1502J0D01*
G02X1190923Y230273I1501J0D01*
G01X1190947Y230301D01*
X1190972Y230368D01*
G37*
G36*
G01X1189118Y237694D02*
X1189454D01*
X1189521Y237719D01*
X1189549Y237743D01*
G02X1191523I987J-1131D01*
G01X1191551Y237719D01*
X1191618Y237694D01*
X1191954D01*
X1192021Y237719D01*
X1192049Y237743D01*
G02X1193036Y238113I987J-1131D01*
G02Y235109I0J-1502D01*
G02X1192049Y235479I0J1501D01*
G01X1192021Y235503D01*
X1191954Y235528D01*
X1191618D01*
X1191551Y235503D01*
X1191523Y235479D01*
G02X1189549I-987J1131D01*
G01X1189521Y235503D01*
X1189454Y235528D01*
X1189118D01*
X1189051Y235503D01*
X1189023Y235479D01*
G02X1188036Y235109I-987J1131D01*
G02Y238113I0J1502D01*
G02X1189023Y237743I0J-1501D01*
G01X1189051Y237719D01*
X1189118Y237694D01*
G37*
G36*
G01X1188820Y249974D02*
X1189156D01*
X1189223Y249999D01*
X1189251Y250023D01*
G02X1191225I987J-1131D01*
G01X1191253Y249999D01*
X1191320Y249974D01*
X1191656D01*
X1191723Y249999D01*
X1191751Y250023D01*
G02X1192738Y250393I987J-1131D01*
G02Y247389I0J-1502D01*
G02X1191751Y247759I0J1501D01*
G01X1191723Y247783D01*
X1191656Y247808D01*
X1191320D01*
X1191253Y247783D01*
X1191225Y247759D01*
G02X1189251I-987J1131D01*
G01X1189223Y247783D01*
X1189156Y247808D01*
X1188820D01*
X1188753Y247783D01*
X1188725Y247759D01*
G02X1187738Y247389I-987J1131D01*
G02Y250393I0J1502D01*
G02X1188725Y250023I0J-1501D01*
G01X1188753Y249999D01*
X1188820Y249974D01*
G37*
G36*
G01X1193115Y190705D02*
G02X1192467Y191941I855J1236D01*
G02X1195471I1502J0D01*
G02X1194718Y190639I-1502J0D01*
G03X1194690Y189963I199J-347D01*
G02X1195338Y188727I-855J-1236D01*
G02X1192334I-1502J0D01*
G02X1193087Y190029I1502J0D01*
G03X1193115Y190705I-199J347D01*
G37*
G36*
G01X1217158Y185330D02*
X1217293Y185710D01*
X1217283Y185800D01*
X1217259Y185839D01*
G02X1217034Y186629I1277J791D01*
G02X1220038I1502J0D01*
G02X1219035Y185212I-1502J0D01*
G01X1218991Y185197D01*
X1218928Y185133D01*
X1218793Y184753D01*
X1218803Y184663D01*
X1218827Y184624D01*
G02X1219052Y183834I-1277J-791D01*
G02X1216048I-1502J0D01*
G02X1217051Y185251I1502J0D01*
G01X1217095Y185266D01*
X1217158Y185330D01*
G37*
G36*
G01X1534810Y1406992D02*
G02Y1409998I0J1503D01*
G01X1538210D01*
G02Y1406992I0J-1503D01*
G01X1534810D01*
G37*
G36*
G01Y1395080D02*
G02Y1398086I0J1503D01*
G01X1538210D01*
G02Y1395080I0J-1503D01*
G01X1534810D01*
G37*
G36*
G01X1547050Y1406992D02*
G02Y1409998I0J1503D01*
G01X1550450D01*
G02Y1406992I0J-1503D01*
G01X1547050D01*
G37*
G36*
G01Y1395080D02*
G02Y1398086I0J1503D01*
G01X1550450D01*
G02Y1395080I0J-1503D01*
G01X1547050D01*
G37*
G36*
G01X1559290Y1406992D02*
G02Y1409998I0J1503D01*
G01X1562690D01*
G02Y1406992I0J-1503D01*
G01X1559290D01*
G37*
G36*
G01Y1395080D02*
G02Y1398086I0J1503D01*
G01X1562690D01*
G02Y1395080I0J-1503D01*
G01X1559290D01*
G37*
G36*
G01X1571530Y1406992D02*
G02Y1409998I0J1503D01*
G01X1574930D01*
G02Y1406992I0J-1503D01*
G01X1571530D01*
G37*
G36*
G01Y1395080D02*
G02Y1398086I0J1503D01*
G01X1574930D01*
G02Y1395080I0J-1503D01*
G01X1571530D01*
G37*
G36*
G01X1559290Y1382794D02*
G02Y1385800I0J1503D01*
G01X1562690D01*
G02Y1382794I0J-1503D01*
G01X1559290D01*
G37*
G36*
G01Y1370882D02*
G02Y1373888I0J1503D01*
G01X1562690D01*
G02Y1370882I0J-1503D01*
G01X1559290D01*
G37*
G36*
G01X1547050D02*
G02Y1373888I0J1503D01*
G01X1550450D01*
G02Y1370882I0J-1503D01*
G01X1547050D01*
G37*
G36*
G01Y1382794D02*
G02Y1385800I0J1503D01*
G01X1550450D01*
G02Y1382794I0J-1503D01*
G01X1547050D01*
G37*
G36*
G01X1534810D02*
G02Y1385800I0J1503D01*
G01X1538210D01*
G02Y1382794I0J-1503D01*
G01X1534810D01*
G37*
G36*
G01Y1370882D02*
G02Y1373888I0J1503D01*
G01X1538210D01*
G02Y1370882I0J-1503D01*
G01X1534810D01*
G37*
G36*
G01Y1358596D02*
G02Y1361602I0J1503D01*
G01X1538210D01*
G02Y1358596I0J-1503D01*
G01X1534810D01*
G37*
G36*
G01Y1346684D02*
G02Y1349690I0J1503D01*
G01X1538210D01*
G02Y1346684I0J-1503D01*
G01X1534810D01*
G37*
G36*
G01X1547050D02*
G02Y1349690I0J1503D01*
G01X1550450D01*
G02Y1346684I0J-1503D01*
G01X1547050D01*
G37*
G36*
G01Y1358596D02*
G02Y1361602I0J1503D01*
G01X1550450D01*
G02Y1358596I0J-1503D01*
G01X1547050D01*
G37*
G36*
G01X1559290D02*
G02Y1361602I0J1503D01*
G01X1562690D01*
G02Y1358596I0J-1503D01*
G01X1559290D01*
G37*
G36*
G01Y1346684D02*
G02Y1349690I0J1503D01*
G01X1562690D01*
G02Y1346684I0J-1503D01*
G01X1559290D01*
G37*
G36*
G01X1522570D02*
G02Y1349690I0J1503D01*
G01X1525970D01*
G02Y1346684I0J-1503D01*
G01X1522570D01*
G37*
G36*
G01Y1358596D02*
G02Y1361602I0J1503D01*
G01X1525970D01*
G02Y1358596I0J-1503D01*
G01X1522570D01*
G37*
G36*
G01X1362218Y1261006D02*
X1362534D01*
G03X1362691Y1261083I-1J200D01*
G02X1365061I1185J-923D01*
G03X1365218Y1261006I158J123D01*
G01X1365534D01*
G03X1365691Y1261083I-1J200D01*
G02X1366876Y1261662I1185J-923D01*
G02X1368378Y1260160I0J-1502D01*
G02X1367799Y1258975I-1502J0D01*
G03X1367722Y1258818I123J-158D01*
G01Y1258502D01*
G03X1367799Y1258345I200J1D01*
G02X1368378Y1257160I-923J-1185D01*
G02X1366876Y1255658I-1502J0D01*
G02X1365691Y1256237I0J1502D01*
G03X1365534Y1256314I-158J-123D01*
G01X1365218D01*
G03X1365061Y1256237I1J-200D01*
G02X1362691I-1185J923D01*
G03X1362534Y1256314I-158J-123D01*
G01X1362218D01*
G03X1362061Y1256237I1J-200D01*
G02X1359691I-1185J923D01*
G03X1359534Y1256314I-158J-123D01*
G01X1359218D01*
G03X1359061Y1256237I1J-200D01*
G02X1356691I-1185J923D01*
G03X1356534Y1256314I-158J-123D01*
G01X1356218D01*
G03X1356061Y1256237I1J-200D01*
G02X1353691I-1185J923D01*
G03X1353534Y1256314I-158J-123D01*
G01X1353218D01*
G03X1353061Y1256237I1J-200D01*
G02X1350691I-1185J923D01*
G03X1350534Y1256314I-158J-123D01*
G01X1350218D01*
G03X1350061Y1256237I1J-200D01*
G02X1347691I-1185J923D01*
G03X1347534Y1256314I-158J-123D01*
G01X1347218D01*
G03X1347061Y1256237I1J-200D01*
G02X1344691I-1185J923D01*
G03X1344534Y1256314I-158J-123D01*
G01X1344218D01*
G03X1344061Y1256237I1J-200D01*
G02X1341691I-1185J923D01*
G03X1341534Y1256314I-158J-123D01*
G01X1341218D01*
G03X1341061Y1256237I1J-200D01*
G02X1338691I-1185J923D01*
G03X1338534Y1256314I-158J-123D01*
G01X1338218D01*
G03X1338061Y1256237I1J-200D01*
G02X1335691I-1185J923D01*
G03X1335534Y1256314I-158J-123D01*
G01X1335218D01*
G03X1335061Y1256237I1J-200D01*
G02X1333876Y1255658I-1185J923D01*
G02X1332374Y1257160I0J1502D01*
G02X1332953Y1258345I1502J0D01*
G03X1333030Y1258502I-123J158D01*
G01Y1258818D01*
G03X1332953Y1258975I-200J-1D01*
G02X1332374Y1260160I923J1185D01*
G02X1333876Y1261662I1502J0D01*
G02X1335061Y1261083I0J-1502D01*
G03X1335218Y1261006I158J123D01*
G01X1335534D01*
G03X1335691Y1261083I-1J200D01*
G02X1338061I1185J-923D01*
G03X1338218Y1261006I158J123D01*
G01X1338534D01*
G03X1338691Y1261083I-1J200D01*
G02X1341061I1185J-923D01*
G03X1341218Y1261006I158J123D01*
G01X1341534D01*
G03X1341691Y1261083I-1J200D01*
G02X1344061I1185J-923D01*
G03X1344218Y1261006I158J123D01*
G01X1344534D01*
G03X1344691Y1261083I-1J200D01*
G02X1347061I1185J-923D01*
G03X1347218Y1261006I158J123D01*
G01X1347534D01*
G03X1347691Y1261083I-1J200D01*
G02X1350061I1185J-923D01*
G03X1350218Y1261006I158J123D01*
G01X1350534D01*
G03X1350691Y1261083I-1J200D01*
G02X1353061I1185J-923D01*
G03X1353218Y1261006I158J123D01*
G01X1353534D01*
G03X1353691Y1261083I-1J200D01*
G02X1356061I1185J-923D01*
G03X1356218Y1261006I158J123D01*
G01X1356534D01*
G03X1356691Y1261083I-1J200D01*
G02X1359061I1185J-923D01*
G03X1359218Y1261006I158J123D01*
G01X1359534D01*
G03X1359691Y1261083I-1J200D01*
G02X1362061I1185J-923D01*
G03X1362218Y1261006I158J123D01*
G37*
G36*
G01X1417163D02*
X1417479D01*
G03X1417636Y1261083I-1J200D01*
G02X1420006I1185J-923D01*
G03X1420163Y1261006I158J123D01*
G01X1420479D01*
G03X1420636Y1261083I-1J200D01*
G02X1421821Y1261662I1185J-923D01*
G02X1423323Y1260160I0J-1502D01*
G02X1422744Y1258975I-1502J0D01*
G03X1422667Y1258818I123J-158D01*
G01Y1258502D01*
G03X1422744Y1258345I200J1D01*
G02X1423323Y1257160I-923J-1185D01*
G02X1421821Y1255658I-1502J0D01*
G02X1420636Y1256237I0J1502D01*
G03X1420479Y1256314I-158J-123D01*
G01X1420163D01*
G03X1420006Y1256237I1J-200D01*
G02X1417636I-1185J923D01*
G03X1417479Y1256314I-158J-123D01*
G01X1417163D01*
G03X1417006Y1256237I1J-200D01*
G02X1414636I-1185J923D01*
G03X1414479Y1256314I-158J-123D01*
G01X1414163D01*
G03X1414006Y1256237I1J-200D01*
G02X1411636I-1185J923D01*
G03X1411479Y1256314I-158J-123D01*
G01X1411163D01*
G03X1411006Y1256237I1J-200D01*
G02X1408636I-1185J923D01*
G03X1408479Y1256314I-158J-123D01*
G01X1408163D01*
G03X1408006Y1256237I1J-200D01*
G02X1405636I-1185J923D01*
G03X1405479Y1256314I-158J-123D01*
G01X1405163D01*
G03X1405006Y1256237I1J-200D01*
G02X1402636I-1185J923D01*
G03X1402479Y1256314I-158J-123D01*
G01X1402163D01*
G03X1402006Y1256237I1J-200D01*
G02X1399636I-1185J923D01*
G03X1399479Y1256314I-158J-123D01*
G01X1399163D01*
G03X1399006Y1256237I1J-200D01*
G02X1396636I-1185J923D01*
G03X1396479Y1256314I-158J-123D01*
G01X1396163D01*
G03X1396006Y1256237I1J-200D01*
G02X1393636I-1185J923D01*
G03X1393479Y1256314I-158J-123D01*
G01X1393163D01*
G03X1393006Y1256237I1J-200D01*
G02X1390636I-1185J923D01*
G03X1390479Y1256314I-158J-123D01*
G01X1390163D01*
G03X1390006Y1256237I1J-200D01*
G02X1387636I-1185J923D01*
G03X1387479Y1256314I-158J-123D01*
G01X1387163D01*
G03X1387006Y1256237I1J-200D01*
G02X1385821Y1255658I-1185J923D01*
G02X1384319Y1257160I0J1502D01*
G02X1384898Y1258345I1502J0D01*
G03X1384975Y1258502I-123J158D01*
G01Y1258818D01*
G03X1384898Y1258975I-200J-1D01*
G02X1384319Y1260160I923J1185D01*
G02X1385821Y1261662I1502J0D01*
G02X1387006Y1261083I0J-1502D01*
G03X1387163Y1261006I158J123D01*
G01X1387479D01*
G03X1387636Y1261083I-1J200D01*
G02X1390006I1185J-923D01*
G03X1390163Y1261006I158J123D01*
G01X1390479D01*
G03X1390636Y1261083I-1J200D01*
G02X1393006I1185J-923D01*
G03X1393163Y1261006I158J123D01*
G01X1393479D01*
G03X1393636Y1261083I-1J200D01*
G02X1396006I1185J-923D01*
G03X1396163Y1261006I158J123D01*
G01X1396479D01*
G03X1396636Y1261083I-1J200D01*
G02X1399006I1185J-923D01*
G03X1399163Y1261006I158J123D01*
G01X1399479D01*
G03X1399636Y1261083I-1J200D01*
G02X1402006I1185J-923D01*
G03X1402163Y1261006I158J123D01*
G01X1402479D01*
G03X1402636Y1261083I-1J200D01*
G02X1405006I1185J-923D01*
G03X1405163Y1261006I158J123D01*
G01X1405479D01*
G03X1405636Y1261083I-1J200D01*
G02X1408006I1185J-923D01*
G03X1408163Y1261006I158J123D01*
G01X1408479D01*
G03X1408636Y1261083I-1J200D01*
G02X1411006I1185J-923D01*
G03X1411163Y1261006I158J123D01*
G01X1411479D01*
G03X1411636Y1261083I-1J200D01*
G02X1414006I1185J-923D01*
G03X1414163Y1261006I158J123D01*
G01X1414479D01*
G03X1414636Y1261083I-1J200D01*
G02X1417006I1185J-923D01*
G03X1417163Y1261006I158J123D01*
G37*
G36*
G01X1263090Y1201265D02*
G02X1264575Y1202545I1485J-221D01*
G02Y1199541I0J-1502D01*
G02X1263662Y1199850I0J1503D01*
G03X1263023Y1199592I-243J-317D01*
G02X1261538Y1198312I-1485J221D01*
G02Y1201316I0J1502D01*
G02X1262451Y1201007I0J-1503D01*
G03X1263090Y1201265I243J317D01*
G37*
G36*
G01X1272968Y1227959D02*
G02X1272944Y1228226I1478J267D01*
G02X1274446Y1226724I1502J0D01*
G02X1274178Y1226748I-1J1502D01*
G03X1273713Y1226283I-71J-394D01*
G02X1273737Y1226016I-1478J-267D01*
G02X1272235Y1227518I-1502J0D01*
G02X1272503Y1227494I1J-1502D01*
G03X1272968Y1227959I71J394D01*
G37*
G36*
G01X1242980Y147959D02*
X1242959Y147998D01*
G02X1242776Y148717I1319J719D01*
G02X1245780I1502J0D01*
G02X1244775Y147300I-1501J0D01*
G01X1244733Y147285D01*
X1244670Y147224D01*
X1244529Y146857D01*
X1244535Y146770D01*
X1244556Y146731D01*
G02X1244739Y146012I-1319J-719D01*
G02X1244079Y144768I-1502J0D01*
G03X1243991Y144603I112J-166D01*
G01Y144271D01*
G03X1244079Y144106I200J1D01*
G02X1244724Y143074I-842J-1244D01*
G01X1244729Y143037D01*
X1244763Y142974D01*
X1245021Y142754D01*
X1245087Y142729D01*
X1245125Y142730D01*
X1245143D01*
G02Y139726I0J-1502D01*
G02X1243656Y141016I0J1502D01*
G01X1243651Y141053D01*
X1243617Y141116D01*
X1243359Y141336D01*
X1243293Y141361D01*
X1243255Y141360D01*
X1243237D01*
G02X1241735Y142862I0J1502D01*
G02X1242395Y144106I1502J0D01*
G03X1242483Y144271I-112J166D01*
G01Y144603D01*
G03X1242395Y144768I-200J-1D01*
G02X1241735Y146012I842J1244D01*
G02X1242740Y147429I1501J0D01*
G01X1242782Y147444D01*
X1242845Y147505D01*
X1242986Y147872D01*
X1242980Y147959D01*
G37*
G36*
G01X1250315Y138793D02*
X1250266Y138795D01*
G02X1248805Y140296I41J1501D01*
G02X1251809I1502J0D01*
G02X1251722Y139792I-1503J0D01*
G01X1251706Y139746D01*
X1251718Y139653D01*
X1251956Y139305D01*
X1252039Y139260D01*
X1252088Y139258D01*
G02X1253549Y137757I-41J-1501D01*
G02X1252047Y136255I-1502J0D01*
G02X1251779Y136279I-1J1502D01*
G03X1251613Y136234I-36J-197D01*
G01X1251517Y136151D01*
G03X1251448Y135991I131J-151D01*
G02X1251450Y135915I-1801J-85D01*
G01Y132515D01*
G02X1251448Y132436I-1803J6D01*
G03X1251517Y132276I200J-9D01*
G01X1251613Y132193D01*
G03X1251779Y132148I130J152D01*
G02X1252047Y132172I267J-1478D01*
G02X1253034Y131802I0J-1501D01*
G01X1253062Y131778D01*
X1253129Y131753D01*
X1253465D01*
X1253532Y131778D01*
X1253560Y131802D01*
G02X1254547Y132172I987J-1131D01*
G02X1256030Y130905I0J-1501D01*
G01X1256037Y130863D01*
X1256082Y130794D01*
X1256398Y130583D01*
X1256479Y130569D01*
X1256520Y130579D01*
G02X1256947Y130630I426J-1751D01*
G02X1257295Y130597I5J-1802D01*
G01X1257335Y130589D01*
X1257413Y130605D01*
X1257717Y130814D01*
X1257759Y130881D01*
X1257766Y130922D01*
G02X1259247Y132172I1481J-252D01*
G02Y129168I0J-1502D01*
G02X1259066Y129179I0J1502D01*
G03X1258908Y129128I-23J-199D01*
G01X1258814Y129043D01*
G03X1258748Y128888I134J-149D01*
G02X1258750Y128828I-1800J-90D01*
G01Y125428D01*
G02X1258748Y125365I-1802J26D01*
G03X1258814Y125210I200J-6D01*
G01X1258908Y125125D01*
G03X1259066Y125074I135J148D01*
G02X1259247Y125085I181J-1491D01*
G02Y122081I0J-1502D01*
G02X1257766Y123333I0J1502D01*
G01X1257759Y123374D01*
X1257716Y123441D01*
X1257413Y123651D01*
X1257335Y123667D01*
X1257294Y123659D01*
G02X1256947Y123626I-343J1769D01*
G02X1256521Y123677I0J1802D01*
G01X1256479Y123687D01*
X1256398Y123672D01*
X1256082Y123462D01*
X1256037Y123392D01*
X1256031Y123350D01*
G02X1254547Y122081I-1484J233D01*
G02X1253559Y122451I-1J1502D01*
G01X1253532Y122476D01*
X1253465Y122501D01*
X1253128D01*
X1253062Y122476D01*
X1253034Y122452D01*
G02X1252047Y122082I-987J1131D01*
G02X1251779Y122106I-1J1502D01*
G03X1251613Y122061I-36J-197D01*
G01X1251517Y121978D01*
G03X1251448Y121818I131J-151D01*
G02X1251450Y121742I-1801J-85D01*
G01Y118342D01*
G02X1251448Y118263I-1803J6D01*
G03X1251517Y118103I200J-9D01*
G01X1251613Y118020D01*
G03X1251779Y117975I130J152D01*
G02X1252047Y117999I267J-1478D01*
G02X1253034Y117629I0J-1501D01*
G01X1253062Y117605D01*
X1253129Y117580D01*
X1253465D01*
X1253532Y117605D01*
X1253560Y117629D01*
G02X1254547Y117999I987J-1131D01*
G02X1256030Y116732I0J-1501D01*
G01X1256037Y116690D01*
X1256082Y116621D01*
X1256398Y116410D01*
X1256479Y116396D01*
X1256520Y116406D01*
G02X1256947Y116458I430J-1751D01*
G02X1257295Y116424I0J-1803D01*
G01X1257335Y116416D01*
X1257413Y116432D01*
X1257717Y116641D01*
X1257759Y116708D01*
X1257766Y116749D01*
G02X1259247Y117998I1481J-254D01*
G02Y114994I0J-1502D01*
G02X1259066Y115005I0J1502D01*
G03X1258908Y114954I-23J-199D01*
G01X1258814Y114869D01*
G03X1258749Y114714I135J-148D01*
G02X1258750Y114655I-1802J-60D01*
G01Y111255D01*
G02X1258748Y111192I-1802J26D01*
G03X1258814Y111037I200J-6D01*
G01X1258908Y110952D01*
G03X1259066Y110901I135J148D01*
G02X1259247Y110912I181J-1491D01*
G02Y107908I0J-1502D01*
G02X1257766Y109160I0J1502D01*
G01X1257759Y109201D01*
X1257716Y109268D01*
X1257413Y109478D01*
X1257335Y109494D01*
X1257294Y109486D01*
G02X1256947Y109452I-348J1769D01*
G02X1256521Y109504I4J1803D01*
G01X1256479Y109514D01*
X1256398Y109499D01*
X1256082Y109289D01*
X1256037Y109219D01*
X1256031Y109177D01*
G02X1254547Y107908I-1484J233D01*
G02Y110912I0J1502D01*
G02X1254815Y110888I1J-1502D01*
G03X1254981Y110933I36J197D01*
G01X1255077Y111016D01*
G03X1255146Y111176I-131J151D01*
G02X1255144Y111255I1801J85D01*
G01Y114655D01*
G02X1255146Y114731I1803J-9D01*
G03X1255077Y114891I-200J9D01*
G01X1254981Y114974D01*
G03X1254815Y115019I-130J-152D01*
G02X1254547Y114995I-267J1478D01*
G02X1253560Y115365I0J1501D01*
G01X1253532Y115389D01*
X1253465Y115414D01*
X1253129D01*
X1253062Y115389D01*
X1253034Y115365D01*
G02X1252047Y114995I-987J1131D01*
G02X1250563Y116264I0J1502D01*
G01X1250557Y116306D01*
X1250512Y116376D01*
X1250196Y116586D01*
X1250115Y116601D01*
X1250073Y116591D01*
G02X1249647Y116540I-426J1751D01*
G02X1249221Y116591I0J1802D01*
G01X1249179Y116601D01*
X1249098Y116586D01*
X1248782Y116376D01*
X1248737Y116306D01*
X1248731Y116264D01*
G02X1247247Y114995I-1484J233D01*
G02Y117999I0J1502D01*
G02X1247515Y117975I1J-1502D01*
G03X1247681Y118020I36J197D01*
G01X1247777Y118103D01*
G03X1247846Y118263I-131J151D01*
G02X1247844Y118342I1801J85D01*
G01Y121742D01*
G02X1247846Y121818I1803J-9D01*
G03X1247777Y121978I-200J9D01*
G01X1247681Y122061D01*
G03X1247515Y122106I-130J-152D01*
G02X1247247Y122082I-267J1478D01*
G02Y125086I0J1502D01*
G02X1248730Y123819I0J-1501D01*
G01X1248737Y123777D01*
X1248782Y123708D01*
X1249098Y123497D01*
X1249179Y123483D01*
X1249220Y123493D01*
G02X1249647Y123544I426J-1751D01*
G02X1250074Y123493I1J-1802D01*
G01X1250115Y123483D01*
X1250196Y123497D01*
X1250512Y123708D01*
X1250557Y123777D01*
X1250564Y123819D01*
G02X1252047Y125086I1483J-234D01*
G02X1253035Y124716I1J-1502D01*
G01X1253062Y124691D01*
X1253129Y124666D01*
X1253466D01*
X1253532Y124691D01*
X1253560Y124715D01*
G02X1254547Y125085I987J-1131D01*
G02X1254815Y125061I1J-1502D01*
G03X1254981Y125106I36J197D01*
G01X1255077Y125189D01*
G03X1255146Y125349I-131J151D01*
G02X1255144Y125428I1801J85D01*
G01Y128828D01*
G02X1255146Y128904I1803J-9D01*
G03X1255077Y129064I-200J9D01*
G01X1254981Y129147D01*
G03X1254815Y129192I-130J-152D01*
G02X1254547Y129168I-267J1478D01*
G02X1253560Y129538I0J1501D01*
G01X1253532Y129562D01*
X1253465Y129587D01*
X1253129D01*
X1253062Y129562D01*
X1253034Y129538D01*
G02X1252047Y129168I-987J1131D01*
G02X1250563Y130437I0J1502D01*
G01X1250557Y130479D01*
X1250512Y130549D01*
X1250196Y130759D01*
X1250115Y130774D01*
X1250073Y130764D01*
G02X1249647Y130712I-430J1751D01*
G02X1249221Y130764I4J1803D01*
G01X1249179Y130774D01*
X1249098Y130759D01*
X1248782Y130549D01*
X1248737Y130479D01*
X1248731Y130437D01*
G02X1247247Y129168I-1484J233D01*
G02Y132172I0J1502D01*
G02X1247515Y132148I1J-1502D01*
G03X1247681Y132193I36J197D01*
G01X1247777Y132276D01*
G03X1247846Y132436I-131J151D01*
G02X1247844Y132515I1801J85D01*
G01Y135915D01*
G02X1247846Y135991I1803J-9D01*
G03X1247777Y136151I-200J9D01*
G01X1247681Y136234D01*
G03X1247515Y136279I-130J-152D01*
G02X1247247Y136255I-267J1478D01*
G02Y139259I0J1502D01*
G02X1248730Y137992I0J-1501D01*
G01X1248737Y137950D01*
X1248782Y137881D01*
X1249098Y137670D01*
X1249179Y137656D01*
X1249220Y137666D01*
G02X1249647Y137718I430J-1751D01*
G02X1250074Y137666I-3J-1803D01*
G01X1250115Y137656D01*
X1250196Y137670D01*
X1250512Y137881D01*
X1250557Y137950D01*
X1250564Y137992D01*
G02X1250632Y138261I1484J-232D01*
G01X1250648Y138307D01*
X1250636Y138400D01*
X1250398Y138748D01*
X1250315Y138793D01*
G37*
G36*
G01X1242838Y110018D02*
X1243154D01*
G03X1243311Y110095I-1J200D01*
G02X1244496Y110674I1185J-923D01*
G02X1245998Y109172I0J-1502D01*
G02X1245034Y107770I-1502J0D01*
G01X1244994Y107754D01*
X1244934Y107693D01*
X1244799Y107331D01*
X1244805Y107245D01*
X1244826Y107207D01*
G02X1245005Y106495I-1323J-711D01*
G02X1242001I-1502J0D01*
G02X1242139Y107123I1502J-1D01*
G01X1242162Y107173D01*
X1242150Y107283D01*
X1241873Y107653D01*
X1241771Y107694D01*
X1241717Y107686D01*
G02X1241496Y107670I-219J1486D01*
G02Y110674I0J1502D01*
G02X1242681Y110095I0J-1502D01*
G03X1242838Y110018I158J123D01*
G37*
G36*
G01X1255605Y105329D02*
X1255565Y105360D01*
G02X1254964Y106561I901J1202D01*
G02X1257968I1502J0D01*
G02X1257242Y105275I-1502J0D01*
G01X1257199Y105249D01*
X1257148Y105164D01*
X1257126Y104732D01*
X1257168Y104643D01*
X1257208Y104612D01*
G02X1257763Y103779I-901J-1202D01*
G01X1257775Y103731D01*
X1257841Y103658D01*
X1258244Y103509D01*
X1258340Y103522D01*
X1258381Y103550D01*
G02X1259247Y103825I866J-1226D01*
G02Y100821I0J-1502D01*
G02X1257791Y101955I0J1502D01*
G01X1257779Y102003D01*
X1257713Y102076D01*
X1257310Y102225D01*
X1257214Y102212D01*
X1257173Y102184D01*
G02X1256307Y101909I-866J1226D01*
G02X1254805Y103411I0J1502D01*
G02X1255531Y104697I1502J0D01*
G01X1255574Y104723D01*
X1255625Y104808D01*
X1255647Y105240D01*
X1255605Y105329D01*
G37*
G36*
G01X1311876Y102731D02*
G02X1311584Y103621I1210J890D01*
G02X1314588I1502J0D01*
G02X1313363Y102145I-1502J0D01*
G03X1313114Y101515I73J-393D01*
G02X1313406Y100625I-1210J-890D01*
G02X1310402I-1502J0D01*
G02X1311627Y102101I1502J0D01*
G03X1311876Y102731I-73J393D01*
G37*
G36*
G01X1276304Y101849D02*
G02X1275721Y103037I919J1188D01*
G02X1278725I1502J0D01*
G02X1278069Y101796I-1502J0D01*
G03X1278049Y101149I225J-331D01*
G02X1278632Y99961I-919J-1188D01*
G02X1275628I-1502J0D01*
G02X1276284Y101202I1502J0D01*
G03X1276304Y101849I-225J331D01*
G37*
G36*
G01X1270817Y91453D02*
G02X1270263Y91347I-554J1395D01*
G02X1271765Y92849I0J1502D01*
G02X1271719Y92481I-1502J1D01*
G03X1272255Y92011I388J-98D01*
G02X1272809Y92117I554J-1395D01*
G02X1271307Y90615I0J-1502D01*
G02X1271353Y90983I1502J-1D01*
G03X1270817Y91453I-388J98D01*
G37*
G36*
G01X1301828Y24856D02*
G02X1300637Y26325I310J1469D01*
G02X1303641I1502J0D01*
G02X1303311Y25385I-1502J-1D01*
G03X1303540Y24743I312J-251D01*
G02X1304731Y23274I-310J-1469D01*
G02X1301727I-1502J0D01*
G02X1302057Y24214I1502J1D01*
G03X1301828Y24856I-312J251D01*
G37*
G36*
G01X1233065Y217133D02*
X1232771D01*
G03X1232624Y217068I1J-200D01*
G02X1231518Y216583I-1105J1017D01*
G02Y219587I0J1502D01*
G02X1232624Y219102I1J-1502D01*
G03X1232771Y219037I148J135D01*
G01X1233065D01*
G03X1233212Y219102I-1J200D01*
G02X1234318Y219587I1105J-1017D01*
G02Y216583I0J-1502D01*
G02X1233212Y217068I-1J1502D01*
G03X1233065Y217133I-148J-135D01*
G37*
G36*
G01X1239245Y205755D02*
X1238909D01*
X1238842Y205730D01*
X1238814Y205706D01*
G02X1237827Y205336I-987J1131D01*
G02Y208340I0J1502D01*
G02X1238814Y207970I0J-1501D01*
G01X1238842Y207946D01*
X1238909Y207921D01*
X1239245D01*
X1239312Y207946D01*
X1239340Y207970D01*
G02X1240327Y208340I987J-1131D01*
G02Y205336I0J-1502D01*
G02X1239340Y205706I0J1501D01*
G01X1239312Y205730D01*
X1239245Y205755D01*
G37*
G36*
G01X1233057Y202310D02*
X1232721D01*
X1232654Y202285D01*
X1232626Y202261D01*
G02X1231639Y201891I-987J1131D01*
G02Y204895I0J1502D01*
G02X1232626Y204525I0J-1501D01*
G01X1232654Y204501D01*
X1232721Y204476D01*
X1233057D01*
X1233124Y204501D01*
X1233152Y204525D01*
G02X1234139Y204895I987J-1131D01*
G02X1235636Y203517I0J-1502D01*
G01X1235639Y203474D01*
X1235680Y203400D01*
X1235987Y203168D01*
X1236068Y203149D01*
X1236111Y203157D01*
G02X1236398Y203185I289J-1474D01*
G02X1237900Y201683I0J-1502D01*
G02X1237415Y200577I-1502J-1D01*
G03X1237350Y200430I135J-148D01*
G01Y200136D01*
G03X1237415Y199989I200J1D01*
G02X1237900Y198883I-1017J-1105D01*
G02X1234896I-1502J0D01*
G02X1235381Y199989I1502J1D01*
G03X1235446Y200136I-135J148D01*
G01Y200430D01*
G03X1235381Y200577I-200J-1D01*
G02X1234901Y201559I1017J1105D01*
G01X1234898Y201602D01*
X1234857Y201676D01*
X1234550Y201908D01*
X1234469Y201927D01*
X1234426Y201919D01*
G02X1234139Y201891I-289J1474D01*
G02X1233152Y202261I0J1501D01*
G01X1233124Y202285D01*
X1233057Y202310D01*
G37*
G36*
G01X1235361Y196259D02*
X1235697D01*
X1235764Y196284D01*
X1235792Y196308D01*
G02X1236779Y196678I987J-1131D01*
G02X1237885Y196193I1J-1502D01*
G03X1238032Y196128I148J135D01*
G01X1238326D01*
G03X1238473Y196193I-1J200D01*
G02X1239579Y196678I1105J-1017D01*
G02Y193674I0J-1502D01*
G02X1238473Y194159I-1J1502D01*
G03X1238326Y194224I-148J-135D01*
G01X1238032D01*
G03X1237885Y194159I1J-200D01*
G02X1236779Y193674I-1105J1017D01*
G02X1235792Y194044I0J1501D01*
G01X1235764Y194068D01*
X1235697Y194093D01*
X1235361D01*
X1235294Y194068D01*
X1235266Y194044D01*
G02X1233292I-987J1131D01*
G01X1233264Y194068D01*
X1233197Y194093D01*
X1232861D01*
X1232794Y194068D01*
X1232766Y194044D01*
G02X1231779Y193674I-987J1131D01*
G02Y196678I0J1502D01*
G02X1232766Y196308I0J-1501D01*
G01X1232794Y196284D01*
X1232861Y196259D01*
X1233197D01*
X1233264Y196284D01*
X1233292Y196308D01*
G02X1235266I987J-1131D01*
G01X1235294Y196284D01*
X1235361Y196259D01*
G37*
G36*
G01X1266667Y84108D02*
Y84460D01*
X1266639Y84529D01*
X1266613Y84557D01*
G02X1266207Y85584I1096J1027D01*
G02X1269211I1502J0D01*
G02X1268805Y84557I-1502J0D01*
G01X1268779Y84529D01*
X1268751Y84460D01*
Y84108D01*
X1268779Y84039D01*
X1268805Y84011D01*
G02Y81957I-1096J-1027D01*
G01X1268779Y81929D01*
X1268751Y81860D01*
Y81508D01*
X1268779Y81439D01*
X1268805Y81411D01*
G02Y79357I-1096J-1027D01*
G01X1268779Y79329D01*
X1268751Y79260D01*
Y78908D01*
X1268779Y78839D01*
X1268805Y78811D01*
G02Y76757I-1096J-1027D01*
G01X1268779Y76729D01*
X1268751Y76660D01*
Y76308D01*
X1268779Y76239D01*
X1268805Y76211D01*
G02X1269211Y75184I-1096J-1027D01*
G02X1266207I-1502J0D01*
G02X1266613Y76211I1502J0D01*
G01X1266639Y76239D01*
X1266667Y76308D01*
Y76660D01*
X1266639Y76729D01*
X1266613Y76757D01*
G02Y78811I1096J1027D01*
G01X1266639Y78839D01*
X1266667Y78908D01*
Y79260D01*
X1266639Y79329D01*
X1266613Y79357D01*
G02Y81411I1096J1027D01*
G01X1266639Y81439D01*
X1266667Y81508D01*
Y81860D01*
X1266639Y81929D01*
X1266613Y81957D01*
G02Y84011I1096J1027D01*
G01X1266639Y84039D01*
X1266667Y84108D01*
G37*
G36*
G01X1285002Y84063D02*
Y84415D01*
X1284974Y84484D01*
X1284948Y84512D01*
G02X1284542Y85539I1096J1027D01*
G02X1287546I1502J0D01*
G02X1287140Y84512I-1502J0D01*
G01X1287114Y84484D01*
X1287086Y84415D01*
Y84063D01*
X1287114Y83994D01*
X1287140Y83966D01*
G02Y81912I-1096J-1027D01*
G01X1287114Y81884D01*
X1287086Y81815D01*
Y81463D01*
X1287114Y81394D01*
X1287140Y81366D01*
G02Y79312I-1096J-1027D01*
G01X1287114Y79284D01*
X1287086Y79215D01*
Y78863D01*
X1287114Y78794D01*
X1287140Y78766D01*
G02Y76712I-1096J-1027D01*
G01X1287114Y76684D01*
X1287086Y76615D01*
Y76263D01*
X1287114Y76194D01*
X1287140Y76166D01*
G02X1287546Y75139I-1096J-1027D01*
G02X1284542I-1502J0D01*
G02X1284948Y76166I1502J0D01*
G01X1284974Y76194D01*
X1285002Y76263D01*
Y76615D01*
X1284974Y76684D01*
X1284948Y76712D01*
G02Y78766I1096J1027D01*
G01X1284974Y78794D01*
X1285002Y78863D01*
Y79215D01*
X1284974Y79284D01*
X1284948Y79312D01*
G02Y81366I1096J1027D01*
G01X1284974Y81394D01*
X1285002Y81463D01*
Y81815D01*
X1284974Y81884D01*
X1284948Y81912D01*
G02Y83966I1096J1027D01*
G01X1284974Y83994D01*
X1285002Y84063D01*
G37*
G36*
G01X1241287Y236121D02*
G02X1244291I1502J0D01*
G02X1243641Y234884I-1502J0D01*
G03X1243647Y234222I227J-329D01*
G02X1244317Y232971I-833J-1251D01*
G02X1241313I-1502J0D01*
G02X1241963Y234208I1502J0D01*
G03X1241957Y234870I-227J329D01*
G02X1241287Y236121I833J1251D01*
G37*
G36*
G01X1239329Y221970D02*
G02X1242333I1502J0D01*
G02X1241963Y220983I-1501J0D01*
G01X1241939Y220955D01*
X1241914Y220888D01*
Y220552D01*
X1241939Y220485D01*
X1241963Y220457D01*
G02Y218483I-1131J-987D01*
G01X1241939Y218455D01*
X1241914Y218388D01*
Y218052D01*
X1241939Y217985D01*
X1241963Y217957D01*
G02X1242333Y216970I-1131J-987D01*
G02X1240831Y215468I-1502J0D01*
G02X1239976Y215735I0J1502D01*
G01X1239942Y215759D01*
X1239861Y215775D01*
X1239494Y215696D01*
X1239427Y215648D01*
X1239406Y215612D01*
G02X1238118Y214883I-1288J773D01*
G02Y217887I0J1502D01*
G02X1238973Y217620I0J-1502D01*
G01X1239007Y217596D01*
X1239088Y217580D01*
X1239455Y217659D01*
X1239522Y217707D01*
X1239543Y217743D01*
G02X1239699Y217957I1287J-774D01*
G01X1239723Y217985D01*
X1239748Y218052D01*
Y218388D01*
X1239723Y218455D01*
X1239699Y218483D01*
G02Y220457I1131J987D01*
G01X1239723Y220485D01*
X1239748Y220552D01*
Y220888D01*
X1239723Y220955D01*
X1239699Y220983D01*
G02X1239329Y221970I1131J987D01*
G37*
G36*
G01X1297027Y223294D02*
Y223630D01*
X1297002Y223697D01*
X1296978Y223725D01*
G02X1296608Y224712I1131J987D01*
G02X1299612I1502J0D01*
G02X1299242Y223725I-1501J0D01*
G01X1299218Y223697D01*
X1299193Y223630D01*
Y223294D01*
X1299218Y223227D01*
X1299242Y223199D01*
G02X1299612Y222212I-1131J-987D01*
G02X1296608I-1502J0D01*
G02X1296978Y223199I1501J0D01*
G01X1297002Y223227D01*
X1297027Y223294D01*
G37*
G36*
G01X1291702Y225189D02*
X1291408D01*
G03X1291261Y225124I1J-200D01*
G02X1290155Y224639I-1105J1017D01*
G02Y227643I0J1502D01*
G02X1291261Y227158I1J-1502D01*
G03X1291408Y227093I148J135D01*
G01X1291702D01*
G03X1291849Y227158I-1J200D01*
G02X1292955Y227643I1105J-1017D01*
G02Y224639I0J-1502D01*
G02X1291849Y225124I-1J1502D01*
G03X1291702Y225189I-148J-135D01*
G37*
G36*
G01X1274909Y229808D02*
Y230144D01*
X1274884Y230211D01*
X1274860Y230239D01*
G02X1274490Y231226I1131J987D01*
G02X1277494I1502J0D01*
G02X1277124Y230239I-1501J0D01*
G01X1277100Y230211D01*
X1277075Y230144D01*
Y229808D01*
X1277100Y229741D01*
X1277124Y229713D01*
G02Y227739I-1131J-987D01*
G01X1277100Y227711D01*
X1277075Y227644D01*
Y227308D01*
X1277100Y227241D01*
X1277124Y227213D01*
G02Y225239I-1131J-987D01*
G01X1277100Y225211D01*
X1277075Y225144D01*
Y224808D01*
X1277100Y224741D01*
X1277124Y224713D01*
G02X1277494Y223726I-1131J-987D01*
G02X1274490I-1502J0D01*
G02X1274860Y224713I1501J0D01*
G01X1274884Y224741D01*
X1274909Y224808D01*
Y225144D01*
X1274884Y225211D01*
X1274860Y225239D01*
G02Y227213I1131J987D01*
G01X1274884Y227241D01*
X1274909Y227308D01*
Y227644D01*
X1274884Y227711D01*
X1274860Y227739D01*
G02Y229713I1131J987D01*
G01X1274884Y229741D01*
X1274909Y229808D01*
G37*
G36*
G01X1285365Y230043D02*
Y230379D01*
X1285340Y230446D01*
X1285316Y230474D01*
G02X1284946Y231461I1131J987D01*
G02X1287950I1502J0D01*
G02X1287580Y230474I-1501J0D01*
G01X1287556Y230446D01*
X1287531Y230379D01*
Y230043D01*
X1287556Y229976D01*
X1287580Y229948D01*
G02Y227974I-1131J-987D01*
G01X1287556Y227946D01*
X1287531Y227879D01*
Y227543D01*
X1287556Y227476D01*
X1287580Y227448D01*
G02X1287950Y226461I-1131J-987D01*
G02X1287465Y225355I-1502J-1D01*
G03X1287400Y225208I135J-148D01*
G01Y224914D01*
G03X1287465Y224767I200J1D01*
G02X1287950Y223661I-1017J-1105D01*
G02X1284946I-1502J0D01*
G02X1285431Y224767I1502J1D01*
G03X1285496Y224914I-135J148D01*
G01Y225208D01*
G03X1285431Y225355I-200J-1D01*
G02X1284946Y226461I1017J1105D01*
G02X1285316Y227448I1501J0D01*
G01X1285340Y227476D01*
X1285365Y227543D01*
Y227879D01*
X1285340Y227946D01*
X1285316Y227974D01*
G02Y229948I1131J987D01*
G01X1285340Y229976D01*
X1285365Y230043D01*
G37*
G36*
G01X1293334Y230368D02*
Y230704D01*
X1293309Y230771D01*
X1293285Y230799D01*
G02X1292915Y231786I1131J987D01*
G02X1295919I1502J0D01*
G02X1295549Y230799I-1501J0D01*
G01X1295525Y230771D01*
X1295500Y230704D01*
Y230368D01*
X1295525Y230301D01*
X1295549Y230273D01*
G02X1295919Y229286I-1131J-987D01*
G02X1292915I-1502J0D01*
G02X1293285Y230273I1501J0D01*
G01X1293309Y230301D01*
X1293334Y230368D01*
G37*
G36*
G01X1291480Y237694D02*
X1291816D01*
X1291883Y237719D01*
X1291911Y237743D01*
G02X1293885I987J-1131D01*
G01X1293913Y237719D01*
X1293980Y237694D01*
X1294316D01*
X1294383Y237719D01*
X1294411Y237743D01*
G02X1295398Y238113I987J-1131D01*
G02Y235109I0J-1502D01*
G02X1294411Y235479I0J1501D01*
G01X1294383Y235503D01*
X1294316Y235528D01*
X1293980D01*
X1293913Y235503D01*
X1293885Y235479D01*
G02X1291911I-987J1131D01*
G01X1291883Y235503D01*
X1291816Y235528D01*
X1291480D01*
X1291413Y235503D01*
X1291385Y235479D01*
G02X1290398Y235109I-987J1131D01*
G02Y238113I0J1502D01*
G02X1291385Y237743I0J-1501D01*
G01X1291413Y237719D01*
X1291480Y237694D01*
G37*
G36*
G01X1291182Y249974D02*
X1291518D01*
X1291585Y249999D01*
X1291613Y250023D01*
G02X1293587I987J-1131D01*
G01X1293615Y249999D01*
X1293682Y249974D01*
X1294018D01*
X1294085Y249999D01*
X1294113Y250023D01*
G02X1295100Y250393I987J-1131D01*
G02Y247389I0J-1502D01*
G02X1294113Y247759I0J1501D01*
G01X1294085Y247783D01*
X1294018Y247808D01*
X1293682D01*
X1293615Y247783D01*
X1293587Y247759D01*
G02X1291613I-987J1131D01*
G01X1291585Y247783D01*
X1291518Y247808D01*
X1291182D01*
X1291115Y247783D01*
X1291087Y247759D01*
G02X1290100Y247389I-987J1131D01*
G02Y250393I0J1502D01*
G02X1291087Y250023I0J-1501D01*
G01X1291115Y249999D01*
X1291182Y249974D01*
G37*
G36*
G01X1295477Y190705D02*
G02X1294829Y191941I855J1236D01*
G02X1297833I1502J0D01*
G02X1297080Y190639I-1502J0D01*
G03X1297052Y189963I199J-347D01*
G02X1297700Y188727I-855J-1236D01*
G02X1294696I-1502J0D01*
G02X1295449Y190029I1502J0D01*
G03X1295477Y190705I-199J347D01*
G37*
G36*
G01X1319520Y185330D02*
X1319655Y185710D01*
X1319645Y185800D01*
X1319621Y185839D01*
G02X1319396Y186629I1277J791D01*
G02X1322400I1502J0D01*
G02X1321397Y185212I-1502J0D01*
G01X1321353Y185197D01*
X1321290Y185133D01*
X1321155Y184753D01*
X1321165Y184663D01*
X1321189Y184624D01*
G02X1321414Y183834I-1277J-791D01*
G02X1318410I-1502J0D01*
G02X1319413Y185251I1502J0D01*
G01X1319457Y185266D01*
X1319520Y185330D01*
G37*
G36*
G01X1306532Y890115D02*
X1306936D01*
X1307018Y890154D01*
X1307046Y890190D01*
G02X1308220Y890755I1174J-937D01*
G02X1309358Y890234I0J-1503D01*
G01X1309387Y890200D01*
X1309468Y890164D01*
X1309864Y890170D01*
X1309943Y890209D01*
X1309971Y890243D01*
G02X1311061Y890763I1090J-882D01*
G02Y887959I0J-1402D01*
G02X1310042Y888399I1J1402D01*
G01X1310011Y888431D01*
X1309928Y888464D01*
X1309533Y888440D01*
X1309455Y888397D01*
X1309429Y888361D01*
G02X1308220Y887751I-1209J893D01*
G02X1307048Y888313I0J1503D01*
G01X1307019Y888349D01*
X1306938Y888388D01*
X1306534D01*
X1306452Y888349D01*
X1306424Y888313D01*
G02X1305250Y887748I-1174J937D01*
G02Y890752I0J1502D01*
G02X1306422Y890190I0J-1503D01*
G01X1306451Y890154D01*
X1306532Y890115D01*
G37*
G36*
G01X1287077Y891270D02*
X1286715Y891245D01*
X1286646Y891211D01*
X1286619Y891181D01*
G02X1285493Y890673I-1126J994D01*
G02Y893677I0J1502D01*
G02X1286476Y893310I-1J-1502D01*
G01X1286507Y893284D01*
X1286580Y893259D01*
X1286942Y893284D01*
X1287011Y893318D01*
X1287038Y893348D01*
G02X1288164Y893856I1126J-994D01*
G02X1289362Y893260I0J-1502D01*
G01X1289390Y893223D01*
X1289470Y893182D01*
X1289874Y893170D01*
X1289956Y893206D01*
X1289986Y893241D01*
G02X1291129Y893769I1143J-973D01*
G02Y890765I0J-1502D01*
G02X1289931Y891361I0J1502D01*
G01X1289903Y891398D01*
X1289823Y891439D01*
X1289419Y891451D01*
X1289337Y891415D01*
X1289307Y891380D01*
G02X1288164Y890852I-1143J973D01*
G02X1287181Y891219I1J1502D01*
G01X1287150Y891245D01*
X1287077Y891270D01*
G37*
G36*
G01X1365963Y1003333D02*
X1365600Y1003469D01*
X1365514Y1003463D01*
X1365476Y1003443D01*
G02X1364765Y1003264I-711J1323D01*
G02Y1006268I0J1502D01*
G02X1366170Y1005297I0J-1502D01*
G01X1366185Y1005256D01*
X1366246Y1005196D01*
X1366609Y1005060D01*
X1366695Y1005066D01*
X1366733Y1005086D01*
G02X1367444Y1005265I711J-1323D01*
G02Y1002261I0J-1502D01*
G02X1366039Y1003232I0J1502D01*
G01X1366024Y1003273D01*
X1365963Y1003333D01*
G37*
G36*
G01X1339713Y1027376D02*
Y1027670D01*
G03X1339648Y1027817I-200J-1D01*
G02X1339163Y1028923I1017J1105D01*
G02X1340665Y1030425I1502J0D01*
G02X1341771Y1029940I1J-1502D01*
G03X1341918Y1029875I148J135D01*
G01X1342212D01*
G03X1342359Y1029940I-1J200D01*
G02X1343465Y1030425I1105J-1017D01*
G02X1344967Y1028923I0J-1502D01*
G02X1344482Y1027817I-1502J-1D01*
G03X1344417Y1027670I135J-148D01*
G01Y1027376D01*
G03X1344482Y1027229I200J1D01*
G02X1344967Y1026123I-1017J-1105D01*
G02X1343465Y1024621I-1502J0D01*
G02X1342359Y1025106I-1J1502D01*
G03X1342212Y1025171I-148J-135D01*
G01X1341918D01*
G03X1341771Y1025106I1J-200D01*
G02X1340665Y1024621I-1105J1017D01*
G02X1339163Y1026123I0J1502D01*
G02X1339648Y1027229I1502J1D01*
G03X1339713Y1027376I-135J148D01*
G37*
G36*
G01X1325303Y1061780D02*
X1325639D01*
X1325706Y1061805D01*
X1325734Y1061829D01*
G02X1327708I987J-1131D01*
G01X1327736Y1061805D01*
X1327803Y1061780D01*
X1328139D01*
X1328206Y1061805D01*
X1328234Y1061829D01*
G02X1329221Y1062199I987J-1131D01*
G02X1330723Y1060697I0J-1502D01*
G02X1330317Y1059670I-1502J0D01*
G01X1330291Y1059642D01*
X1330263Y1059573D01*
Y1059221D01*
X1330291Y1059152D01*
X1330317Y1059124D01*
G02X1330723Y1058097I-1096J-1027D01*
G02X1329221Y1056595I-1502J0D01*
G02X1328234Y1056965I0J1501D01*
G01X1328206Y1056989D01*
X1328139Y1057014D01*
X1327803D01*
X1327736Y1056989D01*
X1327708Y1056965D01*
G02X1325734I-987J1131D01*
G01X1325706Y1056989D01*
X1325639Y1057014D01*
X1325303D01*
X1325236Y1056989D01*
X1325208Y1056965D01*
G02X1323234I-987J1131D01*
G01X1323206Y1056989D01*
X1323139Y1057014D01*
X1322803D01*
X1322736Y1056989D01*
X1322708Y1056965D01*
G02X1320734I-987J1131D01*
G01X1320706Y1056989D01*
X1320639Y1057014D01*
X1320303D01*
X1320236Y1056989D01*
X1320208Y1056965D01*
G02X1319221Y1056595I-987J1131D01*
G02X1317719Y1058097I0J1502D01*
G02X1318125Y1059124I1502J0D01*
G01X1318151Y1059152D01*
X1318179Y1059221D01*
Y1059573D01*
X1318151Y1059642D01*
X1318125Y1059670D01*
G02X1317719Y1060697I1096J1027D01*
G02X1319221Y1062199I1502J0D01*
G02X1320208Y1061829I0J-1501D01*
G01X1320236Y1061805D01*
X1320303Y1061780D01*
X1320639D01*
X1320706Y1061805D01*
X1320734Y1061829D01*
G02X1322708I987J-1131D01*
G01X1322736Y1061805D01*
X1322803Y1061780D01*
X1323139D01*
X1323206Y1061805D01*
X1323234Y1061829D01*
G02X1325208I987J-1131D01*
G01X1325236Y1061805D01*
X1325303Y1061780D01*
G37*
G36*
G01X1413433D02*
X1413769D01*
X1413836Y1061805D01*
X1413864Y1061829D01*
G02X1415838I987J-1131D01*
G01X1415866Y1061805D01*
X1415933Y1061780D01*
X1416269D01*
X1416336Y1061805D01*
X1416364Y1061829D01*
G02X1417351Y1062199I987J-1131D01*
G02X1418853Y1060697I0J-1502D01*
G02X1418447Y1059670I-1502J0D01*
G01X1418421Y1059642D01*
X1418393Y1059573D01*
Y1059221D01*
X1418421Y1059152D01*
X1418447Y1059124D01*
G02X1418853Y1058097I-1096J-1027D01*
G02X1417351Y1056595I-1502J0D01*
G02X1416364Y1056965I0J1501D01*
G01X1416336Y1056989D01*
X1416269Y1057014D01*
X1415933D01*
X1415866Y1056989D01*
X1415838Y1056965D01*
G02X1413864I-987J1131D01*
G01X1413836Y1056989D01*
X1413769Y1057014D01*
X1413433D01*
X1413366Y1056989D01*
X1413338Y1056965D01*
G02X1411364I-987J1131D01*
G01X1411336Y1056989D01*
X1411269Y1057014D01*
X1410933D01*
X1410866Y1056989D01*
X1410838Y1056965D01*
G02X1408864I-987J1131D01*
G01X1408836Y1056989D01*
X1408769Y1057014D01*
X1408433D01*
X1408366Y1056989D01*
X1408338Y1056965D01*
G02X1407351Y1056595I-987J1131D01*
G02X1405849Y1058097I0J1502D01*
G02X1406255Y1059124I1502J0D01*
G01X1406281Y1059152D01*
X1406309Y1059221D01*
Y1059573D01*
X1406281Y1059642D01*
X1406255Y1059670D01*
G02X1405849Y1060697I1096J1027D01*
G02X1407351Y1062199I1502J0D01*
G02X1408338Y1061829I0J-1501D01*
G01X1408366Y1061805D01*
X1408433Y1061780D01*
X1408769D01*
X1408836Y1061805D01*
X1408864Y1061829D01*
G02X1410838I987J-1131D01*
G01X1410866Y1061805D01*
X1410933Y1061780D01*
X1411269D01*
X1411336Y1061805D01*
X1411364Y1061829D01*
G02X1413338I987J-1131D01*
G01X1413366Y1061805D01*
X1413433Y1061780D01*
G37*
G36*
G01X1411759Y1087879D02*
X1412095D01*
X1412162Y1087904D01*
X1412190Y1087928D01*
G02X1414164I987J-1131D01*
G01X1414192Y1087904D01*
X1414259Y1087879D01*
X1414595D01*
X1414662Y1087904D01*
X1414690Y1087928D01*
G02X1415677Y1088298I987J-1131D01*
G02X1417179Y1086796I0J-1502D01*
G02X1416809Y1085809I-1501J0D01*
G01X1416785Y1085781D01*
X1416760Y1085714D01*
Y1085378D01*
X1416785Y1085311D01*
X1416809Y1085283D01*
G02X1417179Y1084296I-1131J-987D01*
G02X1415677Y1082794I-1502J0D01*
G02X1414690Y1083164I0J1501D01*
G01X1414662Y1083188D01*
X1414595Y1083213D01*
X1414259D01*
X1414192Y1083188D01*
X1414164Y1083164D01*
G02X1412190I-987J1131D01*
G01X1412162Y1083188D01*
X1412095Y1083213D01*
X1411759D01*
X1411692Y1083188D01*
X1411664Y1083164D01*
G02X1409690I-987J1131D01*
G01X1409662Y1083188D01*
X1409595Y1083213D01*
X1409259D01*
X1409192Y1083188D01*
X1409164Y1083164D01*
G02X1407190I-987J1131D01*
G01X1407162Y1083188D01*
X1407095Y1083213D01*
X1406759D01*
X1406692Y1083188D01*
X1406664Y1083164D01*
G02X1405677Y1082794I-987J1131D01*
G02X1404175Y1084296I0J1502D01*
G02X1404545Y1085283I1501J0D01*
G01X1404569Y1085311D01*
X1404594Y1085378D01*
Y1085714D01*
X1404569Y1085781D01*
X1404545Y1085809D01*
G02X1404175Y1086796I1131J987D01*
G02X1405677Y1088298I1502J0D01*
G02X1406664Y1087928I0J-1501D01*
G01X1406692Y1087904D01*
X1406759Y1087879D01*
X1407095D01*
X1407162Y1087904D01*
X1407190Y1087928D01*
G02X1409164I987J-1131D01*
G01X1409192Y1087904D01*
X1409259Y1087879D01*
X1409595D01*
X1409662Y1087904D01*
X1409690Y1087928D01*
G02X1411664I987J-1131D01*
G01X1411692Y1087904D01*
X1411759Y1087879D01*
G37*
G36*
G01X1391672Y1087827D02*
Y1088037D01*
G03X1391615Y1088176I-200J-1D01*
G02X1391189Y1089224I1076J1048D01*
G02X1394193I1502J0D01*
G02X1393823Y1088237I-1501J0D01*
G01X1393799Y1088209D01*
X1393774Y1088142D01*
Y1087806D01*
X1393799Y1087739D01*
X1393823Y1087711D01*
G02Y1085737I-1131J-987D01*
G01X1393799Y1085709D01*
X1393774Y1085642D01*
Y1085306D01*
X1393799Y1085239D01*
X1393823Y1085211D01*
G02Y1083237I-1131J-987D01*
G01X1393799Y1083209D01*
X1393774Y1083142D01*
Y1082806D01*
X1393799Y1082739D01*
X1393823Y1082711D01*
G02X1394193Y1081724I-1131J-987D01*
G02X1392691Y1080222I-1502J0D01*
G02X1391704Y1080592I0J1501D01*
G01X1391676Y1080616D01*
X1391609Y1080641D01*
X1391273D01*
X1391206Y1080616D01*
X1391178Y1080592D01*
G02X1390191Y1080222I-987J1131D01*
G02X1388689Y1081724I0J1502D01*
G02X1389059Y1082711I1501J0D01*
G01X1389083Y1082739D01*
X1389108Y1082806D01*
Y1083142D01*
X1389083Y1083209D01*
X1389059Y1083237D01*
G02Y1085211I1131J987D01*
G01X1389083Y1085239D01*
X1389108Y1085306D01*
Y1085642D01*
X1389083Y1085709D01*
X1389059Y1085737D01*
G02X1388689Y1086724I1131J987D01*
G02X1390191Y1088226I1502J0D01*
G02X1391239Y1087800I0J-1502D01*
G03X1391378Y1087743I140J143D01*
G01X1391504D01*
G03X1391643Y1087800I-1J200D01*
G02X1391672Y1087827I1038J-1086D01*
G37*
G36*
G01X1387623Y1091347D02*
X1387613Y1091749D01*
X1387572Y1091829D01*
X1387536Y1091857D01*
G02X1386949Y1093048I915J1191D01*
G02X1389953I1502J0D01*
G02X1389423Y1091903I-1502J0D01*
G01X1389388Y1091874D01*
X1389351Y1091791D01*
X1389361Y1091389D01*
X1389402Y1091309D01*
X1389438Y1091281D01*
G02X1390025Y1090090I-915J-1191D01*
G02X1387021I-1502J0D01*
G02X1387551Y1091235I1502J0D01*
G01X1387586Y1091264D01*
X1387623Y1091347D01*
G37*
G36*
G01X1415053Y1091541D02*
Y1091835D01*
G03X1414988Y1091982I-200J-1D01*
G02X1414503Y1093088I1017J1105D01*
G02X1417507I1502J0D01*
G02X1417022Y1091982I-1502J-1D01*
G03X1416957Y1091835I135J-148D01*
G01Y1091541D01*
G03X1417022Y1091394I200J1D01*
G02X1417507Y1090288I-1017J-1105D01*
G02X1414503I-1502J0D01*
G02X1414988Y1091394I1502J1D01*
G03X1415053Y1091541I-135J148D01*
G37*
G36*
G01X1327672Y1112565D02*
X1327336D01*
X1327269Y1112540D01*
X1327241Y1112516D01*
G02X1326254Y1112146I-987J1131D01*
G02Y1115150I0J1502D01*
G02X1327241Y1114780I0J-1501D01*
G01X1327269Y1114756D01*
X1327336Y1114731D01*
X1327672D01*
X1327739Y1114756D01*
X1327767Y1114780D01*
G02X1328754Y1115150I987J-1131D01*
G02Y1112146I0J-1502D01*
G02X1327767Y1112516I0J1501D01*
G01X1327739Y1112540D01*
X1327672Y1112565D01*
G37*
G36*
G01X1359800D02*
X1359464D01*
X1359397Y1112540D01*
X1359369Y1112516D01*
G02X1358382Y1112146I-987J1131D01*
G02Y1115150I0J1502D01*
G02X1359369Y1114780I0J-1501D01*
G01X1359397Y1114756D01*
X1359464Y1114731D01*
X1359800D01*
X1359867Y1114756D01*
X1359895Y1114780D01*
G02X1360882Y1115150I987J-1131D01*
G02Y1112146I0J-1502D01*
G02X1359895Y1112516I0J1501D01*
G01X1359867Y1112540D01*
X1359800Y1112565D01*
G37*
G36*
G01X1393259D02*
X1392923D01*
X1392856Y1112540D01*
X1392828Y1112516D01*
G02X1391841Y1112146I-987J1131D01*
G02Y1115150I0J1502D01*
G02X1392828Y1114780I0J-1501D01*
G01X1392856Y1114756D01*
X1392923Y1114731D01*
X1393259D01*
X1393326Y1114756D01*
X1393354Y1114780D01*
G02X1394341Y1115150I987J-1131D01*
G02Y1112146I0J-1502D01*
G02X1393354Y1112516I0J1501D01*
G01X1393326Y1112540D01*
X1393259Y1112565D01*
G37*
G36*
G01X1425387D02*
X1425051D01*
X1424984Y1112540D01*
X1424956Y1112516D01*
G02X1423969Y1112146I-987J1131D01*
G02Y1115150I0J1502D01*
G02X1424956Y1114780I0J-1501D01*
G01X1424984Y1114756D01*
X1425051Y1114731D01*
X1425387D01*
X1425454Y1114756D01*
X1425482Y1114780D01*
G02X1426469Y1115150I987J-1131D01*
G02Y1112146I0J-1502D01*
G02X1425482Y1112516I0J1501D01*
G01X1425454Y1112540D01*
X1425387Y1112565D01*
G37*
G36*
G01X1344567Y1116978D02*
Y1117314D01*
X1344542Y1117381D01*
X1344518Y1117409D01*
G02X1344148Y1118396I1131J987D01*
G02X1347152I1502J0D01*
G02X1346782Y1117409I-1501J0D01*
G01X1346758Y1117381D01*
X1346733Y1117314D01*
Y1116978D01*
X1346758Y1116911D01*
X1346782Y1116883D01*
G02X1347152Y1115896I-1131J-987D01*
G02X1344148I-1502J0D01*
G02X1344518Y1116883I1501J0D01*
G01X1344542Y1116911D01*
X1344567Y1116978D01*
G37*
G36*
G01X1376695D02*
Y1117314D01*
X1376670Y1117381D01*
X1376646Y1117409D01*
G02X1376276Y1118396I1131J987D01*
G02X1379280I1502J0D01*
G02X1378910Y1117409I-1501J0D01*
G01X1378886Y1117381D01*
X1378861Y1117314D01*
Y1116978D01*
X1378886Y1116911D01*
X1378910Y1116883D01*
G02X1379280Y1115896I-1131J-987D01*
G02X1376276I-1502J0D01*
G02X1376646Y1116883I1501J0D01*
G01X1376670Y1116911D01*
X1376695Y1116978D01*
G37*
G36*
G01X1410154D02*
Y1117314D01*
X1410129Y1117381D01*
X1410105Y1117409D01*
G02X1409735Y1118396I1131J987D01*
G02X1412739I1502J0D01*
G02X1412369Y1117409I-1501J0D01*
G01X1412345Y1117381D01*
X1412320Y1117314D01*
Y1116978D01*
X1412345Y1116911D01*
X1412369Y1116883D01*
G02X1412739Y1115896I-1131J-987D01*
G02X1409735I-1502J0D01*
G02X1410105Y1116883I1501J0D01*
G01X1410129Y1116911D01*
X1410154Y1116978D01*
G37*
G36*
G01X1442282D02*
Y1117314D01*
X1442257Y1117381D01*
X1442233Y1117409D01*
G02X1441863Y1118396I1131J987D01*
G02X1444867I1502J0D01*
G02X1444497Y1117409I-1501J0D01*
G01X1444473Y1117381D01*
X1444448Y1117314D01*
Y1116978D01*
X1444473Y1116911D01*
X1444497Y1116883D01*
G02X1444867Y1115896I-1131J-987D01*
G02X1441863I-1502J0D01*
G02X1442233Y1116883I1501J0D01*
G01X1442257Y1116911D01*
X1442282Y1116978D01*
G37*
G36*
G01X1322052Y1173466D02*
Y1173802D01*
X1322027Y1173869D01*
X1322003Y1173897D01*
G02X1321633Y1174884I1131J987D01*
G02X1323135Y1176386I1502J0D01*
G02X1324122Y1176016I0J-1501D01*
G01X1324150Y1175992D01*
X1324217Y1175967D01*
X1324553D01*
X1324620Y1175992D01*
X1324648Y1176016D01*
G02X1325635Y1176386I987J-1131D01*
G02X1327137Y1174884I0J-1502D01*
G02X1326767Y1173897I-1501J0D01*
G01X1326743Y1173869D01*
X1326718Y1173802D01*
Y1173466D01*
X1326743Y1173399D01*
X1326767Y1173371D01*
G02Y1171397I-1131J-987D01*
G01X1326743Y1171369D01*
X1326718Y1171302D01*
Y1170966D01*
X1326743Y1170899D01*
X1326767Y1170871D01*
G02Y1168897I-1131J-987D01*
G01X1326743Y1168869D01*
X1326718Y1168802D01*
Y1168466D01*
X1326743Y1168399D01*
X1326767Y1168371D01*
G02Y1166397I-1131J-987D01*
G01X1326743Y1166369D01*
X1326718Y1166302D01*
Y1165966D01*
X1326743Y1165899D01*
X1326767Y1165871D01*
G02Y1163897I-1131J-987D01*
G01X1326743Y1163869D01*
X1326718Y1163802D01*
Y1163466D01*
X1326743Y1163399D01*
X1326767Y1163371D01*
G02X1327137Y1162384I-1131J-987D01*
G02X1325635Y1160882I-1502J0D01*
G02X1324648Y1161252I0J1501D01*
G01X1324620Y1161276D01*
X1324553Y1161301D01*
X1324217D01*
X1324150Y1161276D01*
X1324122Y1161252D01*
G02X1323135Y1160882I-987J1131D01*
G02X1321633Y1162384I0J1502D01*
G02X1322003Y1163371I1501J0D01*
G01X1322027Y1163399D01*
X1322052Y1163466D01*
Y1163802D01*
X1322027Y1163869D01*
X1322003Y1163897D01*
G02Y1165871I1131J987D01*
G01X1322027Y1165899D01*
X1322052Y1165966D01*
Y1166302D01*
X1322027Y1166369D01*
X1322003Y1166397D01*
G02Y1168371I1131J987D01*
G01X1322027Y1168399D01*
X1322052Y1168466D01*
Y1168802D01*
X1322027Y1168869D01*
X1322003Y1168897D01*
G02Y1170871I1131J987D01*
G01X1322027Y1170899D01*
X1322052Y1170966D01*
Y1171302D01*
X1322027Y1171369D01*
X1322003Y1171397D01*
G02Y1173371I1131J987D01*
G01X1322027Y1173399D01*
X1322052Y1173466D01*
G37*
G36*
G01X1340322D02*
Y1173802D01*
X1340297Y1173869D01*
X1340273Y1173897D01*
G02X1339903Y1174884I1131J987D01*
G02X1341405Y1176386I1502J0D01*
G02X1342392Y1176016I0J-1501D01*
G01X1342420Y1175992D01*
X1342487Y1175967D01*
X1342823D01*
X1342890Y1175992D01*
X1342918Y1176016D01*
G02X1343905Y1176386I987J-1131D01*
G02X1345407Y1174884I0J-1502D01*
G02X1345037Y1173897I-1501J0D01*
G01X1345013Y1173869D01*
X1344988Y1173802D01*
Y1173466D01*
X1345013Y1173399D01*
X1345037Y1173371D01*
G02Y1171397I-1131J-987D01*
G01X1345013Y1171369D01*
X1344988Y1171302D01*
Y1170966D01*
X1345013Y1170899D01*
X1345037Y1170871D01*
G02Y1168897I-1131J-987D01*
G01X1345013Y1168869D01*
X1344988Y1168802D01*
Y1168466D01*
X1345013Y1168399D01*
X1345037Y1168371D01*
G02Y1166397I-1131J-987D01*
G01X1345013Y1166369D01*
X1344988Y1166302D01*
Y1165966D01*
X1345013Y1165899D01*
X1345037Y1165871D01*
G02Y1163897I-1131J-987D01*
G01X1345013Y1163869D01*
X1344988Y1163802D01*
Y1163466D01*
X1345013Y1163399D01*
X1345037Y1163371D01*
G02X1345407Y1162384I-1131J-987D01*
G02X1343905Y1160882I-1502J0D01*
G02X1342918Y1161252I0J1501D01*
G01X1342890Y1161276D01*
X1342823Y1161301D01*
X1342487D01*
X1342420Y1161276D01*
X1342392Y1161252D01*
G02X1341405Y1160882I-987J1131D01*
G02X1339903Y1162384I0J1502D01*
G02X1340273Y1163371I1501J0D01*
G01X1340297Y1163399D01*
X1340322Y1163466D01*
Y1163802D01*
X1340297Y1163869D01*
X1340273Y1163897D01*
G02Y1165871I1131J987D01*
G01X1340297Y1165899D01*
X1340322Y1165966D01*
Y1166302D01*
X1340297Y1166369D01*
X1340273Y1166397D01*
G02Y1168371I1131J987D01*
G01X1340297Y1168399D01*
X1340322Y1168466D01*
Y1168802D01*
X1340297Y1168869D01*
X1340273Y1168897D01*
G02Y1170871I1131J987D01*
G01X1340297Y1170899D01*
X1340322Y1170966D01*
Y1171302D01*
X1340297Y1171369D01*
X1340273Y1171397D01*
G02Y1173371I1131J987D01*
G01X1340297Y1173399D01*
X1340322Y1173466D01*
G37*
G36*
G01X1349880D02*
Y1173802D01*
X1349855Y1173869D01*
X1349831Y1173897D01*
G02X1349461Y1174884I1131J987D01*
G02X1350963Y1176386I1502J0D01*
G02X1351950Y1176016I0J-1501D01*
G01X1351978Y1175992D01*
X1352045Y1175967D01*
X1352381D01*
X1352448Y1175992D01*
X1352476Y1176016D01*
G02X1353463Y1176386I987J-1131D01*
G02X1354965Y1174884I0J-1502D01*
G02X1354595Y1173897I-1501J0D01*
G01X1354571Y1173869D01*
X1354546Y1173802D01*
Y1173466D01*
X1354571Y1173399D01*
X1354595Y1173371D01*
G02Y1171397I-1131J-987D01*
G01X1354571Y1171369D01*
X1354546Y1171302D01*
Y1170966D01*
X1354571Y1170899D01*
X1354595Y1170871D01*
G02Y1168897I-1131J-987D01*
G01X1354571Y1168869D01*
X1354546Y1168802D01*
Y1168466D01*
X1354571Y1168399D01*
X1354595Y1168371D01*
G02Y1166397I-1131J-987D01*
G01X1354571Y1166369D01*
X1354546Y1166302D01*
Y1165966D01*
X1354571Y1165899D01*
X1354595Y1165871D01*
G02Y1163897I-1131J-987D01*
G01X1354571Y1163869D01*
X1354546Y1163802D01*
Y1163466D01*
X1354571Y1163399D01*
X1354595Y1163371D01*
G02X1354965Y1162384I-1131J-987D01*
G02X1353463Y1160882I-1502J0D01*
G02X1352476Y1161252I0J1501D01*
G01X1352448Y1161276D01*
X1352381Y1161301D01*
X1352045D01*
X1351978Y1161276D01*
X1351950Y1161252D01*
G02X1350963Y1160882I-987J1131D01*
G02X1349461Y1162384I0J1502D01*
G02X1349831Y1163371I1501J0D01*
G01X1349855Y1163399D01*
X1349880Y1163466D01*
Y1163802D01*
X1349855Y1163869D01*
X1349831Y1163897D01*
G02Y1165871I1131J987D01*
G01X1349855Y1165899D01*
X1349880Y1165966D01*
Y1166302D01*
X1349855Y1166369D01*
X1349831Y1166397D01*
G02Y1168371I1131J987D01*
G01X1349855Y1168399D01*
X1349880Y1168466D01*
Y1168802D01*
X1349855Y1168869D01*
X1349831Y1168897D01*
G02Y1170871I1131J987D01*
G01X1349855Y1170899D01*
X1349880Y1170966D01*
Y1171302D01*
X1349855Y1171369D01*
X1349831Y1171397D01*
G02Y1173371I1131J987D01*
G01X1349855Y1173399D01*
X1349880Y1173466D01*
G37*
G36*
G01X1368150D02*
Y1173802D01*
X1368125Y1173869D01*
X1368101Y1173897D01*
G02X1367731Y1174884I1131J987D01*
G02X1369233Y1176386I1502J0D01*
G02X1370220Y1176016I0J-1501D01*
G01X1370248Y1175992D01*
X1370315Y1175967D01*
X1370651D01*
X1370718Y1175992D01*
X1370746Y1176016D01*
G02X1371733Y1176386I987J-1131D01*
G02X1373235Y1174884I0J-1502D01*
G02X1372865Y1173897I-1501J0D01*
G01X1372841Y1173869D01*
X1372816Y1173802D01*
Y1173466D01*
X1372841Y1173399D01*
X1372865Y1173371D01*
G02Y1171397I-1131J-987D01*
G01X1372841Y1171369D01*
X1372816Y1171302D01*
Y1170966D01*
X1372841Y1170899D01*
X1372865Y1170871D01*
G02Y1168897I-1131J-987D01*
G01X1372841Y1168869D01*
X1372816Y1168802D01*
Y1168466D01*
X1372841Y1168399D01*
X1372865Y1168371D01*
G02Y1166397I-1131J-987D01*
G01X1372841Y1166369D01*
X1372816Y1166302D01*
Y1165966D01*
X1372841Y1165899D01*
X1372865Y1165871D01*
G02Y1163897I-1131J-987D01*
G01X1372841Y1163869D01*
X1372816Y1163802D01*
Y1163466D01*
X1372841Y1163399D01*
X1372865Y1163371D01*
G02X1373235Y1162384I-1131J-987D01*
G02X1371733Y1160882I-1502J0D01*
G02X1370746Y1161252I0J1501D01*
G01X1370718Y1161276D01*
X1370651Y1161301D01*
X1370315D01*
X1370248Y1161276D01*
X1370220Y1161252D01*
G02X1369233Y1160882I-987J1131D01*
G02X1367731Y1162384I0J1502D01*
G02X1368101Y1163371I1501J0D01*
G01X1368125Y1163399D01*
X1368150Y1163466D01*
Y1163802D01*
X1368125Y1163869D01*
X1368101Y1163897D01*
G02Y1165871I1131J987D01*
G01X1368125Y1165899D01*
X1368150Y1165966D01*
Y1166302D01*
X1368125Y1166369D01*
X1368101Y1166397D01*
G02Y1168371I1131J987D01*
G01X1368125Y1168399D01*
X1368150Y1168466D01*
Y1168802D01*
X1368125Y1168869D01*
X1368101Y1168897D01*
G02Y1170871I1131J987D01*
G01X1368125Y1170899D01*
X1368150Y1170966D01*
Y1171302D01*
X1368125Y1171369D01*
X1368101Y1171397D01*
G02Y1173371I1131J987D01*
G01X1368125Y1173399D01*
X1368150Y1173466D01*
G37*
G36*
G01X1387639D02*
Y1173802D01*
X1387614Y1173869D01*
X1387590Y1173897D01*
G02X1387220Y1174884I1131J987D01*
G02X1388722Y1176386I1502J0D01*
G02X1389709Y1176016I0J-1501D01*
G01X1389737Y1175992D01*
X1389804Y1175967D01*
X1390140D01*
X1390207Y1175992D01*
X1390235Y1176016D01*
G02X1391222Y1176386I987J-1131D01*
G02X1392724Y1174884I0J-1502D01*
G02X1392354Y1173897I-1501J0D01*
G01X1392330Y1173869D01*
X1392305Y1173802D01*
Y1173466D01*
X1392330Y1173399D01*
X1392354Y1173371D01*
G02Y1171397I-1131J-987D01*
G01X1392330Y1171369D01*
X1392305Y1171302D01*
Y1170966D01*
X1392330Y1170899D01*
X1392354Y1170871D01*
G02Y1168897I-1131J-987D01*
G01X1392330Y1168869D01*
X1392305Y1168802D01*
Y1168466D01*
X1392330Y1168399D01*
X1392354Y1168371D01*
G02Y1166397I-1131J-987D01*
G01X1392330Y1166369D01*
X1392305Y1166302D01*
Y1165966D01*
X1392330Y1165899D01*
X1392354Y1165871D01*
G02Y1163897I-1131J-987D01*
G01X1392330Y1163869D01*
X1392305Y1163802D01*
Y1163466D01*
X1392330Y1163399D01*
X1392354Y1163371D01*
G02X1392724Y1162384I-1131J-987D01*
G02X1391222Y1160882I-1502J0D01*
G02X1390235Y1161252I0J1501D01*
G01X1390207Y1161276D01*
X1390140Y1161301D01*
X1389804D01*
X1389737Y1161276D01*
X1389709Y1161252D01*
G02X1388722Y1160882I-987J1131D01*
G02X1387220Y1162384I0J1502D01*
G02X1387590Y1163371I1501J0D01*
G01X1387614Y1163399D01*
X1387639Y1163466D01*
Y1163802D01*
X1387614Y1163869D01*
X1387590Y1163897D01*
G02Y1165871I1131J987D01*
G01X1387614Y1165899D01*
X1387639Y1165966D01*
Y1166302D01*
X1387614Y1166369D01*
X1387590Y1166397D01*
G02Y1168371I1131J987D01*
G01X1387614Y1168399D01*
X1387639Y1168466D01*
Y1168802D01*
X1387614Y1168869D01*
X1387590Y1168897D01*
G02Y1170871I1131J987D01*
G01X1387614Y1170899D01*
X1387639Y1170966D01*
Y1171302D01*
X1387614Y1171369D01*
X1387590Y1171397D01*
G02Y1173371I1131J987D01*
G01X1387614Y1173399D01*
X1387639Y1173466D01*
G37*
G36*
G01X1405909D02*
Y1173802D01*
X1405884Y1173869D01*
X1405860Y1173897D01*
G02X1405490Y1174884I1131J987D01*
G02X1406992Y1176386I1502J0D01*
G02X1407979Y1176016I0J-1501D01*
G01X1408007Y1175992D01*
X1408074Y1175967D01*
X1408410D01*
X1408477Y1175992D01*
X1408505Y1176016D01*
G02X1409492Y1176386I987J-1131D01*
G02X1410994Y1174884I0J-1502D01*
G02X1410624Y1173897I-1501J0D01*
G01X1410600Y1173869D01*
X1410575Y1173802D01*
Y1173466D01*
X1410600Y1173399D01*
X1410624Y1173371D01*
G02Y1171397I-1131J-987D01*
G01X1410600Y1171369D01*
X1410575Y1171302D01*
Y1170966D01*
X1410600Y1170899D01*
X1410624Y1170871D01*
G02Y1168897I-1131J-987D01*
G01X1410600Y1168869D01*
X1410575Y1168802D01*
Y1168466D01*
X1410600Y1168399D01*
X1410624Y1168371D01*
G02Y1166397I-1131J-987D01*
G01X1410600Y1166369D01*
X1410575Y1166302D01*
Y1165966D01*
X1410600Y1165899D01*
X1410624Y1165871D01*
G02Y1163897I-1131J-987D01*
G01X1410600Y1163869D01*
X1410575Y1163802D01*
Y1163466D01*
X1410600Y1163399D01*
X1410624Y1163371D01*
G02X1410994Y1162384I-1131J-987D01*
G02X1409492Y1160882I-1502J0D01*
G02X1408505Y1161252I0J1501D01*
G01X1408477Y1161276D01*
X1408410Y1161301D01*
X1408074D01*
X1408007Y1161276D01*
X1407979Y1161252D01*
G02X1406992Y1160882I-987J1131D01*
G02X1405490Y1162384I0J1502D01*
G02X1405860Y1163371I1501J0D01*
G01X1405884Y1163399D01*
X1405909Y1163466D01*
Y1163802D01*
X1405884Y1163869D01*
X1405860Y1163897D01*
G02Y1165871I1131J987D01*
G01X1405884Y1165899D01*
X1405909Y1165966D01*
Y1166302D01*
X1405884Y1166369D01*
X1405860Y1166397D01*
G02Y1168371I1131J987D01*
G01X1405884Y1168399D01*
X1405909Y1168466D01*
Y1168802D01*
X1405884Y1168869D01*
X1405860Y1168897D01*
G02Y1170871I1131J987D01*
G01X1405884Y1170899D01*
X1405909Y1170966D01*
Y1171302D01*
X1405884Y1171369D01*
X1405860Y1171397D01*
G02Y1173371I1131J987D01*
G01X1405884Y1173399D01*
X1405909Y1173466D01*
G37*
G36*
G01X1415467D02*
Y1173802D01*
X1415442Y1173869D01*
X1415418Y1173897D01*
G02X1415048Y1174884I1131J987D01*
G02X1416550Y1176386I1502J0D01*
G02X1417537Y1176016I0J-1501D01*
G01X1417565Y1175992D01*
X1417632Y1175967D01*
X1417968D01*
X1418035Y1175992D01*
X1418063Y1176016D01*
G02X1419050Y1176386I987J-1131D01*
G02X1420552Y1174884I0J-1502D01*
G02X1420182Y1173897I-1501J0D01*
G01X1420158Y1173869D01*
X1420133Y1173802D01*
Y1173466D01*
X1420158Y1173399D01*
X1420182Y1173371D01*
G02Y1171397I-1131J-987D01*
G01X1420158Y1171369D01*
X1420133Y1171302D01*
Y1170966D01*
X1420158Y1170899D01*
X1420182Y1170871D01*
G02Y1168897I-1131J-987D01*
G01X1420158Y1168869D01*
X1420133Y1168802D01*
Y1168466D01*
X1420158Y1168399D01*
X1420182Y1168371D01*
G02Y1166397I-1131J-987D01*
G01X1420158Y1166369D01*
X1420133Y1166302D01*
Y1165966D01*
X1420158Y1165899D01*
X1420182Y1165871D01*
G02Y1163897I-1131J-987D01*
G01X1420158Y1163869D01*
X1420133Y1163802D01*
Y1163466D01*
X1420158Y1163399D01*
X1420182Y1163371D01*
G02X1420552Y1162384I-1131J-987D01*
G02X1419050Y1160882I-1502J0D01*
G02X1418063Y1161252I0J1501D01*
G01X1418035Y1161276D01*
X1417968Y1161301D01*
X1417632D01*
X1417565Y1161276D01*
X1417537Y1161252D01*
G02X1416550Y1160882I-987J1131D01*
G02X1415048Y1162384I0J1502D01*
G02X1415418Y1163371I1501J0D01*
G01X1415442Y1163399D01*
X1415467Y1163466D01*
Y1163802D01*
X1415442Y1163869D01*
X1415418Y1163897D01*
G02Y1165871I1131J987D01*
G01X1415442Y1165899D01*
X1415467Y1165966D01*
Y1166302D01*
X1415442Y1166369D01*
X1415418Y1166397D01*
G02Y1168371I1131J987D01*
G01X1415442Y1168399D01*
X1415467Y1168466D01*
Y1168802D01*
X1415442Y1168869D01*
X1415418Y1168897D01*
G02Y1170871I1131J987D01*
G01X1415442Y1170899D01*
X1415467Y1170966D01*
Y1171302D01*
X1415442Y1171369D01*
X1415418Y1171397D01*
G02Y1173371I1131J987D01*
G01X1415442Y1173399D01*
X1415467Y1173466D01*
G37*
G36*
G01X1433737D02*
Y1173802D01*
X1433712Y1173869D01*
X1433688Y1173897D01*
G02X1433318Y1174884I1131J987D01*
G02X1434820Y1176386I1502J0D01*
G02X1435807Y1176016I0J-1501D01*
G01X1435835Y1175992D01*
X1435902Y1175967D01*
X1436238D01*
X1436305Y1175992D01*
X1436333Y1176016D01*
G02X1437320Y1176386I987J-1131D01*
G02X1438822Y1174884I0J-1502D01*
G02X1438452Y1173897I-1501J0D01*
G01X1438428Y1173869D01*
X1438403Y1173802D01*
Y1173466D01*
X1438428Y1173399D01*
X1438452Y1173371D01*
G02Y1171397I-1131J-987D01*
G01X1438428Y1171369D01*
X1438403Y1171302D01*
Y1170966D01*
X1438428Y1170899D01*
X1438452Y1170871D01*
G02Y1168897I-1131J-987D01*
G01X1438428Y1168869D01*
X1438403Y1168802D01*
Y1168466D01*
X1438428Y1168399D01*
X1438452Y1168371D01*
G02Y1166397I-1131J-987D01*
G01X1438428Y1166369D01*
X1438403Y1166302D01*
Y1165966D01*
X1438428Y1165899D01*
X1438452Y1165871D01*
G02Y1163897I-1131J-987D01*
G01X1438428Y1163869D01*
X1438403Y1163802D01*
Y1163466D01*
X1438428Y1163399D01*
X1438452Y1163371D01*
G02X1438822Y1162384I-1131J-987D01*
G02X1437320Y1160882I-1502J0D01*
G02X1436333Y1161252I0J1501D01*
G01X1436305Y1161276D01*
X1436238Y1161301D01*
X1435902D01*
X1435835Y1161276D01*
X1435807Y1161252D01*
G02X1434820Y1160882I-987J1131D01*
G02X1433318Y1162384I0J1502D01*
G02X1433688Y1163371I1501J0D01*
G01X1433712Y1163399D01*
X1433737Y1163466D01*
Y1163802D01*
X1433712Y1163869D01*
X1433688Y1163897D01*
G02Y1165871I1131J987D01*
G01X1433712Y1165899D01*
X1433737Y1165966D01*
Y1166302D01*
X1433712Y1166369D01*
X1433688Y1166397D01*
G02Y1168371I1131J987D01*
G01X1433712Y1168399D01*
X1433737Y1168466D01*
Y1168802D01*
X1433712Y1168869D01*
X1433688Y1168897D01*
G02Y1170871I1131J987D01*
G01X1433712Y1170899D01*
X1433737Y1170966D01*
Y1171302D01*
X1433712Y1171369D01*
X1433688Y1171397D01*
G02Y1173371I1131J987D01*
G01X1433712Y1173399D01*
X1433737Y1173466D01*
G37*
G36*
G01X1319410Y1185291D02*
Y1185627D01*
X1319385Y1185694D01*
X1319361Y1185722D01*
G02X1318991Y1186709I1131J987D01*
G02X1321995I1502J0D01*
G02X1321625Y1185722I-1501J0D01*
G01X1321601Y1185694D01*
X1321576Y1185627D01*
Y1185291D01*
X1321601Y1185224D01*
X1321625Y1185196D01*
G02Y1183222I-1131J-987D01*
G01X1321601Y1183194D01*
X1321576Y1183127D01*
Y1182791D01*
X1321601Y1182724D01*
X1321625Y1182696D01*
G02Y1180722I-1131J-987D01*
G01X1321601Y1180694D01*
X1321576Y1180627D01*
Y1180291D01*
X1321601Y1180224D01*
X1321625Y1180196D01*
G02X1321995Y1179209I-1131J-987D01*
G02X1318991I-1502J0D01*
G02X1319361Y1180196I1501J0D01*
G01X1319385Y1180224D01*
X1319410Y1180291D01*
Y1180627D01*
X1319385Y1180694D01*
X1319361Y1180722D01*
G02Y1182696I1131J987D01*
G01X1319385Y1182724D01*
X1319410Y1182791D01*
Y1183127D01*
X1319385Y1183194D01*
X1319361Y1183222D01*
G02Y1185196I1131J987D01*
G01X1319385Y1185224D01*
X1319410Y1185291D01*
G37*
G36*
G01X1346340D02*
Y1185627D01*
X1346315Y1185694D01*
X1346291Y1185722D01*
G02X1345921Y1186709I1131J987D01*
G02X1348925I1502J0D01*
G02X1348555Y1185722I-1501J0D01*
G01X1348531Y1185694D01*
X1348506Y1185627D01*
Y1185291D01*
X1348531Y1185224D01*
X1348555Y1185196D01*
G02Y1183222I-1131J-987D01*
G01X1348531Y1183194D01*
X1348506Y1183127D01*
Y1182791D01*
X1348531Y1182724D01*
X1348555Y1182696D01*
G02Y1180722I-1131J-987D01*
G01X1348531Y1180694D01*
X1348506Y1180627D01*
Y1180291D01*
X1348531Y1180224D01*
X1348555Y1180196D01*
G02X1348925Y1179209I-1131J-987D01*
G02X1345921I-1502J0D01*
G02X1346291Y1180196I1501J0D01*
G01X1346315Y1180224D01*
X1346340Y1180291D01*
Y1180627D01*
X1346315Y1180694D01*
X1346291Y1180722D01*
G02Y1182696I1131J987D01*
G01X1346315Y1182724D01*
X1346340Y1182791D01*
Y1183127D01*
X1346315Y1183194D01*
X1346291Y1183222D01*
G02Y1185196I1131J987D01*
G01X1346315Y1185224D01*
X1346340Y1185291D01*
G37*
G36*
G01X1392612D02*
Y1185627D01*
X1392587Y1185694D01*
X1392563Y1185722D01*
G02X1392193Y1186709I1131J987D01*
G02X1395197I1502J0D01*
G02X1394827Y1185722I-1501J0D01*
G01X1394803Y1185694D01*
X1394778Y1185627D01*
Y1185291D01*
X1394803Y1185224D01*
X1394827Y1185196D01*
G02Y1183222I-1131J-987D01*
G01X1394803Y1183194D01*
X1394778Y1183127D01*
Y1182791D01*
X1394803Y1182724D01*
X1394827Y1182696D01*
G02Y1180722I-1131J-987D01*
G01X1394803Y1180694D01*
X1394778Y1180627D01*
Y1180291D01*
X1394803Y1180224D01*
X1394827Y1180196D01*
G02X1395197Y1179209I-1131J-987D01*
G02X1392193I-1502J0D01*
G02X1392563Y1180196I1501J0D01*
G01X1392587Y1180224D01*
X1392612Y1180291D01*
Y1180627D01*
X1392587Y1180694D01*
X1392563Y1180722D01*
G02Y1182696I1131J987D01*
G01X1392587Y1182724D01*
X1392612Y1182791D01*
Y1183127D01*
X1392587Y1183194D01*
X1392563Y1183222D01*
G02Y1185196I1131J987D01*
G01X1392587Y1185224D01*
X1392612Y1185291D01*
G37*
G36*
G01X1419542D02*
Y1185627D01*
X1419517Y1185694D01*
X1419493Y1185722D01*
G02X1419123Y1186709I1131J987D01*
G02X1422127I1502J0D01*
G02X1421757Y1185722I-1501J0D01*
G01X1421733Y1185694D01*
X1421708Y1185627D01*
Y1185291D01*
X1421733Y1185224D01*
X1421757Y1185196D01*
G02Y1183222I-1131J-987D01*
G01X1421733Y1183194D01*
X1421708Y1183127D01*
Y1182791D01*
X1421733Y1182724D01*
X1421757Y1182696D01*
G02Y1180722I-1131J-987D01*
G01X1421733Y1180694D01*
X1421708Y1180627D01*
Y1180291D01*
X1421733Y1180224D01*
X1421757Y1180196D01*
G02X1422127Y1179209I-1131J-987D01*
G02X1419123I-1502J0D01*
G02X1419493Y1180196I1501J0D01*
G01X1419517Y1180224D01*
X1419542Y1180291D01*
Y1180627D01*
X1419517Y1180694D01*
X1419493Y1180722D01*
G02Y1182696I1131J987D01*
G01X1419517Y1182724D01*
X1419542Y1182791D01*
Y1183127D01*
X1419517Y1183194D01*
X1419493Y1183222D01*
G02Y1185196I1131J987D01*
G01X1419517Y1185224D01*
X1419542Y1185291D01*
G37*
G36*
G01X1333710Y1185503D02*
Y1185839D01*
X1333685Y1185906D01*
X1333661Y1185934D01*
G02X1333291Y1186921I1131J987D01*
G02X1336295I1502J0D01*
G02X1335925Y1185934I-1501J0D01*
G01X1335901Y1185906D01*
X1335876Y1185839D01*
Y1185503D01*
X1335901Y1185436D01*
X1335925Y1185408D01*
G02Y1183434I-1131J-987D01*
G01X1335901Y1183406D01*
X1335876Y1183339D01*
Y1183003D01*
X1335901Y1182936D01*
X1335925Y1182908D01*
G02Y1180934I-1131J-987D01*
G01X1335901Y1180906D01*
X1335876Y1180839D01*
Y1180503D01*
X1335901Y1180436D01*
X1335925Y1180408D01*
G02X1336295Y1179421I-1131J-987D01*
G02X1333291I-1502J0D01*
G02X1333661Y1180408I1501J0D01*
G01X1333685Y1180436D01*
X1333710Y1180503D01*
Y1180839D01*
X1333685Y1180906D01*
X1333661Y1180934D01*
G02Y1182908I1131J987D01*
G01X1333685Y1182936D01*
X1333710Y1183003D01*
Y1183339D01*
X1333685Y1183406D01*
X1333661Y1183434D01*
G02Y1185408I1131J987D01*
G01X1333685Y1185436D01*
X1333710Y1185503D01*
G37*
G36*
G01X1360640D02*
Y1185839D01*
X1360615Y1185906D01*
X1360591Y1185934D01*
G02X1360221Y1186921I1131J987D01*
G02X1363225I1502J0D01*
G02X1362855Y1185934I-1501J0D01*
G01X1362831Y1185906D01*
X1362806Y1185839D01*
Y1185503D01*
X1362831Y1185436D01*
X1362855Y1185408D01*
G02Y1183434I-1131J-987D01*
G01X1362831Y1183406D01*
X1362806Y1183339D01*
Y1183003D01*
X1362831Y1182936D01*
X1362855Y1182908D01*
G02Y1180934I-1131J-987D01*
G01X1362831Y1180906D01*
X1362806Y1180839D01*
Y1180503D01*
X1362831Y1180436D01*
X1362855Y1180408D01*
G02X1363225Y1179421I-1131J-987D01*
G02X1360221I-1502J0D01*
G02X1360591Y1180408I1501J0D01*
G01X1360615Y1180436D01*
X1360640Y1180503D01*
Y1180839D01*
X1360615Y1180906D01*
X1360591Y1180934D01*
G02Y1182908I1131J987D01*
G01X1360615Y1182936D01*
X1360640Y1183003D01*
Y1183339D01*
X1360615Y1183406D01*
X1360591Y1183434D01*
G02Y1185408I1131J987D01*
G01X1360615Y1185436D01*
X1360640Y1185503D01*
G37*
G36*
G01X1406912D02*
Y1185839D01*
X1406887Y1185906D01*
X1406863Y1185934D01*
G02X1406493Y1186921I1131J987D01*
G02X1409497I1502J0D01*
G02X1409127Y1185934I-1501J0D01*
G01X1409103Y1185906D01*
X1409078Y1185839D01*
Y1185503D01*
X1409103Y1185436D01*
X1409127Y1185408D01*
G02Y1183434I-1131J-987D01*
G01X1409103Y1183406D01*
X1409078Y1183339D01*
Y1183003D01*
X1409103Y1182936D01*
X1409127Y1182908D01*
G02Y1180934I-1131J-987D01*
G01X1409103Y1180906D01*
X1409078Y1180839D01*
Y1180503D01*
X1409103Y1180436D01*
X1409127Y1180408D01*
G02X1409497Y1179421I-1131J-987D01*
G02X1406493I-1502J0D01*
G02X1406863Y1180408I1501J0D01*
G01X1406887Y1180436D01*
X1406912Y1180503D01*
Y1180839D01*
X1406887Y1180906D01*
X1406863Y1180934D01*
G02Y1182908I1131J987D01*
G01X1406887Y1182936D01*
X1406912Y1183003D01*
Y1183339D01*
X1406887Y1183406D01*
X1406863Y1183434D01*
G02Y1185408I1131J987D01*
G01X1406887Y1185436D01*
X1406912Y1185503D01*
G37*
G36*
G01X1433842D02*
Y1185839D01*
X1433817Y1185906D01*
X1433793Y1185934D01*
G02X1433423Y1186921I1131J987D01*
G02X1436427I1502J0D01*
G02X1436057Y1185934I-1501J0D01*
G01X1436033Y1185906D01*
X1436008Y1185839D01*
Y1185503D01*
X1436033Y1185436D01*
X1436057Y1185408D01*
G02Y1183434I-1131J-987D01*
G01X1436033Y1183406D01*
X1436008Y1183339D01*
Y1183003D01*
X1436033Y1182936D01*
X1436057Y1182908D01*
G02Y1180934I-1131J-987D01*
G01X1436033Y1180906D01*
X1436008Y1180839D01*
Y1180503D01*
X1436033Y1180436D01*
X1436057Y1180408D01*
G02X1436427Y1179421I-1131J-987D01*
G02X1433423I-1502J0D01*
G02X1433793Y1180408I1501J0D01*
G01X1433817Y1180436D01*
X1433842Y1180503D01*
Y1180839D01*
X1433817Y1180906D01*
X1433793Y1180934D01*
G02Y1182908I1131J987D01*
G01X1433817Y1182936D01*
X1433842Y1183003D01*
Y1183339D01*
X1433817Y1183406D01*
X1433793Y1183434D01*
G02Y1185408I1131J987D01*
G01X1433817Y1185436D01*
X1433842Y1185503D01*
G37*
G36*
G01X1399791Y989176D02*
G02X1399763Y989465I1474J289D01*
G02X1401265Y987963I1502J0D01*
G02X1400835Y988026I0J1502D01*
G03X1400328Y987566I-114J-383D01*
G02X1400356Y987277I-1474J-289D01*
G02X1398854Y988779I-1502J0D01*
G02X1399284Y988716I0J-1502D01*
G03X1399791Y989176I114J383D01*
G37*
G36*
G01X1373181Y1017640D02*
X1373144Y1017669D01*
G02X1372557Y1018860I915J1191D01*
G02X1375561I1502J0D01*
G02X1375554Y1018720I-1502J5D01*
G01X1375550Y1018672D01*
X1375585Y1018584D01*
X1375899Y1018306D01*
X1375991Y1018282D01*
X1376038Y1018292D01*
G02X1376359Y1018327I322J-1467D01*
G02Y1015323I0J-1502D01*
G02X1375884Y1015400I0J1502D01*
G01X1375849Y1015412D01*
X1375776Y1015409D01*
X1375463Y1015274D01*
X1375411Y1015223D01*
X1375395Y1015190D01*
G02X1374034Y1014323I-1361J635D01*
G02X1372532Y1015825I0J1502D01*
G02X1373138Y1017031I1503J0D01*
G01X1373177Y1017059D01*
X1373219Y1017142D01*
X1373222Y1017556D01*
X1373181Y1017640D01*
G37*
G36*
G01X1348932Y1093314D02*
X1348941Y1093363D01*
G02X1350418Y1094590I1477J-275D01*
G02X1351920Y1093088I0J-1502D01*
G02X1351435Y1091982I-1502J-1D01*
G03X1351370Y1091835I135J-148D01*
G01Y1091541D01*
G03X1351435Y1091394I200J1D01*
G02X1351920Y1090288I-1017J-1105D01*
G02X1350418Y1088786I-1502J0D01*
G02X1349579Y1089042I0J1503D01*
G01X1349540Y1089069D01*
X1349447Y1089081D01*
X1349057Y1088949D01*
X1348991Y1088883D01*
X1348976Y1088838D01*
G02X1348684Y1088329I-1424J478D01*
G01X1348660Y1088301D01*
X1348635Y1088234D01*
Y1087898D01*
X1348660Y1087831D01*
X1348684Y1087803D01*
G02Y1085829I-1131J-987D01*
G01X1348660Y1085801D01*
X1348635Y1085734D01*
Y1085398D01*
X1348660Y1085331D01*
X1348684Y1085303D01*
G02Y1083329I-1131J-987D01*
G01X1348660Y1083301D01*
X1348635Y1083234D01*
Y1082898D01*
X1348660Y1082831D01*
X1348684Y1082803D01*
G02X1349054Y1081816I-1131J-987D01*
G02X1347552Y1080314I-1502J0D01*
G02X1346565Y1080684I0J1501D01*
G01X1346537Y1080708D01*
X1346470Y1080733D01*
X1346134D01*
X1346067Y1080708D01*
X1346039Y1080684D01*
G02X1345052Y1080314I-987J1131D01*
G02X1343550Y1081816I0J1502D01*
G02X1343920Y1082803I1501J0D01*
G01X1343944Y1082831D01*
X1343969Y1082898D01*
Y1083234D01*
X1343944Y1083301D01*
X1343920Y1083329D01*
G02Y1085303I1131J987D01*
G01X1343944Y1085331D01*
X1343969Y1085398D01*
Y1085734D01*
X1343944Y1085801D01*
X1343920Y1085829D01*
G02X1343550Y1086816I1131J987D01*
G02X1345052Y1088318I1502J0D01*
G02X1346100Y1087892I0J-1502D01*
G03X1346239Y1087835I140J143D01*
G01X1346365D01*
G03X1346504Y1087892I-1J200D01*
G02X1346533Y1087919I1038J-1086D01*
G01Y1088129D01*
G03X1346476Y1088268I-200J-1D01*
G02X1346050Y1089316I1076J1048D01*
G02X1346420Y1090303I1501J0D01*
G01X1346444Y1090331D01*
X1346469Y1090398D01*
Y1090734D01*
X1346444Y1090801D01*
X1346420Y1090829D01*
G02X1346050Y1091816I1131J987D01*
G02X1347552Y1093318I1502J0D01*
G02X1348339Y1093096I1J-1502D01*
G01X1348382Y1093069D01*
X1348479Y1093063D01*
X1348872Y1093237D01*
X1348932Y1093314D01*
G37*
G36*
G01X1322098Y1092771D02*
G02X1321519Y1093956I923J1185D01*
G02X1324523I1502J0D01*
G02X1323944Y1092771I-1502J0D01*
G03X1323867Y1092614I123J-158D01*
G01Y1092298D01*
G03X1323944Y1092141I200J1D01*
G02X1324523Y1090956I-923J-1185D01*
G02X1323863Y1089712I-1502J0D01*
G01X1323820Y1089683D01*
X1323773Y1089589D01*
X1323796Y1089142D01*
X1323852Y1089054D01*
X1323899Y1089029D01*
G02X1324225Y1088792I-712J-1322D01*
G01X1324260Y1088759D01*
X1324349Y1088732D01*
X1324759Y1088800D01*
X1324834Y1088855D01*
X1324856Y1088897D01*
G02X1325399Y1089482I1333J-692D01*
G01X1325439Y1089507D01*
X1325488Y1089587D01*
X1325527Y1089999D01*
X1325493Y1090086D01*
X1325458Y1090118D01*
G02X1324969Y1091227I1013J1109D01*
G02X1327973I1502J0D01*
G02X1327261Y1089950I-1501J0D01*
G01X1327221Y1089925D01*
X1327172Y1089845D01*
X1327133Y1089433D01*
X1327167Y1089346D01*
X1327202Y1089314D01*
G02X1327374Y1089128I-1013J-1109D01*
G03X1327531Y1089051I158J123D01*
G01X1327847D01*
G03X1328004Y1089128I-1J200D01*
G02X1329189Y1089707I1185J-923D01*
G02X1330691Y1088205I0J-1502D01*
G02X1330112Y1087020I-1502J0D01*
G03X1330035Y1086863I123J-158D01*
G01Y1086547D01*
G03X1330112Y1086390I200J1D01*
G02X1330691Y1085205I-923J-1185D01*
G02X1330235Y1084127I-1502J0D01*
G01X1330206Y1084099D01*
X1330175Y1084026D01*
X1330171Y1083661D01*
X1330201Y1083587D01*
X1330230Y1083559D01*
G02X1330665Y1082501I-1067J-1057D01*
G02X1329163Y1080999I-1502J0D01*
G02X1327978Y1081578I0J1502D01*
G03X1327821Y1081655I-158J-123D01*
G01X1327505D01*
G03X1327348Y1081578I1J-200D01*
G02X1324978I-1185J923D01*
G03X1324821Y1081655I-158J-123D01*
G01X1324505D01*
G03X1324348Y1081578I1J-200D01*
G02X1323163Y1080999I-1185J923D01*
G02X1321661Y1082501I0J1502D01*
G02X1322117Y1083579I1502J0D01*
G01X1322146Y1083607D01*
X1322177Y1083680D01*
X1322181Y1084045D01*
X1322151Y1084119D01*
X1322122Y1084147D01*
G02X1321687Y1085205I1067J1057D01*
G02X1322057Y1086192I1501J0D01*
G01X1322081Y1086220D01*
X1322106Y1086287D01*
Y1086623D01*
X1322081Y1086690D01*
X1322057Y1086718D01*
G02X1321687Y1087705I1131J987D01*
G02X1322347Y1088949I1502J0D01*
G01X1322390Y1088978D01*
X1322437Y1089072D01*
X1322414Y1089519D01*
X1322358Y1089607D01*
X1322311Y1089632D01*
G02X1321519Y1090956I711J1324D01*
G02X1322098Y1092141I1502J0D01*
G03X1322175Y1092298I-123J158D01*
G01Y1092614D01*
G03X1322098Y1092771I-200J-1D01*
G37*
G36*
G01X1337778Y1106328D02*
X1337762Y1106372D01*
G02X1337667Y1106897I1407J526D01*
G02X1340671I1502J0D01*
G02X1339269Y1105398I-1502J0D01*
G01X1339222Y1105395D01*
X1339141Y1105347D01*
X1338915Y1104998D01*
X1338905Y1104904D01*
X1338921Y1104860D01*
G02X1339016Y1104335I-1407J-526D01*
G02X1338959Y1103925I-1503J0D01*
G01X1338946Y1103881D01*
X1338962Y1103792D01*
X1339196Y1103463D01*
X1339275Y1103419D01*
X1339321Y1103416D01*
G02X1340736Y1101917I-86J-1499D01*
G02X1337732I-1502J0D01*
G02X1337789Y1102327I1503J0D01*
G01X1337802Y1102371D01*
X1337786Y1102460D01*
X1337552Y1102789D01*
X1337473Y1102833D01*
X1337427Y1102836D01*
G02X1336073Y1103910I86J1499D01*
G01X1336061Y1103952D01*
X1336006Y1104016D01*
X1335659Y1104181D01*
X1335575Y1104183D01*
X1335535Y1104166D01*
G02X1334956Y1104050I-579J1387D01*
G02X1333514Y1105133I0J1502D01*
G01X1333503Y1105171D01*
X1333456Y1105231D01*
X1333146Y1105409D01*
X1333071Y1105419D01*
X1333033Y1105410D01*
G02X1332972Y1105396I-366J1457D01*
G01X1332935Y1105388D01*
X1332872Y1105348D01*
X1332669Y1105069D01*
X1332650Y1104997D01*
X1332655Y1104959D01*
G02X1332664Y1104792I-1493J-164D01*
G02X1329660I-1502J0D01*
G02X1330859Y1106263I1502J0D01*
G01X1330896Y1106271D01*
X1330959Y1106311D01*
X1331162Y1106590D01*
X1331181Y1106662D01*
X1331176Y1106700D01*
G02X1331167Y1106867I1493J164D01*
G02X1332669Y1108369I1502J0D01*
G02X1334111Y1107286I0J-1502D01*
G01X1334122Y1107248D01*
X1334169Y1107188D01*
X1334479Y1107010D01*
X1334554Y1107000D01*
X1334592Y1107009D01*
G02X1334956Y1107054I365J-1457D01*
G02X1336397Y1105977I0J-1503D01*
G01X1336409Y1105935D01*
X1336464Y1105871D01*
X1336811Y1105706D01*
X1336895Y1105704D01*
X1336935Y1105721D01*
G02X1337414Y1105834I580J-1386D01*
G01X1337461Y1105837D01*
X1337542Y1105885D01*
X1337768Y1106234D01*
X1337778Y1106328D01*
G37*
G36*
G01X1369906D02*
X1369890Y1106372D01*
G02X1369795Y1106897I1407J526D01*
G02X1372799I1502J0D01*
G02X1371397Y1105398I-1502J0D01*
G01X1371350Y1105395D01*
X1371269Y1105347D01*
X1371043Y1104998D01*
X1371033Y1104904D01*
X1371049Y1104860D01*
G02X1371144Y1104335I-1407J-526D01*
G02X1371087Y1103925I-1503J0D01*
G01X1371074Y1103881D01*
X1371090Y1103792D01*
X1371324Y1103463D01*
X1371403Y1103419D01*
X1371449Y1103416D01*
G02X1372864Y1101917I-86J-1499D01*
G02X1369860I-1502J0D01*
G02X1369917Y1102327I1503J0D01*
G01X1369930Y1102371D01*
X1369914Y1102460D01*
X1369680Y1102789D01*
X1369601Y1102833D01*
X1369555Y1102836D01*
G02X1368201Y1103910I86J1499D01*
G01X1368189Y1103952D01*
X1368134Y1104016D01*
X1367787Y1104181D01*
X1367703Y1104183D01*
X1367663Y1104166D01*
G02X1367084Y1104050I-579J1387D01*
G02X1365642Y1105133I0J1502D01*
G01X1365631Y1105171D01*
X1365584Y1105231D01*
X1365274Y1105409D01*
X1365199Y1105419D01*
X1365161Y1105410D01*
G02X1365100Y1105396I-366J1457D01*
G01X1365063Y1105388D01*
X1365000Y1105348D01*
X1364797Y1105069D01*
X1364778Y1104997D01*
X1364783Y1104959D01*
G02X1364792Y1104792I-1493J-164D01*
G02X1361788I-1502J0D01*
G02X1362987Y1106263I1502J0D01*
G01X1363024Y1106271D01*
X1363087Y1106311D01*
X1363290Y1106590D01*
X1363309Y1106662D01*
X1363304Y1106700D01*
G02X1363295Y1106867I1493J164D01*
G02X1364797Y1108369I1502J0D01*
G02X1366239Y1107286I0J-1502D01*
G01X1366250Y1107248D01*
X1366297Y1107188D01*
X1366607Y1107010D01*
X1366682Y1107000D01*
X1366720Y1107009D01*
G02X1367084Y1107054I365J-1457D01*
G02X1368525Y1105977I0J-1503D01*
G01X1368537Y1105935D01*
X1368592Y1105871D01*
X1368939Y1105706D01*
X1369023Y1105704D01*
X1369063Y1105721D01*
G02X1369542Y1105834I580J-1386D01*
G01X1369589Y1105837D01*
X1369670Y1105885D01*
X1369896Y1106234D01*
X1369906Y1106328D01*
G37*
G36*
G01X1403365D02*
X1403349Y1106372D01*
G02X1403254Y1106897I1407J526D01*
G02X1406258I1502J0D01*
G02X1404856Y1105398I-1502J0D01*
G01X1404809Y1105395D01*
X1404728Y1105347D01*
X1404502Y1104998D01*
X1404492Y1104904D01*
X1404508Y1104860D01*
G02X1404603Y1104335I-1407J-526D01*
G02X1404546Y1103925I-1503J0D01*
G01X1404533Y1103881D01*
X1404549Y1103792D01*
X1404783Y1103463D01*
X1404862Y1103419D01*
X1404908Y1103416D01*
G02X1406323Y1101917I-86J-1499D01*
G02X1403319I-1502J0D01*
G02X1403376Y1102327I1503J0D01*
G01X1403389Y1102371D01*
X1403373Y1102460D01*
X1403139Y1102789D01*
X1403060Y1102833D01*
X1403014Y1102836D01*
G02X1401660Y1103910I86J1499D01*
G01X1401648Y1103952D01*
X1401593Y1104016D01*
X1401246Y1104181D01*
X1401162Y1104183D01*
X1401122Y1104166D01*
G02X1400543Y1104050I-579J1387D01*
G02X1399101Y1105133I0J1502D01*
G01X1399090Y1105171D01*
X1399043Y1105231D01*
X1398733Y1105409D01*
X1398658Y1105419D01*
X1398620Y1105410D01*
G02X1398559Y1105396I-366J1457D01*
G01X1398522Y1105388D01*
X1398459Y1105348D01*
X1398256Y1105069D01*
X1398237Y1104997D01*
X1398242Y1104959D01*
G02X1398251Y1104792I-1493J-164D01*
G02X1395247I-1502J0D01*
G02X1396446Y1106263I1502J0D01*
G01X1396483Y1106271D01*
X1396546Y1106311D01*
X1396749Y1106590D01*
X1396768Y1106662D01*
X1396763Y1106700D01*
G02X1396754Y1106867I1493J164D01*
G02X1398256Y1108369I1502J0D01*
G02X1399698Y1107286I0J-1502D01*
G01X1399709Y1107248D01*
X1399756Y1107188D01*
X1400066Y1107010D01*
X1400141Y1107000D01*
X1400179Y1107009D01*
G02X1400543Y1107054I365J-1457D01*
G02X1401984Y1105977I0J-1503D01*
G01X1401996Y1105935D01*
X1402051Y1105871D01*
X1402398Y1105706D01*
X1402482Y1105704D01*
X1402522Y1105721D01*
G02X1403001Y1105834I580J-1386D01*
G01X1403048Y1105837D01*
X1403129Y1105885D01*
X1403355Y1106234D01*
X1403365Y1106328D01*
G37*
G36*
G01X1435493D02*
X1435477Y1106372D01*
G02X1435382Y1106897I1407J526D01*
G02X1438386I1502J0D01*
G02X1436984Y1105398I-1502J0D01*
G01X1436937Y1105395D01*
X1436856Y1105347D01*
X1436630Y1104998D01*
X1436620Y1104904D01*
X1436636Y1104860D01*
G02X1436731Y1104335I-1407J-526D01*
G02X1436674Y1103925I-1503J0D01*
G01X1436661Y1103881D01*
X1436677Y1103792D01*
X1436911Y1103463D01*
X1436990Y1103419D01*
X1437036Y1103416D01*
G02X1438451Y1101917I-86J-1499D01*
G02X1435447I-1502J0D01*
G02X1435504Y1102327I1503J0D01*
G01X1435517Y1102371D01*
X1435501Y1102460D01*
X1435267Y1102789D01*
X1435188Y1102833D01*
X1435142Y1102836D01*
G02X1433788Y1103910I86J1499D01*
G01X1433776Y1103952D01*
X1433721Y1104016D01*
X1433374Y1104181D01*
X1433290Y1104183D01*
X1433250Y1104166D01*
G02X1432671Y1104050I-579J1387D01*
G02X1431229Y1105133I0J1502D01*
G01X1431218Y1105171D01*
X1431171Y1105231D01*
X1430861Y1105409D01*
X1430786Y1105419D01*
X1430748Y1105410D01*
G02X1430687Y1105396I-366J1457D01*
G01X1430650Y1105388D01*
X1430587Y1105348D01*
X1430384Y1105069D01*
X1430365Y1104997D01*
X1430370Y1104959D01*
G02X1430379Y1104792I-1493J-164D01*
G02X1427375I-1502J0D01*
G02X1428574Y1106263I1502J0D01*
G01X1428611Y1106271D01*
X1428674Y1106311D01*
X1428877Y1106590D01*
X1428896Y1106662D01*
X1428891Y1106700D01*
G02X1428882Y1106867I1493J164D01*
G02X1430384Y1108369I1502J0D01*
G02X1431826Y1107286I0J-1502D01*
G01X1431837Y1107248D01*
X1431884Y1107188D01*
X1432194Y1107010D01*
X1432269Y1107000D01*
X1432307Y1107009D01*
G02X1432671Y1107054I365J-1457D01*
G02X1434112Y1105977I0J-1503D01*
G01X1434124Y1105935D01*
X1434179Y1105871D01*
X1434526Y1105706D01*
X1434610Y1105704D01*
X1434650Y1105721D01*
G02X1435129Y1105834I580J-1386D01*
G01X1435176Y1105837D01*
X1435257Y1105885D01*
X1435483Y1106234D01*
X1435493Y1106328D01*
G37*
G36*
G01X1322376Y1117707D02*
X1322347Y1117735D01*
G02X1321903Y1118801I1058J1066D01*
G02X1324907I1502J0D01*
G02X1324463Y1117735I-1502J0D01*
G01X1324434Y1117707D01*
X1324404Y1117633D01*
Y1117269D01*
X1324434Y1117195D01*
X1324463Y1117167D01*
G02X1324907Y1116101I-1058J-1066D01*
G02X1323688Y1114626I-1502J0D01*
G01X1323646Y1114618D01*
X1323576Y1114569D01*
X1323379Y1114236D01*
X1323370Y1114151D01*
X1323383Y1114110D01*
G02X1323456Y1113648I-1429J-463D01*
G02X1322459Y1112234I-1501J0D01*
G01X1322412Y1112217D01*
X1322345Y1112144D01*
X1322238Y1111726D01*
X1322261Y1111630D01*
X1322294Y1111592D01*
G02X1322671Y1110597I-1125J-995D01*
G02X1322224Y1109528I-1502J0D01*
G01X1322197Y1109501D01*
X1322167Y1109433D01*
X1322153Y1109081D01*
X1322178Y1109011D01*
X1322203Y1108982D01*
G02X1322571Y1107997I-1134J-985D01*
G02X1321069Y1106495I-1502J0D01*
G02X1319616Y1107615I0J1503D01*
G01X1319607Y1107650D01*
X1319565Y1107710D01*
X1319282Y1107898D01*
X1319211Y1107914D01*
X1319175Y1107909D01*
G02X1318969Y1107895I-205J1488D01*
G02X1318763Y1107909I-1J1502D01*
G01X1318727Y1107914D01*
X1318656Y1107898D01*
X1318373Y1107710D01*
X1318331Y1107650D01*
X1318322Y1107615D01*
G02X1316869Y1106495I-1453J383D01*
G02X1315367Y1107997I0J1502D01*
G02X1315897Y1109142I1502J0D01*
G03X1315968Y1109295I-129J153D01*
G01Y1109599D01*
G03X1315897Y1109752I-200J0D01*
G02Y1112042I972J1145D01*
G03X1315968Y1112195I-129J153D01*
G01Y1112499D01*
G03X1315897Y1112652I-200J0D01*
G02X1315367Y1113797I972J1145D01*
G02X1316869Y1115299I1502J0D01*
G02X1318325Y1114167I0J-1502D01*
G01X1318334Y1114130D01*
X1318379Y1114068D01*
X1318675Y1113880D01*
X1318750Y1113865D01*
X1318787Y1113872D01*
G02X1319069Y1113899I284J-1475D01*
G02X1319872Y1113666I0J-1502D01*
G01X1319914Y1113640D01*
X1320013Y1113632D01*
X1320407Y1113803D01*
X1320469Y1113881D01*
X1320479Y1113929D01*
G02X1321671Y1115123I1475J-281D01*
G01X1321713Y1115131D01*
X1321783Y1115180D01*
X1321980Y1115513D01*
X1321989Y1115598D01*
X1321976Y1115639D01*
G02X1321903Y1116101I1429J463D01*
G02X1322347Y1117167I1502J0D01*
G01X1322376Y1117195D01*
X1322406Y1117269D01*
Y1117633D01*
X1322376Y1117707D01*
G37*
G36*
G01X1354504D02*
X1354475Y1117735D01*
G02X1354031Y1118801I1058J1066D01*
G02X1357035I1502J0D01*
G02X1356591Y1117735I-1502J0D01*
G01X1356562Y1117707D01*
X1356532Y1117633D01*
Y1117269D01*
X1356562Y1117195D01*
X1356591Y1117167D01*
G02X1357035Y1116101I-1058J-1066D01*
G02X1355816Y1114626I-1502J0D01*
G01X1355774Y1114618D01*
X1355704Y1114569D01*
X1355507Y1114236D01*
X1355498Y1114151D01*
X1355511Y1114110D01*
G02X1355584Y1113648I-1429J-463D01*
G02X1354587Y1112234I-1501J0D01*
G01X1354540Y1112217D01*
X1354473Y1112144D01*
X1354366Y1111726D01*
X1354389Y1111630D01*
X1354422Y1111592D01*
G02X1354799Y1110597I-1125J-995D01*
G02X1354352Y1109528I-1502J0D01*
G01X1354325Y1109501D01*
X1354295Y1109433D01*
X1354281Y1109081D01*
X1354306Y1109011D01*
X1354331Y1108982D01*
G02X1354699Y1107997I-1134J-985D01*
G02X1353197Y1106495I-1502J0D01*
G02X1351744Y1107615I0J1503D01*
G01X1351735Y1107650D01*
X1351693Y1107710D01*
X1351410Y1107898D01*
X1351339Y1107914D01*
X1351303Y1107909D01*
G02X1351097Y1107895I-205J1488D01*
G02X1350891Y1107909I-1J1502D01*
G01X1350855Y1107914D01*
X1350784Y1107898D01*
X1350501Y1107710D01*
X1350459Y1107650D01*
X1350450Y1107615D01*
G02X1348997Y1106495I-1453J383D01*
G02X1347495Y1107997I0J1502D01*
G02X1348025Y1109142I1502J0D01*
G03X1348096Y1109295I-129J153D01*
G01Y1109599D01*
G03X1348025Y1109752I-200J0D01*
G02Y1112042I972J1145D01*
G03X1348096Y1112195I-129J153D01*
G01Y1112499D01*
G03X1348025Y1112652I-200J0D01*
G02X1347495Y1113797I972J1145D01*
G02X1348997Y1115299I1502J0D01*
G02X1350453Y1114167I0J-1502D01*
G01X1350462Y1114130D01*
X1350507Y1114068D01*
X1350803Y1113880D01*
X1350878Y1113865D01*
X1350915Y1113872D01*
G02X1351197Y1113899I284J-1475D01*
G02X1352000Y1113666I0J-1502D01*
G01X1352042Y1113640D01*
X1352141Y1113632D01*
X1352535Y1113803D01*
X1352597Y1113881D01*
X1352607Y1113929D01*
G02X1353799Y1115123I1475J-281D01*
G01X1353841Y1115131D01*
X1353911Y1115180D01*
X1354108Y1115513D01*
X1354117Y1115598D01*
X1354104Y1115639D01*
G02X1354031Y1116101I1429J463D01*
G02X1354475Y1117167I1502J0D01*
G01X1354504Y1117195D01*
X1354534Y1117269D01*
Y1117633D01*
X1354504Y1117707D01*
G37*
G36*
G01X1387963D02*
X1387934Y1117735D01*
G02X1387490Y1118801I1058J1066D01*
G02X1390494I1502J0D01*
G02X1390050Y1117735I-1502J0D01*
G01X1390021Y1117707D01*
X1389991Y1117633D01*
Y1117269D01*
X1390021Y1117195D01*
X1390050Y1117167D01*
G02X1390494Y1116101I-1058J-1066D01*
G02X1389275Y1114626I-1502J0D01*
G01X1389233Y1114618D01*
X1389163Y1114569D01*
X1388966Y1114236D01*
X1388957Y1114151D01*
X1388970Y1114110D01*
G02X1389043Y1113648I-1429J-463D01*
G02X1388046Y1112234I-1501J0D01*
G01X1387999Y1112217D01*
X1387932Y1112144D01*
X1387825Y1111726D01*
X1387848Y1111630D01*
X1387881Y1111592D01*
G02X1388258Y1110597I-1125J-995D01*
G02X1387811Y1109528I-1502J0D01*
G01X1387784Y1109501D01*
X1387754Y1109433D01*
X1387740Y1109081D01*
X1387765Y1109011D01*
X1387790Y1108982D01*
G02X1388158Y1107997I-1134J-985D01*
G02X1386656Y1106495I-1502J0D01*
G02X1385203Y1107615I0J1503D01*
G01X1385194Y1107650D01*
X1385152Y1107710D01*
X1384869Y1107898D01*
X1384798Y1107914D01*
X1384762Y1107909D01*
G02X1384556Y1107895I-205J1488D01*
G02X1384350Y1107909I-1J1502D01*
G01X1384314Y1107914D01*
X1384243Y1107898D01*
X1383960Y1107710D01*
X1383918Y1107650D01*
X1383909Y1107615D01*
G02X1382456Y1106495I-1453J383D01*
G02X1380954Y1107997I0J1502D01*
G02X1381484Y1109142I1502J0D01*
G03X1381555Y1109295I-129J153D01*
G01Y1109599D01*
G03X1381484Y1109752I-200J0D01*
G02Y1112042I972J1145D01*
G03X1381555Y1112195I-129J153D01*
G01Y1112499D01*
G03X1381484Y1112652I-200J0D01*
G02X1380954Y1113797I972J1145D01*
G02X1382456Y1115299I1502J0D01*
G02X1383912Y1114167I0J-1502D01*
G01X1383921Y1114130D01*
X1383966Y1114068D01*
X1384262Y1113880D01*
X1384337Y1113865D01*
X1384374Y1113872D01*
G02X1384656Y1113899I284J-1475D01*
G02X1385459Y1113666I0J-1502D01*
G01X1385501Y1113640D01*
X1385600Y1113632D01*
X1385994Y1113803D01*
X1386056Y1113881D01*
X1386066Y1113929D01*
G02X1387258Y1115123I1475J-281D01*
G01X1387300Y1115131D01*
X1387370Y1115180D01*
X1387567Y1115513D01*
X1387576Y1115598D01*
X1387563Y1115639D01*
G02X1387490Y1116101I1429J463D01*
G02X1387934Y1117167I1502J0D01*
G01X1387963Y1117195D01*
X1387993Y1117269D01*
Y1117633D01*
X1387963Y1117707D01*
G37*
G36*
G01X1420091D02*
X1420062Y1117735D01*
G02X1419618Y1118801I1058J1066D01*
G02X1422622I1502J0D01*
G02X1422178Y1117735I-1502J0D01*
G01X1422149Y1117707D01*
X1422119Y1117633D01*
Y1117269D01*
X1422149Y1117195D01*
X1422178Y1117167D01*
G02X1422622Y1116101I-1058J-1066D01*
G02X1421403Y1114626I-1502J0D01*
G01X1421361Y1114618D01*
X1421291Y1114569D01*
X1421094Y1114236D01*
X1421085Y1114151D01*
X1421098Y1114110D01*
G02X1421171Y1113648I-1429J-463D01*
G02X1420174Y1112234I-1501J0D01*
G01X1420127Y1112217D01*
X1420060Y1112144D01*
X1419953Y1111726D01*
X1419976Y1111630D01*
X1420009Y1111592D01*
G02X1420386Y1110597I-1125J-995D01*
G02X1419939Y1109528I-1502J0D01*
G01X1419912Y1109501D01*
X1419882Y1109433D01*
X1419868Y1109081D01*
X1419893Y1109011D01*
X1419918Y1108982D01*
G02X1420286Y1107997I-1134J-985D01*
G02X1418784Y1106495I-1502J0D01*
G02X1417331Y1107615I0J1503D01*
G01X1417322Y1107650D01*
X1417280Y1107710D01*
X1416997Y1107898D01*
X1416926Y1107914D01*
X1416890Y1107909D01*
G02X1416684Y1107895I-205J1488D01*
G02X1416478Y1107909I-1J1502D01*
G01X1416442Y1107914D01*
X1416371Y1107898D01*
X1416088Y1107710D01*
X1416046Y1107650D01*
X1416037Y1107615D01*
G02X1414584Y1106495I-1453J383D01*
G02X1413082Y1107997I0J1502D01*
G02X1413612Y1109142I1502J0D01*
G03X1413683Y1109295I-129J153D01*
G01Y1109599D01*
G03X1413612Y1109752I-200J0D01*
G02Y1112042I972J1145D01*
G03X1413683Y1112195I-129J153D01*
G01Y1112499D01*
G03X1413612Y1112652I-200J0D01*
G02X1413082Y1113797I972J1145D01*
G02X1414584Y1115299I1502J0D01*
G02X1416040Y1114167I0J-1502D01*
G01X1416049Y1114130D01*
X1416094Y1114068D01*
X1416390Y1113880D01*
X1416465Y1113865D01*
X1416502Y1113872D01*
G02X1416784Y1113899I284J-1475D01*
G02X1417587Y1113666I0J-1502D01*
G01X1417629Y1113640D01*
X1417728Y1113632D01*
X1418122Y1113803D01*
X1418184Y1113881D01*
X1418194Y1113929D01*
G02X1419386Y1115123I1475J-281D01*
G01X1419428Y1115131D01*
X1419498Y1115180D01*
X1419695Y1115513D01*
X1419704Y1115598D01*
X1419691Y1115639D01*
G02X1419618Y1116101I1429J463D01*
G02X1420062Y1117167I1502J0D01*
G01X1420091Y1117195D01*
X1420121Y1117269D01*
Y1117633D01*
X1420091Y1117707D01*
G37*
G36*
G01X1373646Y1197781D02*
X1374397Y1198533D01*
G02X1375459Y1198972I1061J-1062D01*
G02X1376960Y1197471I0J-1501D01*
G02X1376521Y1196409I-1501J-1D01*
G01X1375724Y1195612D01*
G03Y1195330I141J-141D01*
G01X1376521Y1194533D01*
G02X1376960Y1193471I-1062J-1061D01*
G02X1375459Y1191970I-1501J0D01*
G02X1374397Y1192409I-1J1501D01*
G01X1373646Y1193161D01*
G03X1373504Y1193220I-142J-141D01*
G01X1365930D01*
G03X1365781Y1193153I0J-200D01*
G01X1365553Y1192901D01*
X1365527Y1192821D01*
X1365532Y1192778D01*
G02X1365540Y1192621I-1494J-155D01*
G02X1365170Y1191634I-1501J0D01*
G01X1365146Y1191606D01*
X1365121Y1191539D01*
Y1191203D01*
X1365146Y1191136D01*
X1365170Y1191108D01*
G02X1365540Y1190121I-1131J-987D01*
G02X1362536I-1502J0D01*
G02X1362906Y1191108I1501J0D01*
G01X1362930Y1191136D01*
X1362955Y1191203D01*
Y1191539D01*
X1362930Y1191606D01*
X1362906Y1191634D01*
G02X1362536Y1192621I1131J987D01*
G02X1362544Y1192778I1502J2D01*
G01X1362549Y1192821D01*
X1362523Y1192901D01*
X1362295Y1193153D01*
G03X1362146Y1193220I-149J-133D01*
G01X1347000D01*
G03X1346851Y1193153I0J-200D01*
G01X1346623Y1192901D01*
X1346597Y1192821D01*
X1346602Y1192778D01*
G02X1346610Y1192621I-1494J-155D01*
G02X1346240Y1191634I-1501J0D01*
G01X1346216Y1191606D01*
X1346191Y1191539D01*
Y1191203D01*
X1346216Y1191136D01*
X1346240Y1191108D01*
G02X1346610Y1190121I-1131J-987D01*
G02X1343606I-1502J0D01*
G02X1343976Y1191108I1501J0D01*
G01X1344000Y1191136D01*
X1344025Y1191203D01*
Y1191539D01*
X1344000Y1191606D01*
X1343976Y1191634D01*
G02X1343606Y1192621I1131J987D01*
G02X1343614Y1192778I1502J2D01*
G01X1343619Y1192821D01*
X1343593Y1192901D01*
X1343365Y1193153D01*
G03X1343216Y1193220I-149J-133D01*
G01X1339000D01*
G03X1338851Y1193153I0J-200D01*
G01X1338623Y1192901D01*
X1338597Y1192821D01*
X1338602Y1192778D01*
G02X1338610Y1192621I-1494J-155D01*
G02X1338240Y1191634I-1501J0D01*
G01X1338216Y1191606D01*
X1338191Y1191539D01*
Y1191203D01*
X1338216Y1191136D01*
X1338240Y1191108D01*
G02X1338610Y1190121I-1131J-987D01*
G02X1335606I-1502J0D01*
G02X1335976Y1191108I1501J0D01*
G01X1336000Y1191136D01*
X1336025Y1191203D01*
Y1191539D01*
X1336000Y1191606D01*
X1335976Y1191634D01*
G02X1335606Y1192621I1131J987D01*
G02X1335614Y1192778I1502J2D01*
G01X1335619Y1192821D01*
X1335593Y1192901D01*
X1335365Y1193153D01*
G03X1335216Y1193220I-149J-133D01*
G01X1333535D01*
G03X1333386Y1193153I0J-200D01*
G01X1333158Y1192901D01*
X1333132Y1192821D01*
X1333137Y1192778D01*
G02X1333145Y1192621I-1494J-155D01*
G02X1332775Y1191634I-1501J0D01*
G01X1332751Y1191606D01*
X1332726Y1191539D01*
Y1191203D01*
X1332751Y1191136D01*
X1332775Y1191108D01*
G02X1333145Y1190121I-1131J-987D01*
G02X1330141I-1502J0D01*
G02X1330511Y1191108I1501J0D01*
G01X1330535Y1191136D01*
X1330560Y1191203D01*
Y1191539D01*
X1330535Y1191606D01*
X1330511Y1191634D01*
G02X1330141Y1192621I1131J987D01*
G02X1330149Y1192778I1502J2D01*
G01X1330154Y1192821D01*
X1330128Y1192901D01*
X1329900Y1193153D01*
G03X1329751Y1193220I-149J-133D01*
G01X1320070D01*
G03X1319921Y1193153I0J-200D01*
G01X1319693Y1192901D01*
X1319667Y1192821D01*
X1319672Y1192778D01*
G02X1319680Y1192621I-1494J-155D01*
G02X1319310Y1191634I-1501J0D01*
G01X1319286Y1191606D01*
X1319261Y1191539D01*
Y1191203D01*
X1319286Y1191136D01*
X1319310Y1191108D01*
G02X1319680Y1190121I-1131J-987D01*
G02X1316676I-1502J0D01*
G02X1317046Y1191108I1501J0D01*
G01X1317070Y1191136D01*
X1317095Y1191203D01*
Y1191539D01*
X1317070Y1191606D01*
X1317046Y1191634D01*
G02X1316676Y1192621I1131J987D01*
G02X1316684Y1192778I1502J2D01*
G01X1316689Y1192821D01*
X1316663Y1192901D01*
X1316435Y1193153D01*
G03X1316286Y1193220I-149J-133D01*
G01X1313065D01*
G03X1312923Y1193161I0J-200D01*
G01X1312090Y1192328D01*
G03X1312032Y1192186I142J-141D01*
G01Y1168886D01*
G02X1311592Y1167824I-1502J0D01*
G01X1289892Y1146125D01*
G03X1289834Y1145983I142J-141D01*
G01Y1126130D01*
G03X1289892Y1125988I200J-1D01*
G01X1293725Y1122155D01*
G03X1293931Y1122107I142J141D01*
G01X1294324Y1122240D01*
X1294397Y1122327D01*
X1294405Y1122384D01*
G02X1294830Y1123243I1488J-202D01*
G01X1294860Y1123273D01*
X1294889Y1123348D01*
X1294879Y1123722D01*
X1294845Y1123796D01*
X1294813Y1123824D01*
G02X1294313Y1124943I1002J1119D01*
G02X1297317I1502J0D01*
G02X1296878Y1123882I-1502J0D01*
G01X1296848Y1123852D01*
X1296819Y1123777D01*
X1296829Y1123403D01*
X1296863Y1123329D01*
X1296895Y1123301D01*
G02X1297395Y1122182I-1002J-1119D01*
G02X1296095Y1120694I-1502J0D01*
G01X1296038Y1120686D01*
X1295951Y1120613D01*
X1295818Y1120220D01*
G03X1295866Y1120014I189J-64D01*
G01X1310962Y1104918D01*
G03X1311104Y1104860I141J142D01*
G01X1322892D01*
G02X1323954Y1104420I0J-1502D01*
G01X1338348Y1090026D01*
G02X1338788Y1088964I-1062J-1062D01*
G01Y1057508D01*
G03X1338846Y1057366I200J-1D01*
G01X1343189Y1053023D01*
G03X1343331Y1052964I142J141D01*
G01X1391857D01*
G02X1392919Y1052525I1J-1501D01*
G01X1397121Y1048323D01*
G02X1397560Y1047261I-1062J-1061D01*
G01Y1040526D01*
G03X1397758Y1040326I200J0D01*
G01X1398071Y1040323D01*
G03X1398213Y1040379I3J200D01*
G01X1398700Y1040854D01*
G02X1399748Y1041280I1048J-1076D01*
G01X1399852D01*
G02X1401354Y1039779I1J-1501D01*
G02X1400545Y1038447I-1501J0D01*
G01X1400518Y1038433D01*
X1400233Y1038155D01*
G03X1400229Y1037872I139J-143D01*
G01X1400881Y1037204D01*
G02X1401308Y1036155I-1075J-1049D01*
G02X1399807Y1034654I-1501J0D01*
G02X1398733Y1035106I0J1502D01*
G01X1398094Y1035760D01*
G03X1397953Y1035820I-143J-140D01*
G01X1397295Y1035828D01*
X1396305D01*
G02X1395243Y1036268I0J1502D01*
G01X1393497Y1038014D01*
G02X1393058Y1039076I1062J1061D01*
G01Y1045934D01*
G03X1392999Y1046076I-200J0D01*
G01X1390672Y1048403D01*
G03X1390530Y1048462I-142J-141D01*
G01X1386358D01*
G03X1386170Y1048329I1J-200D01*
G01X1386022Y1047914D01*
X1386055Y1047793D01*
X1386105Y1047752D01*
G02X1386654Y1046591I-953J-1161D01*
G02X1383650I-1502J0D01*
G02X1384199Y1047752I1502J0D01*
G01X1384249Y1047793D01*
X1384282Y1047914D01*
X1384134Y1048329D01*
G03X1383946Y1048462I-189J-67D01*
G01X1342004D01*
G02X1340942Y1048901I-1J1501D01*
G01X1334724Y1055119D01*
G02X1334284Y1056181I1062J1062D01*
G01Y1087637D01*
G03X1334226Y1087779I-200J1D01*
G01X1321707Y1100298D01*
G03X1321565Y1100356I-141J-142D01*
G01X1309777D01*
G02X1308715Y1100796I0J1502D01*
G01X1285770Y1123741D01*
G02X1285330Y1124803I1062J1062D01*
G01Y1147310D01*
G02X1285770Y1148372I1502J0D01*
G01X1307470Y1170071D01*
G03X1307528Y1170213I-142J141D01*
G01Y1193513D01*
G02X1307968Y1194575I1502J0D01*
G01X1310676Y1197283D01*
G02X1311738Y1197722I1061J-1062D01*
G01X1373504D01*
G03X1373646Y1197781I0J200D01*
G37*
G36*
G01X1378897Y1196409D02*
G02X1378458Y1197471I1062J1061D01*
G02X1379959Y1198972I1501J0D01*
G02X1381021Y1198533I1J-1501D01*
G01X1381772Y1197781D01*
G03X1381914Y1197722I142J141D01*
G01X1446555D01*
G02X1447617Y1197283I1J-1501D01*
G01X1453200Y1191700D01*
G02X1453640Y1190638I-1062J-1062D01*
G01Y1112059D01*
G03X1453698Y1111917I200J-1D01*
G01X1470054Y1095562D01*
G02X1470494Y1094500I-1062J-1062D01*
G01Y1077737D01*
G02X1470054Y1076675I-1502J0D01*
G01X1431947Y1038568D01*
G02X1430885Y1038128I-1062J1062D01*
G01X1414116D01*
G03X1413974Y1038070I-1J-200D01*
G01X1400489Y1024584D01*
G02X1399427Y1024144I-1062J1062D01*
G01X1382810D01*
G02X1381748Y1024584I0J1502D01*
G01X1379299Y1027033D01*
G02X1378860Y1028095I1062J1061D01*
G01Y1030895D01*
G03X1378801Y1031037I-200J0D01*
G01X1378157Y1031681D01*
G03X1378015Y1031740I-142J-141D01*
G01X1375554D01*
G03X1375412Y1031681I0J-200D01*
G01X1374936Y1031204D01*
G02X1373874Y1030764I-1062J1062D01*
G02X1372372Y1032266I0J1502D01*
G02X1372812Y1033328I1502J0D01*
G01X1373334Y1033850D01*
G03Y1034132I-141J141D01*
G01X1372812Y1034654D01*
G02X1372372Y1035716I1062J1062D01*
G02X1373874Y1037218I1502J0D01*
G02X1374936Y1036778I0J-1502D01*
G01X1375412Y1036301D01*
G03X1375554Y1036242I142J141D01*
G01X1379342D01*
G02X1380404Y1035803I1J-1501D01*
G01X1382923Y1033284D01*
G02X1382989Y1033213I-1066J-1057D01*
G03X1383333Y1033396I151J132D01*
G02X1383282Y1033783I1451J388D01*
G02X1384784Y1032281I1502J0D01*
G02X1383655Y1032792I0J1503D01*
G03X1383312Y1032608I-150J-132D01*
G02X1383362Y1032222I-1451J-384D01*
G01Y1029422D01*
G03X1383421Y1029280I200J0D01*
G01X1383995Y1028706D01*
G03X1384137Y1028648I141J142D01*
G01X1384153D01*
G03X1384353Y1028848I0J200D01*
G01Y1028886D01*
X1384338Y1028922D01*
G02X1384230Y1029482I1394J559D01*
G02X1385732Y1030984I1502J0D01*
G02X1385910Y1030973I-3J-1502D01*
G01X1385948Y1030969D01*
X1386018Y1030987D01*
X1386299Y1031185D01*
X1386339Y1031246D01*
X1386348Y1031283D01*
G02X1387813Y1032454I1465J-331D01*
G02Y1029450I0J-1502D01*
G02X1387635Y1029461I3J1502D01*
G01X1387597Y1029465D01*
X1387527Y1029447D01*
X1387246Y1029249D01*
X1387206Y1029188D01*
X1387197Y1029151D01*
G02X1387194Y1029139I-1458J358D01*
G01X1387184Y1029093D01*
X1387203Y1029006D01*
X1387427Y1028723D01*
G03X1387584Y1028648I156J125D01*
G01X1398100D01*
G03X1398242Y1028706I1J200D01*
G01X1411727Y1042192D01*
G02X1412789Y1042632I1062J-1062D01*
G01X1429558D01*
G03X1429700Y1042690I1J200D01*
G01X1465932Y1078922D01*
G03X1465990Y1079064I-142J141D01*
G01Y1093173D01*
G03X1465932Y1093315I-200J1D01*
G01X1449576Y1109670D01*
G02X1449136Y1110732I1062J1062D01*
G01Y1189311D01*
G03X1449078Y1189453I-200J1D01*
G01X1445370Y1193161D01*
G03X1445228Y1193220I-142J-141D01*
G01X1439132D01*
G03X1438983Y1193153I0J-200D01*
G01X1438755Y1192901D01*
X1438729Y1192821D01*
X1438734Y1192778D01*
G02X1438742Y1192621I-1494J-155D01*
G02X1438372Y1191634I-1501J0D01*
G01X1438348Y1191606D01*
X1438323Y1191539D01*
Y1191203D01*
X1438348Y1191136D01*
X1438372Y1191108D01*
G02X1438742Y1190121I-1131J-987D01*
G02X1435738I-1502J0D01*
G02X1436108Y1191108I1501J0D01*
G01X1436132Y1191136D01*
X1436157Y1191203D01*
Y1191539D01*
X1436132Y1191606D01*
X1436108Y1191634D01*
G02X1435738Y1192621I1131J987D01*
G02X1435746Y1192778I1502J2D01*
G01X1435751Y1192821D01*
X1435725Y1192901D01*
X1435497Y1193153D01*
G03X1435348Y1193220I-149J-133D01*
G01X1420202D01*
G03X1420053Y1193153I0J-200D01*
G01X1419825Y1192901D01*
X1419799Y1192821D01*
X1419804Y1192778D01*
G02X1419812Y1192621I-1494J-155D01*
G02X1419442Y1191634I-1501J0D01*
G01X1419418Y1191606D01*
X1419393Y1191539D01*
Y1191203D01*
X1419418Y1191136D01*
X1419442Y1191108D01*
G02X1419812Y1190121I-1131J-987D01*
G02X1416808I-1502J0D01*
G02X1417178Y1191108I1501J0D01*
G01X1417202Y1191136D01*
X1417227Y1191203D01*
Y1191539D01*
X1417202Y1191606D01*
X1417178Y1191634D01*
G02X1416808Y1192621I1131J987D01*
G02X1416816Y1192778I1502J2D01*
G01X1416821Y1192821D01*
X1416795Y1192901D01*
X1416567Y1193153D01*
G03X1416418Y1193220I-149J-133D01*
G01X1412202D01*
G03X1412053Y1193153I0J-200D01*
G01X1411825Y1192901D01*
X1411799Y1192821D01*
X1411804Y1192778D01*
G02X1411812Y1192621I-1494J-155D01*
G02X1411442Y1191634I-1501J0D01*
G01X1411418Y1191606D01*
X1411393Y1191539D01*
Y1191203D01*
X1411418Y1191136D01*
X1411442Y1191108D01*
G02X1411812Y1190121I-1131J-987D01*
G02X1408808I-1502J0D01*
G02X1409178Y1191108I1501J0D01*
G01X1409202Y1191136D01*
X1409227Y1191203D01*
Y1191539D01*
X1409202Y1191606D01*
X1409178Y1191634D01*
G02X1408808Y1192621I1131J987D01*
G02X1408816Y1192778I1502J2D01*
G01X1408821Y1192821D01*
X1408795Y1192901D01*
X1408567Y1193153D01*
G03X1408418Y1193220I-149J-133D01*
G01X1406737D01*
G03X1406588Y1193153I0J-200D01*
G01X1406360Y1192901D01*
X1406334Y1192821D01*
X1406339Y1192778D01*
G02X1406347Y1192621I-1494J-155D01*
G02X1405977Y1191634I-1501J0D01*
G01X1405953Y1191606D01*
X1405928Y1191539D01*
Y1191203D01*
X1405953Y1191136D01*
X1405977Y1191108D01*
G02X1406347Y1190121I-1131J-987D01*
G02X1403343I-1502J0D01*
G02X1403713Y1191108I1501J0D01*
G01X1403737Y1191136D01*
X1403762Y1191203D01*
Y1191539D01*
X1403737Y1191606D01*
X1403713Y1191634D01*
G02X1403343Y1192621I1131J987D01*
G02X1403351Y1192778I1502J2D01*
G01X1403356Y1192821D01*
X1403330Y1192901D01*
X1403102Y1193153D01*
G03X1402953Y1193220I-149J-133D01*
G01X1393272D01*
G03X1393123Y1193153I0J-200D01*
G01X1392895Y1192901D01*
X1392869Y1192821D01*
X1392874Y1192778D01*
G02X1392882Y1192621I-1494J-155D01*
G02X1392512Y1191634I-1501J0D01*
G01X1392488Y1191606D01*
X1392463Y1191539D01*
Y1191203D01*
X1392488Y1191136D01*
X1392512Y1191108D01*
G02X1392882Y1190121I-1131J-987D01*
G02X1389878I-1502J0D01*
G02X1390248Y1191108I1501J0D01*
G01X1390272Y1191136D01*
X1390297Y1191203D01*
Y1191539D01*
X1390272Y1191606D01*
X1390248Y1191634D01*
G02X1389878Y1192621I1131J987D01*
G02X1389886Y1192778I1502J2D01*
G01X1389891Y1192821D01*
X1389865Y1192901D01*
X1389637Y1193153D01*
G03X1389488Y1193220I-149J-133D01*
G01X1381914D01*
G03X1381772Y1193161I0J-200D01*
G01X1381021Y1192409D01*
G02X1379959Y1191970I-1061J1062D01*
G02X1378458Y1193471I0J1501D01*
G02X1378897Y1194533I1501J1D01*
G01X1379694Y1195330D01*
G03Y1195612I-141J141D01*
G01X1378897Y1196409D01*
G37*
G36*
G01X1398247Y924759D02*
G02Y927763I0J1502D01*
G02X1399506Y927080I0J-1502D01*
G01X1399529Y927044D01*
X1399598Y926999D01*
X1399972Y926935D01*
X1400052Y926955D01*
X1400086Y926981D01*
G02X1401000Y927291I914J-1192D01*
G02Y924287I0J-1502D01*
G02X1399741Y924970I0J1502D01*
G01X1399718Y925006D01*
X1399649Y925051D01*
X1399275Y925115D01*
X1399195Y925095D01*
X1399161Y925069D01*
G02X1398247Y924759I-914J1192D01*
G37*
G36*
G01X1305891Y959487D02*
G03X1305240Y959402I-296J-269D01*
G02X1303907Y958591I-1333J690D01*
G02Y961595I0J1502D01*
G02X1305016Y961106I0J-1502D01*
G03X1305667Y961191I296J269D01*
G02X1307000Y962002I1333J-690D01*
G02Y958998I0J-1502D01*
G02X1305891Y959487I0J1502D01*
G37*
G36*
G01X1318375Y942449D02*
G02Y945453I0J1502D01*
G02X1319559Y944875I-1J-1503D01*
G03X1319707Y944799I157J124D01*
G01X1320054Y944782D01*
X1320135Y944815D01*
X1320165Y944847D01*
G02X1321256Y945317I1091J-1031D01*
G02Y942313I0J-1502D01*
G02X1320072Y942891I1J1503D01*
G03X1319924Y942967I-157J-124D01*
G01X1319577Y942984D01*
X1319496Y942951D01*
X1319466Y942919D01*
G02X1318375Y942449I-1091J1031D01*
G37*
G36*
G01X1374369Y927002D02*
G02X1374435Y927001I10J-1503D01*
G02X1374500Y927002I56J-1501D01*
G02Y923998I0J-1502D01*
G02X1374457Y923999I13J1502D01*
G02X1374369Y923996I-95J1500D01*
G02Y927002I0J1503D01*
G37*
G36*
G01X1491425Y796923D02*
G02Y799927I0J1502D01*
G02X1492917Y798595I0J-1502D01*
G01X1492923Y798539D01*
X1492993Y798450D01*
X1493384Y798307D01*
G03X1493589Y798349I68J188D01*
G02X1495170Y798976I1581J-1680D01*
G02X1497476Y796670I0J-2306D01*
G01Y794169D01*
G02X1496801Y792539I-2306J0D01*
G01X1495085Y790823D01*
G03X1495049Y790590I142J-141D01*
G02X1495218Y789898I-1332J-692D01*
G02X1493716Y788396I-1502J0D01*
G02X1493024Y788565I0J1501D01*
G01X1492965Y788595D01*
X1492837Y788575D01*
X1491409Y787148D01*
G03X1491350Y787006I141J-142D01*
G01Y745776D01*
G02X1490675Y744146I-2306J0D01*
G01X1487391Y740863D01*
G03X1487332Y740721I141J-142D01*
G01Y740708D01*
G03X1487532Y740508I200J0D01*
G01X1487572D01*
X1487645Y740538D01*
X1487673Y740566D01*
G02X1488731Y741002I1058J-1066D01*
G02Y737998I0J-1502D01*
G02X1487942Y738222I0J1502D01*
G01X1487896Y738250D01*
X1487789Y738253D01*
X1487435Y738056D01*
G03X1487332Y737881I97J-175D01*
G01Y733383D01*
G03X1487401Y733232I200J0D01*
G01X1487629Y733034D01*
G03X1487788Y732987I131J151D01*
G01X1487789D01*
G02X1488000Y733002I212J-1487D01*
G02Y729998I0J-1502D01*
G02X1487789Y730013I1J1502D01*
G01X1487788D01*
G03X1487629Y729966I-28J-198D01*
G01X1487401Y729768D01*
G03X1487332Y729617I131J-151D01*
G01Y722639D01*
G02X1486657Y721009I-2306J0D01*
G01X1478865Y713218D01*
G03X1478806Y713076I141J-142D01*
G01Y711197D01*
G03X1478889Y711035I200J0D01*
G01X1479189Y710817D01*
X1479284Y710802D01*
X1479330Y710817D01*
G02X1479791Y710890I463J-1429D01*
G01X1479794D01*
G02Y707886I0J-1502D01*
G01X1479792D01*
G02X1478895Y708184I1J1502D01*
G01X1478863Y708208D01*
X1478786Y708228D01*
X1478468Y708182D01*
G03X1478337Y708106I27J-198D01*
G02X1478131Y707869I-1840J1391D01*
G01X1476808Y706546D01*
G03X1476758Y706346I141J-142D01*
G01X1476876Y705955D01*
X1476957Y705882D01*
X1477012Y705871D01*
G02X1478218Y704398I-297J-1473D01*
G02X1475214I-1502J0D01*
G01Y704415D01*
G03X1475133Y704578I-200J2D01*
G01X1474834Y704799D01*
X1474740Y704815D01*
X1474694Y704800D01*
G02X1474000Y704694I-691J2200D01*
G02X1472297Y705444I-1J2306D01*
G01X1472270Y705474D01*
X1472196Y705508D01*
X1471866Y705516D01*
G03X1471719Y705457I-5J-200D01*
G01X1471588Y705326D01*
G02X1469957Y704650I-1632J1631D01*
G02X1467650Y706957I0J2307D01*
G02X1468326Y708588I2307J-1D01*
G01X1468991Y709252D01*
G03X1469050Y709394I-141J142D01*
G01Y715950D01*
G02X1469294Y716982I2306J0D01*
G01X1469295Y716983D01*
G03X1469290Y717169I-180J88D01*
G01X1469130Y717458D01*
G03X1468974Y717560I-175J-97D01*
G02X1467614Y719055I142J1495D01*
G02X1469116Y720557I1502J0D01*
G02X1470592Y719332I0J-1502D01*
G01X1470602Y719278D01*
X1470676Y719195D01*
X1471068Y719074D01*
G03X1471268Y719123I59J191D01*
G01X1477230Y725085D01*
G02X1478860Y725760I1630J-1631D01*
G01X1480238D01*
G03X1480380Y725819I0J200D01*
G01X1480543Y725982D01*
G03X1480602Y726124I-141J142D01*
G01Y729609D01*
G03X1480536Y729758I-200J0D01*
G01X1480282Y729985D01*
X1480202Y730011D01*
X1480159Y730006D01*
G02X1480000Y729998I-155J1494D01*
G02Y733002I0J1502D01*
G02X1480159Y732994I4J-1502D01*
G01X1480202Y732989D01*
X1480282Y733015D01*
X1480536Y733242D01*
G03X1480602Y733391I-134J149D01*
G01Y733678D01*
G03X1480521Y733838I-200J-1D01*
G01X1480226Y734058D01*
X1480132Y734075D01*
X1480087Y734061D01*
G02X1479657Y733998I-430J1439D01*
G02Y737002I0J1502D01*
G02X1480087Y736939I0J-1502D01*
G01X1480132Y736925D01*
X1480226Y736942D01*
X1480521Y737162D01*
G03X1480602Y737322I-119J161D01*
G01Y737609D01*
G03X1480536Y737758I-200J0D01*
G01X1480282Y737985D01*
X1480202Y738011D01*
X1480159Y738006D01*
G02X1480000Y737998I-155J1494D01*
G02Y741002I0J1502D01*
G02X1480159Y740994I4J-1502D01*
G01X1480202Y740989D01*
X1480282Y741015D01*
X1480536Y741242D01*
G03X1480602Y741391I-134J149D01*
G01Y741650D01*
G03X1480526Y741807I-200J0D01*
G01X1480279Y742002D01*
G03X1480108Y742039I-124J-157D01*
G02X1479760Y741998I-349J1461D01*
G01X1479759D01*
G02Y745002I0J1502D01*
G02X1480504Y744804I0J-1502D01*
G01X1480537Y744785D01*
X1480609Y744774D01*
X1480908Y744840D01*
G03X1481028Y744919I-43J196D01*
G01Y744920D01*
G02X1481277Y745215I1881J-1335D01*
G01X1484591Y748529D01*
G03X1484650Y748671I-141J142D01*
G01Y792457D01*
G02X1489264I2307J0D01*
G01Y792008D01*
G03X1489387Y791823I200J0D01*
G01X1489443Y791800D01*
X1489561Y791823D01*
X1489737Y791999D01*
G03X1489768Y792242I-141J142D01*
G02X1489560Y793003I1294J763D01*
G02X1491062Y794505I1502J0D01*
G02X1491824Y794297I-1J-1502D01*
G03X1492067Y794328I101J172D01*
G01X1492805Y795066D01*
G03X1492864Y795208I-141J142D01*
G01Y796670D01*
G02X1492868Y796811I2306J5D01*
G03X1492769Y796996I-200J12D01*
G01X1492409Y797204D01*
X1492297Y797201D01*
X1492249Y797169D01*
G02X1491425Y796923I-824J1257D01*
G37*
G36*
G01X1492625Y839630D02*
G02X1494932Y837324I1J-2306D01*
G02X1494256Y835693I-2307J1D01*
G01X1494095Y835532D01*
G03X1494036Y835390I141J-142D01*
G01X1494037Y835066D01*
X1494068Y834993D01*
X1494096Y834965D01*
G02X1494540Y833899I-1058J-1066D01*
G01Y833898D01*
G02X1493038Y832396I-1502J0D01*
G02X1492098Y832727I1J1502D01*
G03X1491831Y832712I-125J-156D01*
G01X1486547Y827428D01*
G03X1486496Y827232I141J-141D01*
G01X1486606Y826845D01*
X1486684Y826769D01*
X1486737Y826757D01*
G02X1487888Y825296I-352J-1461D01*
G02X1486386Y823794I-1502J0D01*
G02X1484925Y824945I0J1503D01*
G01X1484913Y824998D01*
X1484837Y825076D01*
X1484450Y825186D01*
G03X1484254Y825135I-55J-192D01*
G01X1473981Y814863D01*
G03X1473922Y814721I141J-142D01*
G01Y758824D01*
G03X1473985Y758679I200J1D01*
G01X1474225Y758451D01*
X1474303Y758423D01*
X1474344Y758425D01*
G02X1474425Y758427I78J-1500D01*
G02X1475927Y756925I0J-1502D01*
G02X1475304Y755707I-1502J0D01*
G01X1475268Y755681D01*
X1475225Y755605D01*
X1475197Y755257D01*
G03X1475255Y755100I200J-16D01*
G01X1475631Y754724D01*
G02X1476306Y753093I-1631J-1630D01*
G02X1474000Y750786I-2306J-1D01*
G02X1472586Y751271I1J2307D01*
G01X1472560Y751292D01*
X1472497Y751313D01*
X1472464D01*
G03X1472264Y751113I0J-200D01*
G01Y750957D01*
G02X1467650I-2307J0D01*
G01Y752223D01*
G03X1467624Y752322I-200J0D01*
G02X1467318Y753467I2000J1148D01*
G01Y816725D01*
G02X1467993Y818355I2306J0D01*
G01X1475626Y825987D01*
G03X1475685Y826129I-141J142D01*
G01X1475683Y826454D01*
X1475652Y826527D01*
X1475623Y826555D01*
G02X1475175Y827624I1054J1070D01*
G01Y827626D01*
G02X1476677Y829128I1502J0D01*
G01X1476679D01*
G02X1477748Y828680I-1J-1502D01*
G01X1477776Y828651D01*
X1477849Y828620D01*
X1478174Y828618D01*
G03X1478316Y828677I0J200D01*
G01X1484591Y834953D01*
G03X1484650Y835095I-141J142D01*
G01Y836457D01*
G02X1486957Y838764I2307J0D01*
G02X1488483Y838186I-1J-2306D01*
G03X1488737Y838177I132J150D01*
G02X1489650Y838487I914J-1192D01*
G02X1490233Y838370I2J-1503D01*
G03X1490451Y838412I78J184D01*
G01X1490994Y838955D01*
G02X1492625Y839630I1630J-1631D01*
G37*
G36*
G01X1513926Y907148D02*
X1510526D01*
G02Y910754I0J1803D01*
G01X1513926D01*
G02Y907148I0J-1803D01*
G37*
G36*
G01X1447558Y352361D02*
G02X1450562I1502J0D01*
G02X1449798Y351053I-1502J0D01*
G03X1449698Y350911I97J-175D01*
G01X1449639Y350559D01*
X1449664Y350473D01*
X1449695Y350439D01*
G02X1450074Y349442I-1123J-998D01*
G01Y349441D01*
G02X1447070I-1502J0D01*
G02X1447834Y350749I1502J0D01*
G03X1447934Y350891I-97J175D01*
G01X1447993Y351243D01*
X1447968Y351329D01*
X1447937Y351363D01*
G02X1447558Y352360I1123J998D01*
G01Y352361D01*
G37*
G36*
G01X1372232Y359796D02*
G02Y362800I0J1502D01*
G02X1373328Y362325I0J-1502D01*
G01X1373357Y362294D01*
X1373436Y362260D01*
X1373779Y362270D01*
G03X1373926Y362340I-5J200D01*
G02X1375073Y362873I1147J-968D01*
G02Y359869I0J-1502D01*
G02X1373977Y360344I0J1502D01*
G01X1373948Y360375D01*
X1373869Y360409D01*
X1373526Y360399D01*
G03X1373379Y360329I5J-200D01*
G02X1372232Y359796I-1147J968D01*
G37*
G36*
G01X1400231Y388754D02*
G02Y391758I0J1502D01*
G02X1401342Y391267I0J-1502D01*
G01X1401369Y391237D01*
X1401443Y391203D01*
X1401813Y391192D01*
X1401888Y391222D01*
X1401917Y391250D01*
G02X1402968Y391679I1051J-1073D01*
G02Y388675I0J-1502D01*
G02X1401857Y389166I0J1502D01*
G01X1401830Y389196D01*
X1401756Y389230D01*
X1401386Y389241D01*
X1401311Y389211D01*
X1401282Y389183D01*
G02X1400231Y388754I-1051J1073D01*
G37*
G36*
G01X1438888Y461652D02*
G02X1440390Y463154I1502J0D01*
G02X1441377Y462784I0J-1501D01*
G01X1441378D01*
Y462783D01*
G03X1441508Y462735I130J152D01*
G01X1441772D01*
G03X1441902Y462783I0J200D01*
G01X1441903Y462784D01*
G02X1442890Y463154I987J-1131D01*
G02X1444392Y461652I0J-1502D01*
G02X1444022Y460665I-1501J0D01*
G01Y460664D01*
X1444021D01*
G03X1443973Y460534I152J-130D01*
G01Y460270D01*
G03X1444021Y460140I200J0D01*
G01X1444022Y460139D01*
G02Y458165I-1131J-987D01*
G01Y458164D01*
X1444021D01*
G03X1443973Y458034I152J-130D01*
G01Y457770D01*
G03X1444021Y457640I200J0D01*
G01X1444022Y457639D01*
G02X1444392Y456652I-1131J-987D01*
G02X1442890Y455150I-1502J0D01*
G02X1441903Y455520I0J1501D01*
G01X1441902D01*
Y455521D01*
G03X1441772Y455569I-130J-152D01*
G01X1441508D01*
G03X1441378Y455521I0J-200D01*
G01X1441377Y455520D01*
G02X1440390Y455150I-987J1131D01*
G02X1438888Y456652I0J1502D01*
G02X1439258Y457639I1501J0D01*
G01Y457640D01*
X1439259D01*
G03X1439307Y457770I-152J130D01*
G01Y458034D01*
G03X1439259Y458164I-200J0D01*
G01X1439258Y458165D01*
G02Y460139I1131J987D01*
G01Y460140D01*
X1439259D01*
G03X1439307Y460270I-152J130D01*
G01Y460534D01*
G03X1439259Y460664I-200J0D01*
G01X1439258Y460665D01*
G02X1438888Y461652I1131J987D01*
G37*
G36*
G01X1424882Y478625D02*
G02X1427886I1502J0D01*
G02X1427516Y477638I-1501J0D01*
G01Y477637D01*
X1427515D01*
G03X1427467Y477507I152J-130D01*
G01Y477243D01*
G03X1427515Y477113I200J0D01*
G01X1427516Y477112D01*
G02X1427886Y476125I-1131J-987D01*
G02X1424882I-1502J0D01*
G02X1425252Y477112I1501J0D01*
G01Y477113D01*
X1425253D01*
G03X1425301Y477243I-152J130D01*
G01Y477507D01*
G03X1425253Y477637I-200J0D01*
G01X1425252Y477638D01*
G02X1424882Y478625I1131J987D01*
G37*
G36*
G01X1425986Y486270D02*
X1425987Y486269D01*
G03X1426117Y486221I130J152D01*
G01X1426381D01*
G03X1426511Y486269I0J200D01*
G01X1426512Y486270D01*
G02X1427499Y486640I987J-1131D01*
G02X1429001Y485138I0J-1502D01*
G02X1428734Y484283I-1502J0D01*
G01X1428711Y484249D01*
X1428694Y484168D01*
X1428774Y483801D01*
X1428822Y483734D01*
X1428857Y483713D01*
G02X1429586Y482425I-773J-1288D01*
G02X1426582I-1502J0D01*
G02X1426849Y483280I1502J0D01*
G01X1426872Y483314D01*
X1426889Y483395D01*
X1426809Y483762D01*
X1426761Y483829D01*
X1426726Y483850D01*
G02X1426513Y484006I777J1285D01*
G03X1426511Y484007I-88J-173D01*
G03X1426381Y484055I-130J-152D01*
G01X1426117D01*
G03X1425987Y484007I0J-200D01*
G01X1425986Y484006D01*
G02X1424012I-987J1131D01*
G01X1424011D01*
Y484007D01*
G03X1423881Y484055I-130J-152D01*
G01X1423617D01*
G03X1423487Y484007I0J-200D01*
G01X1423486Y484006D01*
G02X1422499Y483636I-987J1131D01*
G02X1421378Y484139I0J1501D01*
G01X1421349Y484172D01*
X1421272Y484206D01*
X1420927Y484204D01*
G03X1420779Y484138I0J-200D01*
G01X1420778Y484137D01*
G02X1419650Y483626I-1129J991D01*
G02Y486630I0J1502D01*
G02X1420771Y486127I0J-1501D01*
G01X1420800Y486094D01*
X1420877Y486060D01*
X1421222Y486062D01*
G03X1421370Y486128I0J200D01*
G01X1421371Y486129D01*
G02X1422499Y486640I1129J-991D01*
G02X1423486Y486270I0J-1501D01*
G01X1423487D01*
Y486269D01*
G03X1423617Y486221I130J152D01*
G01X1423881D01*
G03X1424011Y486269I0J200D01*
G01X1424012Y486270D01*
G02X1425986I987J-1131D01*
G37*
G36*
G01X1432458Y493714D02*
G02X1435462I1502J0D01*
G02X1435092Y492727I-1501J0D01*
G01Y492726D01*
X1435091D01*
G03X1435043Y492596I152J-130D01*
G01Y492332D01*
G03X1435091Y492202I200J0D01*
G01X1435092Y492201D01*
G02X1435462Y491214I-1131J-987D01*
G02X1432458I-1502J0D01*
G02X1432828Y492201I1501J0D01*
G01Y492202D01*
X1432829D01*
G03X1432877Y492332I-152J130D01*
G01Y492596D01*
G03X1432829Y492726I-200J0D01*
G01X1432828Y492727D01*
G02X1432458Y493714I1131J987D01*
G37*
G36*
G01X1436161Y495487D02*
G02X1439165I1502J0D01*
G02X1438795Y494500I-1501J0D01*
G01Y494499D01*
X1438794D01*
G03X1438746Y494369I152J-130D01*
G01Y494105D01*
G03X1438794Y493975I200J0D01*
G01X1438795Y493974D01*
G02X1439165Y492987I-1131J-987D01*
G02X1436161I-1502J0D01*
G02X1436531Y493974I1501J0D01*
G01Y493975D01*
X1436532D01*
G03X1436580Y494105I-152J130D01*
G01Y494369D01*
G03X1436532Y494499I-200J0D01*
G01X1436531Y494500D01*
G02X1436161Y495487I1131J987D01*
G37*
G36*
G01X1447791Y498633D02*
G02X1450795I1502J0D01*
G02X1450425Y497646I-1501J0D01*
G01Y497645D01*
X1450424D01*
G03X1450376Y497515I152J-130D01*
G01Y497251D01*
G03X1450424Y497121I200J0D01*
G01X1450425Y497120D01*
G02Y495146I-1131J-987D01*
G01Y495145D01*
X1450424D01*
G03X1450376Y495015I152J-130D01*
G01Y494751D01*
G03X1450424Y494621I200J0D01*
G01X1450425Y494620D01*
G02Y492646I-1131J-987D01*
G01Y492645D01*
X1450424D01*
G03X1450376Y492515I152J-130D01*
G01Y492251D01*
G03X1450424Y492121I200J0D01*
G01X1450425Y492120D01*
G02X1450795Y491133I-1131J-987D01*
G02X1447791I-1502J0D01*
G02X1448161Y492120I1501J0D01*
G01Y492121D01*
X1448162D01*
G03X1448210Y492251I-152J130D01*
G01Y492515D01*
G03X1448162Y492645I-200J0D01*
G01X1448161Y492646D01*
G02Y494620I1131J987D01*
G01Y494621D01*
X1448162D01*
G03X1448210Y494751I-152J130D01*
G01Y495015D01*
G03X1448162Y495145I-200J0D01*
G01X1448161Y495146D01*
G02Y497120I1131J987D01*
G01Y497121D01*
X1448162D01*
G03X1448210Y497251I-152J130D01*
G01Y497515D01*
G03X1448162Y497645I-200J0D01*
G01X1448161Y497646D01*
G02X1447791Y498633I1131J987D01*
G37*
G36*
G01X1414548Y505957D02*
X1414549Y505956D01*
G03X1414679Y505908I130J152D01*
G01X1414943D01*
G03X1415073Y505956I0J200D01*
G01X1415074Y505957D01*
G02X1416061Y506327I987J-1131D01*
G02Y503323I0J-1502D01*
G02X1415074Y503693I0J1501D01*
G01X1415073D01*
Y503694D01*
G03X1414943Y503742I-130J-152D01*
G01X1414679D01*
G03X1414549Y503694I0J-200D01*
G01X1414548Y503693D01*
G02X1412574I-987J1131D01*
G01X1412573D01*
Y503694D01*
G03X1412443Y503742I-130J-152D01*
G01X1412179D01*
G03X1412049Y503694I0J-200D01*
G01X1412048Y503693D01*
G02X1411061Y503323I-987J1131D01*
G02Y506327I0J1502D01*
G02X1412048Y505957I0J-1501D01*
G01X1412049D01*
Y505956D01*
G03X1412179Y505908I130J152D01*
G01X1412443D01*
G03X1412573Y505956I0J200D01*
G01X1412574Y505957D01*
G02X1414548I987J-1131D01*
G37*
G36*
G01X1414489Y518533D02*
X1414490Y518532D01*
G03X1414620Y518484I130J152D01*
G01X1414884D01*
G03X1415014Y518532I0J200D01*
G01X1415015Y518533D01*
G02X1416002Y518903I987J-1131D01*
G02Y515899I0J-1502D01*
G02X1415015Y516269I0J1501D01*
G01X1415014D01*
Y516270D01*
G03X1414884Y516318I-130J-152D01*
G01X1414620D01*
G03X1414490Y516270I0J-200D01*
G01X1414489Y516269D01*
G02X1412515I-987J1131D01*
G01X1412514D01*
Y516270D01*
G03X1412384Y516318I-130J-152D01*
G01X1412120D01*
G03X1411990Y516270I0J-200D01*
G01X1411989Y516269D01*
G02X1411002Y515899I-987J1131D01*
G02Y518903I0J1502D01*
G02X1411989Y518533I0J-1501D01*
G01X1411990D01*
Y518532D01*
G03X1412120Y518484I130J152D01*
G01X1412384D01*
G03X1412514Y518532I0J200D01*
G01X1412515Y518533D01*
G02X1414489I987J-1131D01*
G37*
G36*
G01X1415601Y523822D02*
Y524116D01*
G03X1415536Y524263I-200J-1D01*
G02X1415051Y525369I1019J1106D01*
G02X1418055I1502J0D01*
G02X1417570Y524263I-1504J0D01*
G03X1417505Y524116I135J-148D01*
G01Y523822D01*
G03X1417570Y523675I200J1D01*
G02X1418055Y522569I-1019J-1106D01*
G02X1415051I-1502J0D01*
G02X1415536Y523675I1504J0D01*
G03X1415601Y523822I-135J148D01*
G37*
G36*
G01X1423177Y538911D02*
Y539205D01*
G03X1423112Y539352I-200J-1D01*
G02X1422627Y540458I1019J1106D01*
G02X1425631I1502J0D01*
G02X1425146Y539352I-1504J0D01*
G03X1425081Y539205I135J-148D01*
G01Y538911D01*
G03X1425146Y538764I200J1D01*
G02X1425631Y537658I-1019J-1106D01*
G02X1422627I-1502J0D01*
G02X1423112Y538764I1504J0D01*
G03X1423177Y538911I-135J148D01*
G37*
G36*
G01X1426330Y542231D02*
G02X1429334I1502J0D01*
G02X1428964Y541244I-1501J0D01*
G01Y541243D01*
X1428963D01*
G03X1428915Y541113I152J-130D01*
G01Y540849D01*
G03X1428963Y540719I200J0D01*
G01X1428964Y540718D01*
G02X1429334Y539731I-1131J-987D01*
G02X1426330I-1502J0D01*
G02X1426700Y540718I1501J0D01*
G01Y540719D01*
X1426701D01*
G03X1426749Y540849I-152J130D01*
G01Y541113D01*
G03X1426701Y541243I-200J0D01*
G01X1426700Y541244D01*
G02X1426330Y542231I1131J987D01*
G37*
G36*
G01X1593958Y549800D02*
G02X1596962I1502J0D01*
G02X1596423Y548648I-1502J1D01*
G01X1596422Y548647D01*
G03X1596352Y548509I129J-152D01*
G01X1596331Y548221D01*
G03X1596380Y548075I200J-14D01*
G01X1596381Y548074D01*
G02X1596762Y547075I-1121J-1000D01*
G02X1593758I-1502J0D01*
G02X1594297Y548227I1502J-1D01*
G01X1594298Y548228D01*
G03X1594368Y548366I-129J152D01*
G01X1594389Y548654D01*
G03X1594340Y548800I-200J14D01*
G01X1594339Y548801D01*
G02X1593958Y549800I1121J1000D01*
G37*
G36*
G01X1690778Y549181D02*
X1690486D01*
G03X1690339Y549117I0J-200D01*
G02X1689236Y548635I-1103J1021D01*
G02Y551639I0J1502D01*
G02X1690339Y551157I0J-1503D01*
G03X1690486Y551093I147J136D01*
G01X1690778D01*
G03X1690925Y551157I0J200D01*
G02X1692028Y551639I1103J-1021D01*
G02Y548635I0J-1502D01*
G02X1690925Y549117I0J1503D01*
G03X1690778Y549181I-147J-136D01*
G37*
G36*
G01X1542873Y553407D02*
G02X1544375Y554909I1502J0D01*
G02X1545362Y554539I0J-1501D01*
G01X1545363D01*
Y554538D01*
G03X1545493Y554490I130J152D01*
G01X1545757D01*
G03X1545887Y554538I0J200D01*
G01X1545888Y554539D01*
G02X1546875Y554909I987J-1131D01*
G02X1548377Y553407I0J-1502D01*
G02X1548007Y552420I-1501J0D01*
G01Y552419D01*
X1548006D01*
G03X1547958Y552289I152J-130D01*
G01Y552025D01*
G03X1548006Y551895I200J0D01*
G01X1548007Y551894D01*
G02X1548377Y550907I-1131J-987D01*
G02X1546875Y549405I-1502J0D01*
G02X1545888Y549775I0J1501D01*
G01X1545887D01*
Y549776D01*
G03X1545757Y549824I-130J-152D01*
G01X1545493D01*
G03X1545363Y549776I0J-200D01*
G01X1545362Y549775D01*
G02X1544375Y549405I-987J1131D01*
G02X1542873Y550907I0J1502D01*
G02X1543243Y551894I1501J0D01*
G01Y551895D01*
X1543244D01*
G03X1543292Y552025I-152J130D01*
G01Y552289D01*
G03X1543244Y552419I-200J0D01*
G01X1543243Y552420D01*
G02X1542873Y553407I1131J987D01*
G37*
G36*
G01X1416650Y554242D02*
X1416356D01*
G03X1416209Y554177I1J-200D01*
G02X1415103Y553692I-1106J1019D01*
G02Y556696I0J1502D01*
G02X1416209Y556211I0J-1504D01*
G03X1416356Y556146I148J135D01*
G01X1416650D01*
G03X1416797Y556211I-1J200D01*
G02X1417903Y556696I1106J-1019D01*
G02Y553692I0J-1502D01*
G02X1416797Y554177I0J1504D01*
G03X1416650Y554242I-148J-135D01*
G37*
G36*
G01Y562242D02*
X1416356D01*
G03X1416209Y562177I1J-200D01*
G02X1415103Y561692I-1106J1019D01*
G02Y564696I0J1502D01*
G02X1416209Y564211I0J-1504D01*
G03X1416356Y564146I148J135D01*
G01X1416650D01*
G03X1416797Y564211I-1J200D01*
G02X1417903Y564696I1106J-1019D01*
G02Y561692I0J-1502D01*
G02X1416797Y562177I0J1504D01*
G03X1416650Y562242I-148J-135D01*
G37*
G36*
G01Y570242D02*
X1416356D01*
G03X1416209Y570177I1J-200D01*
G02X1415103Y569692I-1106J1019D01*
G02Y572696I0J1502D01*
G02X1416209Y572211I0J-1504D01*
G03X1416356Y572146I148J135D01*
G01X1416650D01*
G03X1416797Y572211I-1J200D01*
G02X1417903Y572696I1106J-1019D01*
G02Y569692I0J-1502D01*
G02X1416797Y570177I0J1504D01*
G03X1416650Y570242I-148J-135D01*
G37*
G36*
G01X1541202Y572162D02*
G02X1544206I1502J0D01*
G02X1544167Y571820I-1502J-2D01*
G01X1544158Y571784D01*
X1544168Y571710D01*
X1544336Y571410D01*
X1544393Y571363D01*
X1544428Y571351D01*
G02X1544507Y571321I-493J-1419D01*
G03X1544664Y571324I75J185D01*
G01X1544779Y571375D01*
G03X1544886Y571488I-80J183D01*
G02X1546293Y572464I1407J-526D01*
G02X1547769Y571243I0J-1503D01*
G01X1547776Y571205D01*
X1547815Y571142D01*
X1548063Y570958D01*
G03X1548202Y570920I119J161D01*
G01X1548203D01*
G02X1548357Y570928I155J-1494D01*
G01X1548359D01*
G02X1549861Y569426I0J-1502D01*
G02X1549592Y568568I-1503J0D01*
G03X1549558Y568431I164J-114D01*
G01X1549587Y568169D01*
G03X1549652Y568043I199J23D01*
G02X1550147Y566929I-1006J-1114D01*
G02X1548645Y565427I-1502J0D01*
G02X1547153Y566758I0J1502D01*
G01Y566760D01*
G03X1547056Y566908I-198J-24D01*
G01X1546781Y567072D01*
G03X1546604Y567085I-102J-172D01*
G02X1546036Y566973I-569J1390D01*
G02X1544574Y568132I0J1502D01*
G01Y568133D01*
G03X1544493Y568250I-194J-48D01*
G01X1544272Y568404D01*
G03X1544135Y568438I-114J-165D01*
G01X1544134D01*
G02X1543946Y568426I-189J1490D01*
G02X1542444Y569928I0J1502D01*
G02X1542483Y570270I1502J2D01*
G01X1542492Y570306D01*
X1542482Y570380D01*
X1542314Y570680D01*
X1542257Y570727D01*
X1542222Y570739D01*
G02X1541202Y572162I483J1423D01*
G37*
G36*
G01X1417913Y582174D02*
X1418207D01*
G03X1418354Y582239I-1J200D01*
G02X1420566I1106J-1017D01*
G03X1420713Y582174I148J135D01*
G01X1421007D01*
G03X1421154Y582239I-1J200D01*
G02X1422260Y582724I1106J-1019D01*
G02Y579720I0J-1502D01*
G02X1421154Y580205I0J1504D01*
G03X1421007Y580270I-148J-135D01*
G01X1420713D01*
G03X1420566Y580205I1J-200D01*
G02X1418354I-1106J1017D01*
G03X1418207Y580270I-148J-135D01*
G01X1417913D01*
G03X1417766Y580205I1J-200D01*
G02X1416660Y579720I-1106J1019D01*
G02Y582724I0J1502D01*
G02X1417766Y582239I0J-1504D01*
G03X1417913Y582174I148J135D01*
G37*
G36*
G01Y592167D02*
X1418207D01*
G03X1418354Y592232I-1J200D01*
G02X1420566I1106J-1017D01*
G03X1420713Y592167I148J135D01*
G01X1421007D01*
G03X1421154Y592232I-1J200D01*
G02X1422260Y592717I1106J-1019D01*
G02Y589713I0J-1502D01*
G02X1421154Y590198I0J1504D01*
G03X1421007Y590263I-148J-135D01*
G01X1420713D01*
G03X1420566Y590198I1J-200D01*
G02X1418354I-1106J1017D01*
G03X1418207Y590263I-148J-135D01*
G01X1417913D01*
G03X1417766Y590198I1J-200D01*
G02X1416660Y589713I-1106J1019D01*
G02Y592717I0J1502D01*
G02X1417766Y592232I0J-1504D01*
G03X1417913Y592167I148J135D01*
G37*
G36*
G01X1420885Y611514D02*
X1421179D01*
G03X1421326Y611579I-1J200D01*
G02X1423538I1106J-1017D01*
G03X1423685Y611514I148J135D01*
G01X1423979D01*
G03X1424126Y611579I-1J200D01*
G02X1425232Y612064I1106J-1019D01*
G02X1426734Y610562I0J-1502D01*
G02X1426249Y609456I-1504J0D01*
G03X1426184Y609309I135J-148D01*
G01Y609015D01*
G03X1426249Y608868I200J1D01*
G02X1426734Y607762I-1019J-1106D01*
G02X1425232Y606260I-1502J0D01*
G02X1424126Y606745I0J1504D01*
G03X1423979Y606810I-148J-135D01*
G01X1423685D01*
G03X1423538Y606745I1J-200D01*
G02X1421326I-1106J1017D01*
G03X1421179Y606810I-148J-135D01*
G01X1420885D01*
G03X1420738Y606745I1J-200D01*
G02X1418526I-1106J1017D01*
G03X1418379Y606810I-148J-135D01*
G01X1418085D01*
G03X1417938Y606745I1J-200D01*
G02X1416832Y606260I-1106J1019D01*
G02X1415330Y607762I0J1502D01*
G02X1415815Y608868I1504J0D01*
G03X1415880Y609015I-135J148D01*
G01Y609309D01*
G03X1415815Y609456I-200J-1D01*
G02X1415330Y610562I1019J1106D01*
G02X1416832Y612064I1502J0D01*
G02X1417938Y611579I0J-1504D01*
G03X1418085Y611514I148J135D01*
G01X1418379D01*
G03X1418526Y611579I-1J200D01*
G02X1420738I1106J-1017D01*
G03X1420885Y611514I148J135D01*
G37*
G36*
G01X1439978Y617966D02*
Y618260D01*
G03X1439913Y618407I-200J-1D01*
G02X1439428Y619513I1019J1106D01*
G02X1442432I1502J0D01*
G02X1441947Y618407I-1504J0D01*
G03X1441882Y618260I135J-148D01*
G01Y617966D01*
G03X1441947Y617819I200J1D01*
G02Y615607I-1017J-1106D01*
G03X1441882Y615460I135J-148D01*
G01Y615166D01*
G03X1441947Y615019I200J1D01*
G02X1442432Y613913I-1019J-1106D01*
G02X1439428I-1502J0D01*
G02X1439913Y615019I1504J0D01*
G03X1439978Y615166I-135J148D01*
G01Y615460D01*
G03X1439913Y615607I-200J-1D01*
G02Y617819I1017J1106D01*
G03X1439978Y617966I-135J148D01*
G37*
G36*
G01X1452048Y618211D02*
Y618505D01*
G03X1451983Y618652I-200J-1D01*
G02X1451498Y619758I1019J1106D01*
G02X1454502I1502J0D01*
G02X1454017Y618652I-1504J0D01*
G03X1453952Y618505I135J-148D01*
G01Y618211D01*
G03X1454017Y618064I200J1D01*
G02Y615852I-1017J-1106D01*
G03X1453952Y615705I135J-148D01*
G01Y615411D01*
G03X1454017Y615264I200J1D01*
G02X1454502Y614158I-1019J-1106D01*
G02X1451498I-1502J0D01*
G02X1451983Y615264I1504J0D01*
G03X1452048Y615411I-135J148D01*
G01Y615705D01*
G03X1451983Y615852I-200J-1D01*
G02Y618064I1017J1106D01*
G03X1452048Y618211I-135J148D01*
G37*
G36*
G01X1432162Y619106D02*
Y619400D01*
G03X1432097Y619547I-200J-1D01*
G02X1431612Y620653I1019J1106D01*
G02X1434616I1502J0D01*
G02X1434131Y619547I-1504J0D01*
G03X1434066Y619400I135J-148D01*
G01Y619106D01*
G03X1434131Y618959I200J1D01*
G02X1434616Y617853I-1019J-1106D01*
G02X1431612I-1502J0D01*
G02X1432097Y618959I1504J0D01*
G03X1432162Y619106I-135J148D01*
G37*
G36*
G01X1569434Y675609D02*
G02Y678613I0J1502D01*
G02X1570131Y678441I-1J-1502D01*
G03X1570135Y678439I91J178D01*
G01X1570156Y678428D01*
X1570200Y678418D01*
X1574890D01*
G02X1575814Y678035I0J-1306D01*
G01X1585043Y668806D01*
G02X1585426Y667882I-923J-924D01*
G01Y647261D01*
G02X1585043Y646337I-1306J0D01*
G01X1571425Y632719D01*
G03X1571366Y632577I141J-142D01*
G01Y580257D01*
G03X1571425Y580115I200J0D01*
G01X1572120Y579420D01*
G03X1572200Y579371I142J141D01*
G01X1572201D01*
G02X1573257Y577937I-446J-1434D01*
G02X1571755Y576435I-1502J0D01*
G02X1570321Y577490I0J1502D01*
G01Y577492D01*
G03X1570272Y577572I-190J-62D01*
G01X1569135Y578709D01*
G02X1568752Y579633I923J924D01*
G01Y633201D01*
G02X1569135Y634125I1306J0D01*
G01X1582753Y647743D01*
G03X1582812Y647885I-141J142D01*
G01Y667258D01*
G03X1582753Y667400I-200J0D01*
G01X1574408Y675745D01*
G03X1574266Y675804I-142J-141D01*
G01X1570224D01*
G03X1570135Y675783I0J-200D01*
G01X1570133Y675782D01*
G02X1569434Y675609I-700J1329D01*
G37*
G36*
G01X1522031Y899796D02*
G02X1521379Y901034I849J1238D01*
G02X1524383I1502J0D01*
G02X1523789Y899837I-1503J0D01*
G03X1523804Y899189I242J-319D01*
G02X1524456Y897951I-849J-1238D01*
G02X1521452I-1502J0D01*
G02X1522046Y899148I1503J0D01*
G03X1522031Y899796I-242J319D01*
G37*
G36*
G01X1495012Y821444D02*
G02X1496447Y822502I1435J-444D01*
G02Y819498I0J-1502D01*
G02X1495232Y820117I0J1502D01*
G03X1494527Y820000I-323J-236D01*
G02X1493092Y818942I-1435J444D01*
G02Y821946I0J1502D01*
G02X1494307Y821327I0J-1502D01*
G03X1495012Y821444I323J236D01*
G37*
G36*
G01X1450006Y693285D02*
G02X1448991Y692890I-1015J1107D01*
G02Y695894I0J1502D01*
G02X1450333Y695066I0J-1502D01*
G03X1450961Y694951I357J180D01*
G02X1451976Y695346I1015J-1107D01*
G02Y692342I0J-1502D01*
G02X1450634Y693170I0J1502D01*
G03X1450006Y693285I-357J-180D01*
G37*
G36*
G01X1571144Y447127D02*
G02X1571526Y448049I1306J-1D01*
G01X1586321Y462843D01*
G03X1586380Y462985I-141J142D01*
G01Y465123D01*
G02X1586762Y466045I1306J-1D01*
G01X1591523Y470805D01*
G03X1591582Y470947I-141J142D01*
G01Y517376D01*
G03X1591523Y517518I-200J0D01*
G01X1588836Y520204D01*
G02X1588454Y521126I924J923D01*
G01Y566069D01*
G03X1588330Y566254I-200J0D01*
G01X1588274Y566278D01*
X1588156Y566254D01*
X1579188Y557286D01*
G02X1577557Y556610I-1632J1631D01*
G01X1575934D01*
G02X1573628Y558917I1J2307D01*
G02X1573936Y560068I2305J0D01*
G03Y560268I-173J100D01*
G02X1573628Y561419I1998J1151D01*
G01Y561420D01*
G02X1575934Y563726I2306J0D01*
G01X1576334D01*
G03X1576476Y563785I0J200D01*
G01X1583397Y570707D01*
G03X1583456Y570849I-141J142D01*
G01Y619298D01*
G03X1583397Y619440I-200J0D01*
G01X1577603Y625235D01*
G03X1577461Y625294I-142J-141D01*
G01X1576295D01*
G02X1573990Y627600I1J2306D01*
G02X1575408Y629728I2306J0D01*
G01X1575445Y629744D01*
X1575473Y629772D01*
G03Y630054I-142J141D01*
G01X1575446Y630081D01*
G02X1574770Y631712I1631J1632D01*
G02X1577077Y634018I2307J-1D01*
G01X1577078D01*
G02X1578708Y633343I0J-2306D01*
G01X1581907Y630144D01*
G03X1582049Y630085I142J141D01*
G01X1589195D01*
G03X1589337Y630144I0J200D01*
G01X1613352Y654159D01*
G03X1613401Y654363I-141J142D01*
G01X1613273Y654755D01*
X1613187Y654828D01*
X1613131Y654837D01*
G02X1611860Y656321I231J1484D01*
G02X1613362Y657823I1502J0D01*
G02X1614846Y656552I0J-1502D01*
G01X1614855Y656496D01*
X1614928Y656410D01*
X1615320Y656282D01*
G03X1615524Y656331I62J190D01*
G01X1615879Y656686D01*
G03X1615928Y656766I-141J142D01*
G01Y656767D01*
G02X1617131Y657805I1434J-446D01*
G01X1617187Y657814D01*
X1617273Y657887D01*
X1617401Y658279D01*
G03X1617352Y658483I-190J62D01*
G01X1609976Y665859D01*
G02X1609594Y666781I924J923D01*
G01Y685387D01*
G02X1609841Y686150I1306J-1D01*
G03X1609871Y686212I-162J117D01*
G02X1611316Y687302I1445J-413D01*
G02X1612818Y685800I0J-1502D01*
G02X1612278Y684646I-1503J0D01*
G03X1612206Y684493I128J-154D01*
G01Y667407D01*
G03X1612265Y667265I200J0D01*
G01X1621727Y657804D01*
G03X1621807Y657755I142J141D01*
G01X1621808D01*
G02X1622864Y656321I-446J-1434D01*
G02X1622691Y655622I-1502J1D01*
G03X1622668Y655529I177J-93D01*
G01Y647754D01*
G02X1622286Y646832I-1306J1D01*
G01X1617767Y642314D01*
G03X1617708Y642172I141J-142D01*
G01Y633741D01*
G02X1617326Y632819I-1306J1D01*
G01X1615903Y631397D01*
G03X1615844Y631255I141J-142D01*
G01Y619080D01*
G03X1615867Y618987I200J0D01*
G02X1616040Y618288I-1329J-700D01*
G02X1613036I-1502J0D01*
G02X1613209Y618987I1502J-1D01*
G03X1613232Y619080I-177J93D01*
G01Y631881D01*
G02X1613614Y632803I1306J-1D01*
G01X1615037Y634225D01*
G03X1615096Y634367I-141J142D01*
G01Y642798D01*
G02X1615478Y643720I1306J-1D01*
G01X1619997Y648238D01*
G03X1620056Y648380I-141J142D01*
G01Y655529D01*
G03X1620033Y655622I-200J0D01*
G02X1619928Y655874I1328J701D01*
G01Y655876D01*
G03X1619879Y655956I-190J-62D01*
G01X1619524Y656311D01*
G03X1619320Y656360I-142J-141D01*
G01X1618928Y656232D01*
X1618855Y656146D01*
X1618846Y656090D01*
G02X1617809Y654887I-1484J231D01*
G01X1617807D01*
G03X1617727Y654838I62J-190D01*
G01X1591125Y628237D01*
G03X1591066Y628095I141J-142D01*
G01Y537637D01*
G03X1591190Y537452I200J0D01*
G01X1591246Y537428D01*
X1591364Y537452D01*
X1594777Y540865D01*
G03X1594826Y540945I-141J142D01*
G01Y540946D01*
G02X1596260Y542002I1434J-446D01*
G02X1597762Y540500I0J-1502D01*
G02X1596707Y539066I-1502J0D01*
G01X1596705D01*
G03X1596625Y539017I62J-190D01*
G01X1593125Y535518D01*
G03X1593066Y535376I141J-142D01*
G01Y522505D01*
G03X1593125Y522363I200J0D01*
G01X1595389Y520100D01*
G02X1595772Y519176I-923J-924D01*
G01Y457741D01*
G02X1595389Y456817I-1306J0D01*
G01X1594118Y455546D01*
G03X1594069Y455466I141J-142D01*
G01Y455465D01*
G02X1592635Y454409I-1434J446D01*
G02X1591133Y455911I0J1502D01*
G02X1592188Y457345I1502J0D01*
G01X1592190D01*
G03X1592270Y457394I-62J190D01*
G01X1593099Y458223D01*
G03X1593158Y458365I-141J142D01*
G01Y463958D01*
G03X1593037Y464142I-200J0D01*
G01X1592643Y464311D01*
X1592525Y464289D01*
X1592482Y464247D01*
G02X1591443Y463830I-1039J1086D01*
G02X1590032Y464816I0J1503D01*
G01X1590015Y464864D01*
X1589938Y464932D01*
X1589559Y465015D01*
G03X1589374Y464962I-44J-195D01*
G01X1589051Y464639D01*
G03X1588992Y464497I141J-142D01*
G01Y462359D01*
G02X1588610Y461437I-1306J1D01*
G01X1573815Y446643D01*
G03X1573756Y446501I141J-142D01*
G01Y388431D01*
G03X1573815Y388289I200J0D01*
G01X1576859Y385246D01*
G02X1577242Y384322I-923J-924D01*
G01Y382899D01*
G03X1577263Y382810I200J0D01*
G01X1577264Y382808D01*
G02X1577437Y382109I-1329J-700D01*
G02X1574433I-1502J0D01*
G02X1574605Y382806I1502J-1D01*
G03X1574607Y382810I-178J91D01*
G01X1574618Y382831D01*
X1574628Y382875D01*
Y383698D01*
G03X1574569Y383840I-200J0D01*
G01X1571526Y386883D01*
G02X1571144Y387805I924J923D01*
G01Y447127D01*
G37*
G36*
G01X1425814Y619590D02*
G02X1425252Y620661I739J1071D01*
G02X1427856I1302J0D01*
G02X1427294Y619590I-1301J0D01*
G03Y618932I228J-329D01*
G02X1427856Y617861I-739J-1071D01*
G02X1425252I-1302J0D01*
G02X1425814Y618932I1301J0D01*
G03Y619590I-228J329D01*
G37*
G36*
G01X1422270D02*
G02X1421708Y620661I739J1071D01*
G02X1424312I1302J0D01*
G02X1423750Y619590I-1301J0D01*
G03Y618932I228J-329D01*
G02X1424312Y617861I-739J-1071D01*
G02X1421708I-1302J0D01*
G02X1422270Y618932I1301J0D01*
G03Y619590I-228J329D01*
G37*
G36*
G01X1418727D02*
G02X1418165Y620661I739J1071D01*
G02X1420769I1302J0D01*
G02X1420207Y619590I-1301J0D01*
G03Y618932I228J-329D01*
G02X1420769Y617861I-739J-1071D01*
G02X1418165I-1302J0D01*
G02X1418727Y618932I1301J0D01*
G03Y619590I-228J329D01*
G37*
G36*
G01X1415184D02*
G02X1414622Y620661I739J1071D01*
G02X1417226I1302J0D01*
G02X1416664Y619590I-1301J0D01*
G03Y618932I228J-329D01*
G02X1417226Y617861I-739J-1071D01*
G02X1414622I-1302J0D01*
G02X1415184Y618932I1301J0D01*
G03Y619590I-228J329D01*
G37*
G36*
G01X1445098Y576484D02*
G02X1448102I1502J0D01*
G02X1447460Y575253I-1501J0D01*
G03X1447376Y575114I114J-164D01*
G01X1447333Y574778D01*
X1447357Y574697D01*
X1447385Y574665D01*
G02X1447745Y573689I-1143J-976D01*
G02X1447024Y572406I-1502J0D01*
G01X1446980Y572379D01*
X1446929Y572291D01*
X1446921Y571849D01*
X1446968Y571759D01*
X1447011Y571731D01*
G02X1447685Y570478I-828J-1253D01*
G02X1446183Y568976I-1502J0D01*
G02X1445004Y569547I0J1503D01*
G01X1444978Y569580D01*
X1444904Y569619D01*
X1444525Y569648D01*
X1444447Y569620D01*
X1444416Y569591D01*
G02X1443388Y569184I-1028J1095D01*
G02X1441886Y570686I0J1502D01*
G02X1442387Y571806I1502J0D01*
G01X1442416Y571831D01*
X1442450Y571901D01*
X1442475Y572215D01*
G03X1442431Y572356I-199J15D01*
G02X1442095Y573303I1167J947D01*
G02X1443597Y574805I1502J0D01*
G02X1444488Y574512I0J-1501D01*
G01X1444489D01*
X1444520Y574489D01*
X1444596Y574470D01*
X1444952Y574522D01*
X1445021Y574563D01*
X1445044Y574594D01*
G02X1445383Y574920I1198J-906D01*
G03X1445467Y575059I-114J164D01*
G01X1445510Y575395D01*
X1445486Y575476D01*
X1445458Y575508D01*
G02X1445098Y576484I1143J976D01*
G37*
G36*
G01X1433843Y545847D02*
X1434137D01*
G03X1434284Y545912I-1J200D01*
G02X1435390Y546397I1106J-1019D01*
G02X1436892Y544895I0J-1502D01*
G02X1436313Y543710I-1502J0D01*
G03X1436236Y543552I123J-158D01*
G01Y543238D01*
G03X1436313Y543080I200J0D01*
G02X1436892Y541895I-923J-1185D01*
G02X1435390Y540393I-1502J0D01*
G02X1434403Y540763I0J1501D01*
G01X1434402D01*
Y540764D01*
G03X1434272Y540812I-130J-152D01*
G01X1434008D01*
G03X1433878Y540764I0J-200D01*
G01X1433877Y540763D01*
G02X1432890Y540393I-987J1131D01*
G02X1431388Y541895I0J1502D01*
G02X1431860Y542988I1502J0D01*
G01X1431861Y542989D01*
G03X1431922Y543154I-138J145D01*
G01X1431891Y543469D01*
G03X1431797Y543619I-199J-20D01*
G02X1431088Y544895I794J1276D01*
G02X1432590Y546397I1502J0D01*
G02X1433696Y545912I0J-1504D01*
G03X1433843Y545847I148J135D01*
G37*
G36*
G01X1409618Y530446D02*
G02Y533450I0J1502D01*
G02X1410842Y532819I0J-1503D01*
G01X1410869Y532780D01*
X1410953Y532736D01*
X1411321Y532728D01*
G03X1411483Y532805I4J200D01*
G02X1412668Y533384I1185J-923D01*
G02X1413655Y533014I0J-1501D01*
G01X1413656D01*
Y533013D01*
G03X1413786Y532965I130J152D01*
G01X1414050D01*
G03X1414180Y533013I0J200D01*
G01X1414181Y533014D01*
G02X1416155I987J-1131D01*
G01X1416156D01*
Y533013D01*
G03X1416286Y532965I130J152D01*
G01X1416550D01*
G03X1416680Y533013I0J200D01*
G01X1416681Y533014D01*
G02X1417668Y533384I987J-1131D01*
G02X1419170Y531882I0J-1502D01*
G02X1418903Y531027I-1502J0D01*
G01X1418880Y530993D01*
X1418863Y530912D01*
X1418943Y530545D01*
X1418991Y530478D01*
X1419026Y530457D01*
G02X1419755Y529169I-773J-1288D01*
G02X1416751I-1502J0D01*
G02X1417018Y530024I1502J0D01*
G01X1417041Y530058D01*
X1417058Y530139D01*
X1416978Y530506D01*
X1416930Y530573D01*
X1416895Y530594D01*
G02X1416682Y530750I777J1285D01*
G03X1416680Y530751I-88J-173D01*
G03X1416550Y530799I-130J-152D01*
G01X1416286D01*
G03X1416156Y530751I0J-200D01*
G01X1416155Y530750D01*
G02X1414181I-987J1131D01*
G01X1414180D01*
Y530751D01*
G03X1414050Y530799I-130J-152D01*
G01X1413786D01*
G03X1413656Y530751I0J-200D01*
G01X1413655Y530750D01*
G02X1412668Y530380I-987J1131D01*
G02X1411444Y531011I0J1503D01*
G01X1411417Y531050D01*
X1411333Y531094D01*
X1410965Y531102D01*
G03X1410803Y531025I-4J-200D01*
G02X1409618Y530446I-1185J923D01*
G37*
G36*
G01X1393155Y509780D02*
G02X1392542Y510990I888J1210D01*
G02X1395546I1502J0D01*
G02X1394854Y509725I-1502J0D01*
G03X1394833Y509066I216J-337D01*
G02X1395446Y507856I-888J-1210D01*
G02X1392442I-1502J0D01*
G02X1393134Y509121I1502J0D01*
G03X1393155Y509780I-216J337D01*
G37*
G36*
G01X1443674Y499103D02*
X1443968D01*
G03X1444115Y499168I-1J200D01*
G02X1445221Y499653I1106J-1019D01*
G02X1446723Y498151I0J-1502D01*
G02X1446144Y496966I-1502J0D01*
G03X1446067Y496808I123J-158D01*
G01Y496494D01*
G03X1446144Y496336I200J0D01*
G02X1446723Y495151I-923J-1185D01*
G02X1445221Y493649I-1502J0D01*
G02X1444234Y494019I0J1501D01*
G01X1444233D01*
Y494020D01*
G03X1444103Y494068I-130J-152D01*
G01X1443839D01*
G03X1443709Y494020I0J-200D01*
G01X1443708Y494019D01*
G02X1442721Y493649I-987J1131D01*
G02X1441219Y495151I0J1502D01*
G02X1441691Y496244I1502J0D01*
G01X1441692Y496245D01*
G03X1441753Y496410I-138J145D01*
G01X1441722Y496725D01*
G03X1441628Y496875I-199J-20D01*
G02X1440919Y498151I794J1276D01*
G02X1442421Y499653I1502J0D01*
G02X1443527Y499168I0J-1504D01*
G03X1443674Y499103I148J135D01*
G37*
G36*
G01X1425982Y462004D02*
G02X1428986I1502J0D01*
G02X1427627Y460509I-1502J0D01*
G03X1427473Y460411I19J-199D01*
G01X1427310Y460131D01*
G03X1427300Y459948I173J-101D01*
G02X1427429Y459339I-1373J-609D01*
G02X1427059Y458352I-1501J0D01*
G01Y458351D01*
X1427058D01*
G03X1427010Y458221I152J-130D01*
G01Y457957D01*
G03X1427058Y457827I200J0D01*
G01X1427059Y457826D01*
G02Y455852I-1131J-987D01*
G01Y455851D01*
X1427058D01*
G03X1427010Y455721I152J-130D01*
G01Y455457D01*
G03X1427058Y455327I200J0D01*
G01X1427059Y455326D01*
G02X1427429Y454339I-1131J-987D01*
G02X1425927Y452837I-1502J0D01*
G02X1424940Y453207I0J1501D01*
G01X1424939D01*
Y453208D01*
G03X1424809Y453256I-130J-152D01*
G01X1424545D01*
G03X1424415Y453208I0J-200D01*
G01X1424414Y453207D01*
G02X1423427Y452837I-987J1131D01*
G02X1421925Y454339I0J1502D01*
G02X1422295Y455326I1501J0D01*
G01Y455327D01*
X1422296D01*
G03X1422344Y455457I-152J130D01*
G01Y455721D01*
G03X1422296Y455851I-200J0D01*
G01X1422295Y455852D01*
G02Y457826I1131J987D01*
G01Y457827D01*
X1422296D01*
G03X1422344Y457957I-152J130D01*
G01Y458221D01*
G03X1422296Y458351I-200J0D01*
G01X1422295Y458352D01*
G02X1421925Y459339I1131J987D01*
G02X1423427Y460841I1502J0D01*
G02X1424414Y460471I0J-1501D01*
G01X1424415D01*
Y460470D01*
G03X1424545Y460422I130J152D01*
G01X1424809D01*
G03X1424939Y460470I0J200D01*
G01X1424940Y460471D01*
G02X1425784Y460834I987J-1132D01*
G03X1425938Y460932I-19J199D01*
G01X1426101Y461212D01*
G03X1426111Y461395I-173J101D01*
G02X1425982Y462004I1373J609D01*
G37*
G36*
G01X1397740Y398341D02*
X1397768Y398302D01*
X1397851Y398259D01*
X1398219Y398255D01*
G03X1398380Y398333I2J200D01*
G02X1399571Y398920I1191J-915D01*
G02Y395916I0J-1502D01*
G02X1398359Y396531I0J1502D01*
G01X1398331Y396570D01*
X1398248Y396613D01*
X1397880Y396617D01*
G03X1397719Y396539I-2J-200D01*
G02X1396528Y395952I-1191J915D01*
G02X1395408Y396453I0J1502D01*
G01X1395407Y396454D01*
G03X1395249Y396519I-148J-135D01*
G01X1394893Y396502D01*
X1394814Y396460D01*
X1394787Y396423D01*
G02X1393575Y395808I-1212J887D01*
G02X1392344Y396450I0J1501D01*
G01X1392317Y396488D01*
X1392235Y396533D01*
X1391870Y396548D01*
G03X1391709Y396477I-8J-200D01*
G01X1391708Y396476D01*
G02X1390553Y395934I-1155J960D01*
G02Y398938I0J1502D01*
G02X1391784Y398296I0J-1501D01*
G01X1391811Y398258D01*
X1391893Y398213D01*
X1392258Y398198D01*
G03X1392419Y398269I8J200D01*
G01X1392420Y398270D01*
G02X1393575Y398812I1155J-960D01*
G02X1394695Y398311I0J-1502D01*
G01X1394696Y398310D01*
G03X1394854Y398245I148J135D01*
G01X1395210Y398262D01*
X1395289Y398304D01*
X1395316Y398341D01*
G02X1397740I1212J-887D01*
G37*
G36*
G01X1461136Y390891D02*
G02X1459873Y390203I-1263J815D01*
G02Y393207I0J1502D01*
G02X1461194Y392419I0J-1501D01*
G03X1461882Y392393I352J190D01*
G02X1463145Y393081I1263J-815D01*
G02Y390077I0J-1502D01*
G02X1461824Y390865I0J1501D01*
G03X1461136Y390891I-352J-190D01*
G37*
G36*
G01X1383086Y351440D02*
G02X1382763Y352371I1180J931D01*
G02X1385767I1502J0D01*
G02X1384844Y350985I-1502J0D01*
G03X1384684Y350368I154J-369D01*
G02X1385007Y349437I-1180J-931D01*
G02X1382003I-1502J0D01*
G02X1382926Y350823I1502J0D01*
G03X1383086Y351440I-154J369D01*
G37*
G36*
G01X1572868Y343287D02*
G02X1571625Y342629I-1243J845D01*
G02Y345633I0J1502D01*
G02X1572870Y344971I0J-1502D01*
G03X1573532I331J224D01*
G02X1574775Y345629I1243J-845D01*
G02Y342625I0J-1502D01*
G02X1573530Y343287I0J1502D01*
G03X1572868I-331J-224D01*
G37*
G36*
G01X1447979Y331612D02*
G02X1447232Y332910I754J1298D01*
G02X1450236I1502J0D01*
G02X1449747Y331801I-1502J0D01*
G03X1449815Y331159I269J-296D01*
G02X1450562Y329861I-754J-1298D01*
G02X1447558I-1502J0D01*
G02X1448047Y330970I1502J0D01*
G03X1447979Y331612I-269J296D01*
G37*
G36*
G01X1392777Y148717D02*
G02X1395781I1502J0D01*
G02X1394776Y147300I-1501J0D01*
G03X1394656Y147183I67J-188D01*
G01X1394530Y146857D01*
X1394536Y146770D01*
X1394557Y146731D01*
G02X1394740Y146013I-1319J-719D01*
G01Y146012D01*
G02X1394080Y144768I-1502J0D01*
G03X1393992Y144603I112J-166D01*
G01Y144271D01*
G03X1394080Y144106I200J1D01*
G02X1394725Y143074I-842J-1244D01*
G01Y143073D01*
G03X1394793Y142950I198J29D01*
G01X1394993Y142778D01*
G03X1395126Y142730I130J152D01*
G01X1395144D01*
G02Y139726I0J-1502D01*
G02X1393657Y141016I0J1502D01*
G01Y141017D01*
G03X1393589Y141140I-198J-29D01*
G01X1393389Y141312D01*
G03X1393256Y141360I-130J-152D01*
G01X1393238D01*
G02X1391736Y142862I0J1502D01*
G02X1392396Y144106I1502J0D01*
G03X1392484Y144271I-112J166D01*
G01Y144603D01*
G03X1392396Y144768I-200J-1D01*
G02X1391736Y146012I842J1244D01*
G02X1392741Y147429I1501J0D01*
G03X1392861Y147546I-67J188D01*
G01X1392987Y147872D01*
X1392981Y147959D01*
X1392960Y147998D01*
G02X1392777Y148716I1319J719D01*
G01Y148717D01*
G37*
G36*
G01X1392840Y110018D02*
X1393154D01*
G03X1393312Y110095I0J200D01*
G02X1394497Y110674I1185J-923D01*
G02X1395999Y109172I0J-1502D01*
G02X1395036Y107770I-1502J0D01*
G01X1395034D01*
X1394994Y107754D01*
X1394935Y107694D01*
X1394800Y107330D01*
X1394806Y107245D01*
X1394827Y107207D01*
G02X1395006Y106497I-1323J-711D01*
G01Y106495D01*
G02X1392002I-1502J0D01*
G02X1392140Y107123I1502J-1D01*
G01Y107124D01*
G03X1392119Y107327I-182J84D01*
G01X1391874Y107653D01*
X1391773Y107694D01*
X1391718Y107686D01*
G02X1391497Y107670I-219J1486D01*
G02Y110674I0J1502D01*
G02X1392682Y110095I0J-1502D01*
G03X1392840Y110018I158J123D01*
G37*
G36*
G01X1404965Y106561D02*
G02X1407969I1502J0D01*
G02X1407243Y105275I-1502J0D01*
G03X1407147Y105114I104J-171D01*
G01X1407129Y104782D01*
G03X1407209Y104612I200J-10D01*
G02X1407764Y103779I-901J-1202D01*
G03X1407889Y103641I194J50D01*
G01X1408198Y103526D01*
G03X1408382Y103550I69J188D01*
G02X1409248Y103825I866J-1226D01*
G02Y100821I0J-1502D01*
G02X1407792Y101955I0J1502D01*
G03X1407667Y102093I-194J-50D01*
G01X1407358Y102208D01*
G03X1407174Y102184I-69J-188D01*
G02X1406308Y101909I-866J1226D01*
G02X1404806Y103411I0J1502D01*
G02X1405532Y104697I1502J0D01*
G03X1405628Y104858I-104J171D01*
G01X1405646Y105190D01*
G03X1405566Y105360I-200J10D01*
G02X1404965Y106561I901J1202D01*
G37*
G36*
G01X1461877Y102731D02*
G02X1461585Y103621I1210J890D01*
G02X1464589I1502J0D01*
G02X1463364Y102145I-1502J0D01*
G03X1463115Y101515I73J-393D01*
G02X1463407Y100625I-1210J-890D01*
G02X1460403I-1502J0D01*
G02X1461628Y102101I1502J0D01*
G03X1461877Y102731I-73J393D01*
G37*
G36*
G01X1426305Y101849D02*
G02X1425722Y103037I919J1188D01*
G02X1428726I1502J0D01*
G02X1428070Y101796I-1502J0D01*
G03X1428050Y101149I225J-331D01*
G02X1428633Y99961I-919J-1188D01*
G02X1425629I-1502J0D01*
G02X1426285Y101202I1502J0D01*
G03X1426305Y101849I-225J331D01*
G37*
G36*
G01X1420818Y91453D02*
G02X1420264Y91347I-554J1395D01*
G02X1421766Y92849I0J1502D01*
G02X1421720Y92481I-1502J1D01*
G03X1422256Y92011I388J-98D01*
G02X1422810Y92117I554J-1395D01*
G02X1421308Y90615I0J-1502D01*
G02X1421354Y90983I1502J-1D01*
G03X1420818Y91453I-388J98D01*
G37*
G36*
G01X1471657Y90701D02*
G02X1470987Y91951I831J1250D01*
G02X1473991I1502J0D01*
G02X1473341Y90714I-1502J0D01*
G03X1473346Y90051I227J-330D01*
G02X1474016Y88801I-831J-1250D01*
G02X1471012I-1502J0D01*
G02X1471662Y90038I1502J0D01*
G03X1471657Y90701I-227J330D01*
G37*
G36*
G01X1383066Y217133D02*
X1382772D01*
G03X1382625Y217068I1J-200D01*
G02X1381519Y216583I-1106J1019D01*
G02Y219587I0J1502D01*
G02X1382625Y219102I0J-1504D01*
G03X1382772Y219037I148J135D01*
G01X1383066D01*
G03X1383213Y219102I-1J200D01*
G02X1384319Y219587I1106J-1019D01*
G02Y216583I0J-1502D01*
G02X1383213Y217068I0J1504D01*
G03X1383066Y217133I-148J-135D01*
G37*
G36*
G01X1387828Y205336D02*
G02Y208340I0J1502D01*
G02X1388815Y207970I0J-1501D01*
G01X1388816D01*
Y207969D01*
G03X1388946Y207921I130J152D01*
G01X1389210D01*
G03X1389340Y207969I0J200D01*
G01X1389341Y207970D01*
G02X1390328Y208340I987J-1131D01*
G02Y205336I0J-1502D01*
G02X1389341Y205706I0J1501D01*
G01X1389340D01*
Y205707D01*
G03X1389210Y205755I-130J-152D01*
G01X1388946D01*
G03X1388816Y205707I0J-200D01*
G01X1388815Y205706D01*
G02X1387828Y205336I-987J1131D01*
G37*
G36*
G01X1381640Y201891D02*
G02Y204895I0J1502D01*
G02X1382627Y204525I0J-1501D01*
G01X1382628D01*
Y204524D01*
G03X1382758Y204476I130J152D01*
G01X1383022D01*
G03X1383152Y204524I0J200D01*
G01X1383153Y204525D01*
G02X1384140Y204895I987J-1131D01*
G02X1385637Y203517I0J-1502D01*
G01X1385640Y203474D01*
X1385681Y203400D01*
X1385953Y203194D01*
G03X1386112Y203157I121J159D01*
G02X1386399Y203185I289J-1474D01*
G02X1387901Y201683I0J-1502D01*
G02X1387416Y200577I-1504J0D01*
G03X1387351Y200430I135J-148D01*
G01Y200136D01*
G03X1387416Y199989I200J1D01*
G02X1387901Y198883I-1019J-1106D01*
G02X1384897I-1502J0D01*
G02X1385382Y199989I1504J0D01*
G03X1385447Y200136I-135J148D01*
G01Y200430D01*
G03X1385382Y200577I-200J-1D01*
G02X1384902Y201559I1017J1105D01*
G01X1384899Y201602D01*
X1384858Y201676D01*
X1384586Y201882D01*
G03X1384427Y201919I-121J-159D01*
G02X1384140Y201891I-289J1474D01*
G02X1383153Y202261I0J1501D01*
G01X1383152D01*
Y202262D01*
G03X1383022Y202310I-130J-152D01*
G01X1382758D01*
G03X1382628Y202262I0J-200D01*
G01X1382627Y202261D01*
G02X1381640Y201891I-987J1131D01*
G37*
G36*
G01X1386780Y196678D02*
G02X1387886Y196193I0J-1504D01*
G03X1388033Y196128I148J135D01*
G01X1388327D01*
G03X1388474Y196193I-1J200D01*
G02X1389580Y196678I1106J-1019D01*
G02Y193674I0J-1502D01*
G02X1388474Y194159I0J1504D01*
G03X1388327Y194224I-148J-135D01*
G01X1388033D01*
G03X1387886Y194159I1J-200D01*
G02X1386780Y193674I-1106J1019D01*
G02X1385793Y194044I0J1501D01*
G01X1385792D01*
Y194045D01*
G03X1385662Y194093I-130J-152D01*
G01X1385398D01*
G03X1385268Y194045I0J-200D01*
G01X1385267Y194044D01*
G02X1383293I-987J1131D01*
G01X1383292D01*
Y194045D01*
G03X1383162Y194093I-130J-152D01*
G01X1382898D01*
G03X1382768Y194045I0J-200D01*
G01X1382767Y194044D01*
G02X1381780Y193674I-987J1131D01*
G02Y196678I0J1502D01*
G02X1382767Y196308I0J-1501D01*
G01X1382768D01*
Y196307D01*
G03X1382898Y196259I130J152D01*
G01X1383162D01*
G03X1383292Y196307I0J200D01*
G01X1383293Y196308D01*
G02X1385267I987J-1131D01*
G01X1385268D01*
Y196307D01*
G03X1385398Y196259I130J152D01*
G01X1385662D01*
G03X1385792Y196307I0J200D01*
G01X1385793Y196308D01*
G02X1386780Y196678I987J-1131D01*
G37*
G36*
G01X1406948Y123626D02*
G02X1406523Y123677I1J1802D01*
G01X1406520D01*
G03X1406364Y123649I-46J-195D01*
G01X1406083Y123462D01*
X1406038Y123392D01*
X1406032Y123350D01*
G02X1404548Y122081I-1484J233D01*
G01X1404547D01*
G02X1403560Y122451I0J1502D01*
G01X1403533Y122475D01*
X1403465Y122501D01*
X1403129D01*
X1403062Y122476D01*
X1403035Y122452D01*
G02X1402048Y122082I-987J1131D01*
G02X1401780Y122106I-1J1502D01*
G03X1401614Y122060I-35J-197D01*
G01X1401518Y121977D01*
G03X1401448Y121817I130J-152D01*
G02X1401450Y121743I-1800J-86D01*
G01Y118342D01*
G02X1401448Y118263I-1802J6D01*
G03X1401517Y118104I200J-8D01*
G01X1401614Y118020D01*
G03X1401781Y117975I130J152D01*
G02X1402048Y117999I267J-1478D01*
G02X1403035Y117629I0J-1501D01*
G01X1403036D01*
Y117628D01*
G03X1403166Y117580I130J152D01*
G01X1403430D01*
G03X1403560Y117628I0J200D01*
G01X1403561Y117629D01*
G02X1404548Y117999I987J-1131D01*
G02X1406031Y116732I0J-1501D01*
G01X1406038Y116690D01*
X1406082Y116621D01*
X1406398Y116411D01*
X1406481Y116396D01*
X1406521Y116406D01*
G02X1406948Y116458I430J-1751D01*
G02X1407296Y116424I0J-1803D01*
G01X1407336Y116416D01*
X1407415Y116432D01*
X1407718Y116642D01*
X1407760Y116708D01*
X1407767Y116749D01*
G02X1409248Y117998I1481J-254D01*
G02Y114994I0J-1502D01*
G01X1409245D01*
G02X1409067Y115005I3J1502D01*
G03X1408909Y114954I-23J-199D01*
G01X1408815Y114869D01*
G03X1408749Y114715I134J-149D01*
G02X1408750Y114655I-1801J-60D01*
G01Y111255D01*
G02X1408749Y111192I-1802J-3D01*
G03X1408814Y111038I200J-6D01*
G01X1408909Y110952D01*
G03X1409067Y110901I135J148D01*
G02X1409245Y110912I181J-1491D01*
G01X1409248D01*
G02Y107908I0J-1502D01*
G02X1407767Y109160I0J1502D01*
G03X1407683Y109292I-197J-33D01*
G01X1407414Y109478D01*
X1407335Y109494D01*
X1407295Y109486D01*
G02X1406948Y109452I-348J1769D01*
G02X1406523Y109504I5J1802D01*
G01X1406520D01*
G03X1406364Y109476I-46J-195D01*
G01X1406083Y109289D01*
X1406038Y109219D01*
X1406032Y109177D01*
G02X1404548Y107908I-1484J233D01*
G02Y110912I0J1502D01*
G02X1404815Y110888I0J-1502D01*
G03X1404982Y110933I37J197D01*
G01X1405079Y111017D01*
G03X1405148Y111176I-131J151D01*
G02X1405146Y111255I1800J85D01*
G01Y114656D01*
G02X1405148Y114730I1802J-12D01*
G03X1405078Y114890I-200J8D01*
G01X1404982Y114973D01*
G03X1404816Y115019I-131J-151D01*
G02X1404548Y114995I-267J1478D01*
G02X1403561Y115365I0J1501D01*
G01X1403560D01*
Y115366D01*
G03X1403430Y115414I-130J-152D01*
G01X1403166D01*
G03X1403036Y115366I0J-200D01*
G01X1403035Y115365D01*
G02X1402048Y114995I-987J1131D01*
G02X1400564Y116264I0J1502D01*
G01X1400558Y116306D01*
X1400513Y116376D01*
X1400232Y116563D01*
G03X1400076Y116591I-110J-167D01*
G01X1400074D01*
G02X1399648Y116540I-426J1751D01*
G02X1399223Y116591I1J1802D01*
G01X1399220D01*
G03X1399064Y116563I-46J-195D01*
G01X1398783Y116376D01*
X1398738Y116306D01*
X1398732Y116264D01*
G02X1397248Y114995I-1484J233D01*
G02Y117999I0J1502D01*
G02X1397515Y117975I0J-1502D01*
G03X1397682Y118020I37J197D01*
G01X1397779Y118104D01*
G03X1397848Y118263I-131J151D01*
G02X1397846Y118342I1800J85D01*
G01Y121743D01*
G02X1397848Y121817I1802J-12D01*
G03X1397778Y121977I-200J8D01*
G01X1397682Y122060D01*
G03X1397516Y122106I-131J-151D01*
G02X1397248Y122082I-267J1478D01*
G02Y125086I0J1502D01*
G02X1398731Y123819I0J-1501D01*
G01X1398738Y123777D01*
X1398782Y123708D01*
X1399098Y123498D01*
X1399181Y123483D01*
X1399221Y123493D01*
G02X1399648Y123544I426J-1751D01*
G02X1400075Y123493I1J-1802D01*
G01X1400115Y123483D01*
X1400198Y123498D01*
X1400479Y123685D01*
G03X1400565Y123819I-111J166D01*
G02X1402048Y125086I1483J-234D01*
G01X1402049D01*
G02X1403036Y124716I0J-1502D01*
G01X1403063Y124692D01*
X1403131Y124666D01*
X1403467D01*
X1403534Y124691D01*
X1403561Y124715D01*
G02X1404548Y125085I987J-1131D01*
G02X1404815Y125061I0J-1502D01*
G03X1404982Y125106I37J197D01*
G01X1405079Y125190D01*
G03X1405148Y125349I-131J151D01*
G02X1405146Y125428I1800J85D01*
G01Y128829D01*
G02X1405148Y128903I1802J-12D01*
G03X1405078Y129063I-200J8D01*
G01X1404982Y129146D01*
G03X1404816Y129192I-131J-151D01*
G02X1404548Y129168I-267J1478D01*
G02X1403561Y129538I0J1501D01*
G01X1403560D01*
Y129539D01*
G03X1403430Y129587I-130J-152D01*
G01X1403166D01*
G03X1403036Y129539I0J-200D01*
G01X1403035Y129538D01*
G02X1402048Y129168I-987J1131D01*
G02X1400564Y130437I0J1502D01*
G01X1400558Y130479D01*
X1400513Y130549D01*
X1400232Y130736D01*
G03X1400076Y130764I-110J-167D01*
G01X1400074D01*
G02X1399648Y130712I-430J1751D01*
G02X1399223Y130764I5J1802D01*
G01X1399220D01*
G03X1399064Y130736I-46J-195D01*
G01X1398783Y130549D01*
X1398738Y130479D01*
X1398732Y130437D01*
G02X1397248Y129168I-1484J233D01*
G02Y132172I0J1502D01*
G02X1397515Y132148I0J-1502D01*
G03X1397682Y132193I37J197D01*
G01X1397779Y132277D01*
G03X1397848Y132436I-131J151D01*
G02X1397846Y132515I1800J85D01*
G01Y135916D01*
G02X1397848Y135990I1802J-12D01*
G03X1397778Y136150I-200J8D01*
G01X1397682Y136233D01*
G03X1397516Y136279I-131J-151D01*
G02X1397248Y136255I-267J1478D01*
G02Y139259I0J1502D01*
G02X1398731Y137992I0J-1501D01*
G01X1398738Y137950D01*
X1398782Y137881D01*
X1399098Y137671D01*
X1399181Y137656D01*
X1399221Y137666D01*
G02X1399648Y137718I430J-1751D01*
G02X1400075Y137666I-3J-1803D01*
G01X1400115Y137656D01*
X1400198Y137671D01*
X1400479Y137858D01*
G03X1400565Y137992I-111J166D01*
G02X1402048Y139259I1483J-234D01*
G02Y136255I0J-1502D01*
G02X1401780Y136279I-1J1502D01*
G03X1401614Y136233I-35J-197D01*
G01X1401518Y136150D01*
G03X1401448Y135990I130J-152D01*
G02X1401450Y135916I-1800J-86D01*
G01Y132515D01*
G02X1401448Y132436I-1802J6D01*
G03X1401517Y132277I200J-8D01*
G01X1401614Y132193D01*
G03X1401781Y132148I130J152D01*
G02X1402048Y132172I267J-1478D01*
G02X1403035Y131802I0J-1501D01*
G01X1403036D01*
Y131801D01*
G03X1403166Y131753I130J152D01*
G01X1403430D01*
G03X1403560Y131801I0J200D01*
G01X1403561Y131802D01*
G02X1404548Y132172I987J-1131D01*
G02X1406031Y130905I0J-1501D01*
G01X1406038Y130863D01*
X1406082Y130794D01*
X1406398Y130584D01*
X1406481Y130569D01*
X1406521Y130579D01*
G02X1406948Y130630I426J-1751D01*
G02X1407296Y130597I5J-1802D01*
G01X1407336Y130589D01*
X1407415Y130605D01*
X1407718Y130815D01*
X1407760Y130881D01*
X1407767Y130922D01*
G02X1409248Y132172I1481J-252D01*
G02Y129168I0J-1502D01*
G01X1409245D01*
G02X1409067Y129179I3J1502D01*
G03X1408909Y129128I-23J-199D01*
G01X1408815Y129043D01*
G03X1408749Y128889I134J-149D01*
G02X1408750Y128828I-1801J-60D01*
G01Y125428D01*
G02X1408749Y125365I-1802J-3D01*
G03X1408814Y125211I200J-6D01*
G01X1408909Y125125D01*
G03X1409067Y125074I135J148D01*
G02X1409245Y125085I181J-1491D01*
G01X1409248D01*
G02Y122081I0J-1502D01*
G02X1407767Y123333I0J1502D01*
G03X1407683Y123465I-197J-33D01*
G01X1407414Y123651D01*
X1407335Y123667D01*
X1407295Y123659D01*
G02X1406948Y123626I-343J1769D01*
G37*
G36*
G01X1416208Y85584D02*
G02X1419212I1502J0D01*
G02X1418806Y84557I-1502J0D01*
G01X1418780Y84530D01*
X1418752Y84459D01*
Y84109D01*
X1418780Y84038D01*
X1418806Y84011D01*
G02Y81957I-1096J-1027D01*
G01X1418780Y81930D01*
X1418752Y81859D01*
Y81509D01*
X1418780Y81438D01*
X1418806Y81411D01*
G02Y79357I-1096J-1027D01*
G01X1418780Y79330D01*
X1418752Y79259D01*
Y78909D01*
X1418780Y78838D01*
X1418806Y78811D01*
G02Y76757I-1096J-1027D01*
G01X1418780Y76730D01*
X1418752Y76659D01*
Y76309D01*
X1418780Y76238D01*
X1418806Y76211D01*
G02X1419212Y75184I-1096J-1027D01*
G02X1416208I-1502J0D01*
G02X1416614Y76211I1502J0D01*
G01X1416640Y76238D01*
X1416668Y76309D01*
Y76659D01*
X1416640Y76730D01*
X1416614Y76757D01*
G02Y78811I1096J1027D01*
G01X1416640Y78838D01*
X1416668Y78909D01*
Y79259D01*
X1416640Y79330D01*
X1416614Y79357D01*
G02Y81411I1096J1027D01*
G01X1416640Y81438D01*
X1416668Y81509D01*
Y81859D01*
X1416640Y81930D01*
X1416614Y81957D01*
G02Y84011I1096J1027D01*
G01X1416640Y84038D01*
X1416668Y84109D01*
Y84459D01*
X1416640Y84530D01*
X1416614Y84557D01*
G02X1416208Y85584I1096J1027D01*
G37*
G36*
G01X1434543Y85193D02*
G02X1437547I1502J0D01*
G02X1437141Y84166I-1502J0D01*
G01X1437115Y84139D01*
X1437087Y84068D01*
Y83718D01*
X1437115Y83647D01*
X1437141Y83620D01*
G02Y81566I-1096J-1027D01*
G01X1437115Y81539D01*
X1437087Y81468D01*
Y81118D01*
X1437115Y81047D01*
X1437141Y81020D01*
G02Y78966I-1096J-1027D01*
G01X1437115Y78939D01*
X1437087Y78868D01*
Y78518D01*
X1437115Y78447D01*
X1437141Y78420D01*
G02Y76366I-1096J-1027D01*
G01X1437115Y76339D01*
X1437087Y76268D01*
Y75918D01*
X1437115Y75847D01*
X1437141Y75820D01*
G02X1437547Y74793I-1096J-1027D01*
G02X1434543I-1502J0D01*
G02X1434949Y75820I1502J0D01*
G01X1434975Y75847D01*
X1435003Y75918D01*
Y76268D01*
X1434975Y76339D01*
X1434949Y76366D01*
G02Y78420I1096J1027D01*
G01X1434975Y78447D01*
X1435003Y78518D01*
Y78868D01*
X1434975Y78939D01*
X1434949Y78966D01*
G02Y81020I1096J1027D01*
G01X1434975Y81047D01*
X1435003Y81118D01*
Y81468D01*
X1434975Y81539D01*
X1434949Y81566D01*
G02Y83620I1096J1027D01*
G01X1434975Y83647D01*
X1435003Y83718D01*
Y84068D01*
X1434975Y84139D01*
X1434949Y84166D01*
G02X1434543Y85193I1096J1027D01*
G37*
G36*
G01X1457718Y74638D02*
G02Y77642I0J1502D01*
G01X1457719D01*
G02X1458639Y77327I0J-1502D01*
G03X1458794Y77287I123J157D01*
G01X1459082Y77334D01*
G03X1459216Y77420I-32J197D01*
G01X1459217Y77421D01*
G02X1460466Y78089I1249J-834D01*
G02Y75085I0J-1502D01*
G01X1460465D01*
G02X1459545Y75400I0J1502D01*
G03X1459390Y75440I-123J-157D01*
G01X1459102Y75393D01*
G03X1458968Y75307I32J-197D01*
G01X1458967Y75306D01*
G02X1457718Y74638I-1249J834D01*
G37*
G36*
G01X1391288Y236121D02*
G02X1394292I1502J0D01*
G02X1393642Y234884I-1502J0D01*
G03X1393648Y234222I227J-329D01*
G02X1394318Y232971I-833J-1251D01*
G02X1391314I-1502J0D01*
G02X1391964Y234208I1502J0D01*
G03X1391958Y234870I-227J329D01*
G02X1391288Y236121I833J1251D01*
G37*
G36*
G01X1389330Y221970D02*
G02X1392334I1502J0D01*
G02X1391964Y220983I-1501J0D01*
G01Y220982D01*
X1391963D01*
G03X1391915Y220852I152J-130D01*
G01Y220588D01*
G03X1391963Y220458I200J0D01*
G01X1391964Y220457D01*
G02Y218483I-1131J-987D01*
G01Y218482D01*
X1391963D01*
G03X1391915Y218352I152J-130D01*
G01Y218088D01*
G03X1391963Y217958I200J0D01*
G01X1391964Y217957D01*
G02X1392334Y216970I-1131J-987D01*
G02X1390832Y215468I-1502J0D01*
G02X1389977Y215735I0J1502D01*
G01X1389943Y215758D01*
X1389862Y215775D01*
X1389495Y215695D01*
X1389428Y215647D01*
X1389407Y215612D01*
G02X1388119Y214883I-1288J773D01*
G02Y217887I0J1502D01*
G02X1388974Y217620I0J-1502D01*
G01X1389008Y217597D01*
X1389089Y217580D01*
X1389456Y217660D01*
X1389523Y217708D01*
X1389544Y217743D01*
G02X1389700Y217956I1285J-777D01*
G03X1389701Y217958I-173J88D01*
G03X1389749Y218088I-152J130D01*
G01Y218352D01*
G03X1389701Y218482I-200J0D01*
G01X1389700Y218483D01*
G02Y220457I1131J987D01*
G01Y220458D01*
X1389701D01*
G03X1389749Y220588I-152J130D01*
G01Y220852D01*
G03X1389701Y220982I-200J0D01*
G01X1389700Y220983D01*
G02X1389330Y221970I1131J987D01*
G37*
G36*
G01X1447028Y223294D02*
Y223630D01*
X1447003Y223697D01*
X1446979Y223725D01*
G02X1446609Y224712I1131J987D01*
G02X1449613I1502J0D01*
G02X1449243Y223725I-1501J0D01*
G01X1449219Y223697D01*
X1449194Y223630D01*
Y223294D01*
X1449219Y223227D01*
X1449243Y223199D01*
G02X1449613Y222212I-1131J-987D01*
G02X1446609I-1502J0D01*
G02X1446979Y223199I1501J0D01*
G01X1447003Y223227D01*
X1447028Y223294D01*
G37*
G36*
G01X1441703Y225189D02*
X1441409D01*
G03X1441262Y225124I1J-200D01*
G02X1440156Y224639I-1105J1017D01*
G02Y227643I0J1502D01*
G02X1441262Y227158I1J-1502D01*
G03X1441409Y227093I148J135D01*
G01X1441703D01*
G03X1441850Y227158I-1J200D01*
G02X1442956Y227643I1105J-1017D01*
G02Y224639I0J-1502D01*
G02X1441850Y225124I-1J1502D01*
G03X1441703Y225189I-148J-135D01*
G37*
G36*
G01X1424910Y229808D02*
Y230144D01*
X1424885Y230211D01*
X1424861Y230239D01*
G02X1424491Y231226I1131J987D01*
G02X1427495I1502J0D01*
G02X1427125Y230239I-1501J0D01*
G01X1427101Y230211D01*
X1427076Y230144D01*
Y229808D01*
X1427101Y229741D01*
X1427125Y229713D01*
G02Y227739I-1131J-987D01*
G01X1427101Y227711D01*
X1427076Y227644D01*
Y227308D01*
X1427101Y227241D01*
X1427125Y227213D01*
G02Y225239I-1131J-987D01*
G01X1427101Y225211D01*
X1427076Y225144D01*
Y224808D01*
X1427101Y224741D01*
X1427125Y224713D01*
G02X1427495Y223726I-1131J-987D01*
G02X1424491I-1502J0D01*
G02X1424861Y224713I1501J0D01*
G01X1424885Y224741D01*
X1424910Y224808D01*
Y225144D01*
X1424885Y225211D01*
X1424861Y225239D01*
G02Y227213I1131J987D01*
G01X1424885Y227241D01*
X1424910Y227308D01*
Y227644D01*
X1424885Y227711D01*
X1424861Y227739D01*
G02Y229713I1131J987D01*
G01X1424885Y229741D01*
X1424910Y229808D01*
G37*
G36*
G01X1435366Y230043D02*
Y230379D01*
X1435341Y230446D01*
X1435317Y230474D01*
G02X1434947Y231461I1131J987D01*
G02X1437951I1502J0D01*
G02X1437581Y230474I-1501J0D01*
G01X1437557Y230446D01*
X1437532Y230379D01*
Y230043D01*
X1437557Y229976D01*
X1437581Y229948D01*
G02Y227974I-1131J-987D01*
G01X1437557Y227946D01*
X1437532Y227879D01*
Y227543D01*
X1437557Y227476D01*
X1437581Y227448D01*
G02X1437951Y226461I-1131J-987D01*
G02X1437466Y225355I-1502J-1D01*
G03X1437401Y225208I135J-148D01*
G01Y224914D01*
G03X1437466Y224767I200J1D01*
G02X1437951Y223661I-1017J-1105D01*
G02X1434947I-1502J0D01*
G02X1435432Y224767I1502J1D01*
G03X1435497Y224914I-135J148D01*
G01Y225208D01*
G03X1435432Y225355I-200J-1D01*
G02X1434947Y226461I1017J1105D01*
G02X1435317Y227448I1501J0D01*
G01X1435341Y227476D01*
X1435366Y227543D01*
Y227879D01*
X1435341Y227946D01*
X1435317Y227974D01*
G02Y229948I1131J987D01*
G01X1435341Y229976D01*
X1435366Y230043D01*
G37*
G36*
G01X1443335Y230368D02*
Y230704D01*
X1443310Y230771D01*
X1443286Y230799D01*
G02X1442916Y231786I1131J987D01*
G02X1445920I1502J0D01*
G02X1445550Y230799I-1501J0D01*
G01X1445526Y230771D01*
X1445501Y230704D01*
Y230368D01*
X1445526Y230301D01*
X1445550Y230273D01*
G02X1445920Y229286I-1131J-987D01*
G02X1442916I-1502J0D01*
G02X1443286Y230273I1501J0D01*
G01X1443310Y230301D01*
X1443335Y230368D01*
G37*
G36*
G01X1441481Y237694D02*
X1441817D01*
X1441884Y237719D01*
X1441912Y237743D01*
G02X1443886I987J-1131D01*
G01X1443914Y237719D01*
X1443981Y237694D01*
X1444317D01*
X1444384Y237719D01*
X1444412Y237743D01*
G02X1445399Y238113I987J-1131D01*
G02Y235109I0J-1502D01*
G02X1444412Y235479I0J1501D01*
G01X1444384Y235503D01*
X1444317Y235528D01*
X1443981D01*
X1443914Y235503D01*
X1443886Y235479D01*
G02X1441912I-987J1131D01*
G01X1441884Y235503D01*
X1441817Y235528D01*
X1441481D01*
X1441414Y235503D01*
X1441386Y235479D01*
G02X1440399Y235109I-987J1131D01*
G02Y238113I0J1502D01*
G02X1441386Y237743I0J-1501D01*
G01X1441414Y237719D01*
X1441481Y237694D01*
G37*
G36*
G01X1441183Y249974D02*
X1441519D01*
X1441586Y249999D01*
X1441614Y250023D01*
G02X1443588I987J-1131D01*
G01X1443616Y249999D01*
X1443683Y249974D01*
X1444019D01*
X1444086Y249999D01*
X1444114Y250023D01*
G02X1445101Y250393I987J-1131D01*
G02Y247389I0J-1502D01*
G02X1444114Y247759I0J1501D01*
G01X1444086Y247783D01*
X1444019Y247808D01*
X1443683D01*
X1443616Y247783D01*
X1443588Y247759D01*
G02X1441614I-987J1131D01*
G01X1441586Y247783D01*
X1441519Y247808D01*
X1441183D01*
X1441116Y247783D01*
X1441088Y247759D01*
G02X1440101Y247389I-987J1131D01*
G02Y250393I0J1502D01*
G02X1441088Y250023I0J-1501D01*
G01X1441116Y249999D01*
X1441183Y249974D01*
G37*
G36*
G01X1445478Y190705D02*
G02X1444830Y191941I855J1236D01*
G02X1447834I1502J0D01*
G02X1447081Y190639I-1502J0D01*
G03X1447053Y189963I199J-347D01*
G02X1447701Y188727I-855J-1236D01*
G02X1444697I-1502J0D01*
G02X1445450Y190029I1502J0D01*
G03X1445478Y190705I-199J347D01*
G37*
G36*
G01X1469521Y185330D02*
X1469656Y185710D01*
X1469646Y185800D01*
X1469622Y185839D01*
G02X1469397Y186629I1277J791D01*
G02X1472401I1502J0D01*
G02X1471398Y185212I-1502J0D01*
G01X1471354Y185197D01*
X1471291Y185133D01*
X1471156Y184753D01*
X1471166Y184663D01*
X1471190Y184624D01*
G02X1471415Y183834I-1277J-791D01*
G02X1468411I-1502J0D01*
G02X1469414Y185251I1502J0D01*
G01X1469458Y185266D01*
X1469521Y185330D01*
G37*
G36*
G01X1439891Y872319D02*
G02Y875323I0J1502D01*
G02X1441172Y874606I0J-1503D01*
G03X1441834Y874577I341J209D01*
G02X1443041Y875185I1207J-894D01*
G02Y872181I0J-1502D01*
G02X1441760Y872898I0J1503D01*
G03X1441098Y872927I-341J-209D01*
G02X1439891Y872319I-1207J894D01*
G37*
G36*
G01X1461771Y876674D02*
G02X1461192Y877859I923J1185D01*
G02X1464196I1502J0D01*
G02X1463617Y876674I-1502J0D01*
G03X1463540Y876516I123J-158D01*
G01Y876202D01*
G03X1463617Y876044I200J0D01*
G02X1464196Y874859I-923J-1185D01*
G02X1461192I-1502J0D01*
G02X1461771Y876044I1502J0D01*
G03X1461848Y876202I-123J158D01*
G01Y876516D01*
G03X1461771Y876674I-200J0D01*
G37*
G36*
G01X1480140Y913288D02*
G02X1478841Y914776I203J1488D01*
G02X1481845I1502J0D01*
G02X1481423Y913732I-1502J0D01*
G03X1481657Y913058I288J-278D01*
G02X1482956Y911570I-203J-1488D01*
G02X1479952I-1502J0D01*
G02X1480374Y912614I1502J0D01*
G03X1480140Y913288I-288J278D01*
G37*
G36*
G01X1472169Y921417D02*
G03X1472831I331J224D01*
G02X1474075Y922077I1244J-842D01*
G02Y919073I0J-1502D01*
G02X1472831Y919733I0J1502D01*
G03X1472169I-331J-224D01*
G02X1470925Y919073I-1244J842D01*
G02Y922077I0J1502D01*
G02X1472169Y921417I0J-1502D01*
G37*
G36*
G01X1484066Y932947D02*
G02X1485500Y934002I1434J-447D01*
G02Y930998I0J-1502D01*
G01X1485498D01*
G02X1484897Y931124I1J1502D01*
G01X1484857Y931142D01*
X1484773Y931141D01*
X1484462Y930999D01*
G03X1484355Y930877I84J-182D01*
G02X1482921Y929822I-1434J447D01*
G02Y932826I0J1502D01*
G01X1482923D01*
G02X1483524Y932700I-1J-1502D01*
G01X1483564Y932682D01*
X1483648Y932683D01*
X1483959Y932825D01*
G03X1484066Y932947I-84J182D01*
G37*
G36*
G01X1427553Y937698D02*
G02X1429055Y939200I0J1502D01*
G02X1429027Y938913I-1502J2D01*
G03X1429522Y938450I393J-76D01*
G02X1429906Y938500I384J-1452D01*
G01X1429907D01*
G02X1428405Y936998I0J-1502D01*
G02X1428433Y937285I1502J-2D01*
G03X1427938Y937748I-393J76D01*
G02X1427554Y937698I-384J1452D01*
G01X1427553D01*
G37*
G36*
G01X1479444Y945551D02*
G02X1478642Y946880I700J1329D01*
G02X1481646I1502J0D01*
G02X1480816Y945537I-1502J0D01*
G03X1480809Y944825I179J-358D01*
G02X1481611Y943496I-700J-1329D01*
G02X1478607I-1502J0D01*
G02X1479437Y944839I1502J0D01*
G03X1479444Y945551I-179J358D01*
G37*
G36*
G01X1485334Y946053D02*
G02X1484998Y947000I1167J947D01*
G02X1488002I1502J0D01*
G02X1486560Y945499I-1502J0D01*
G03X1486266Y944847I16J-400D01*
G02X1486602Y943900I-1167J-947D01*
G02X1483598I-1502J0D01*
G02X1485040Y945401I1502J0D01*
G03X1485334Y946053I-16J400D01*
G37*
G36*
G01X1461309Y959044D02*
G02X1460498Y960378I692J1334D01*
G02X1463502I1502J0D01*
G02X1462691Y959044I-1503J0D01*
G03Y958334I184J-355D01*
G02X1463502Y957000I-692J-1334D01*
G02X1460498I-1502J0D01*
G02X1461309Y958334I1503J0D01*
G03Y959044I-184J355D01*
G37*
G36*
G01X1427473Y964119D02*
G02Y967123I0J1502D01*
G02X1428818Y966290I0J-1502D01*
G03X1429525Y966274I358J179D01*
G02X1430839Y967048I1314J-728D01*
G02Y964044I0J-1502D01*
G02X1429494Y964877I0J1502D01*
G03X1428787Y964893I-358J-179D01*
G02X1427473Y964119I-1314J728D01*
G37*
G36*
G01X1524514Y972903D02*
X1524464Y972922D01*
G02X1523503Y974323I541J1401D01*
G02X1526507I1502J0D01*
G02X1525955Y973159I-1502J-1D01*
G01X1525913Y973125D01*
X1525875Y973026D01*
X1525947Y972578D01*
X1526013Y972495D01*
X1526063Y972476D01*
G02X1527024Y971075I-541J-1401D01*
G02X1526651Y970084I-1503J0D01*
G01X1526626Y970056D01*
X1526601Y969986D01*
X1526609Y969639D01*
X1526638Y969570D01*
X1526664Y969543D01*
G02X1527085Y968500I-1081J-1043D01*
G02X1524081I-1502J0D01*
G02X1524454Y969491I1503J0D01*
G01X1524479Y969519D01*
X1524504Y969589D01*
X1524496Y969936D01*
X1524467Y970005D01*
X1524441Y970032D01*
G02X1524020Y971075I1081J1043D01*
G02X1524572Y972239I1502J1D01*
G01X1524614Y972273D01*
X1524652Y972372D01*
X1524580Y972820D01*
X1524514Y972903D01*
G37*
G36*
G01X1439399Y981011D02*
X1439377Y981052D01*
G02X1439198Y981763I1323J711D01*
G02X1442202I1502J0D01*
G02X1441035Y980299I-1502J0D01*
G01X1440989Y980288D01*
X1440917Y980229D01*
X1440747Y979854D01*
X1440750Y979761D01*
X1440772Y979720D01*
G02X1440951Y979009I-1323J-711D01*
G01Y979008D01*
G02X1440845Y978454I-1502J0D01*
G01X1440827Y978409D01*
X1440836Y978315D01*
X1441033Y978001D01*
G03X1441189Y977908I169J107D01*
G02X1442590Y976409I-101J-1499D01*
G02X1439586I-1502J0D01*
G01Y976410D01*
G02X1439692Y976964I1502J0D01*
G01X1439710Y977009D01*
X1439701Y977103D01*
X1439504Y977417D01*
G03X1439348Y977510I-169J-107D01*
G02X1437947Y979009I101J1499D01*
G02X1439114Y980473I1502J0D01*
G01X1439160Y980484D01*
X1439232Y980543D01*
X1439402Y980918D01*
X1439399Y981011D01*
G37*
G36*
G01X1531299Y1178719D02*
G02X1532501Y1179921I0J1202D01*
G02X1532480Y1179699I-1202J2D01*
G01X1532471Y1179650D01*
X1532500Y1179557D01*
X1532805Y1179252D01*
X1532898Y1179223D01*
X1532947Y1179232D01*
G02X1533169Y1179253I224J-1181D01*
G02X1534371Y1178051I0J-1202D01*
G02X1534350Y1177828I-1202J1D01*
G01X1534341Y1177779D01*
X1534370Y1177686D01*
X1534639Y1177416D01*
G03X1534816Y1177361I141J142D01*
G01X1534817D01*
G02X1535039Y1177382I224J-1181D01*
G02X1536241Y1176180I0J-1202D01*
G02X1536220Y1175958I-1202J2D01*
G01X1536211Y1175909D01*
X1536240Y1175816D01*
X1536545Y1175511D01*
X1536638Y1175482D01*
X1536687Y1175491D01*
G02X1536909Y1175512I224J-1181D01*
G02X1535707Y1174310I0J-1202D01*
G02X1535728Y1174532I1202J-2D01*
G01X1535737Y1174581D01*
X1535708Y1174674D01*
X1535403Y1174979D01*
X1535310Y1175008D01*
X1535261Y1174999D01*
G02X1535039Y1174978I-224J1181D01*
G02X1534817Y1174999I2J1202D01*
G01X1534768Y1175008D01*
X1534675Y1174979D01*
X1534370Y1174674D01*
X1534341Y1174581D01*
X1534350Y1174532D01*
G02X1534371Y1174310I-1181J-224D01*
G02X1531967I-1202J0D01*
G02X1531976Y1174452I1202J-5D01*
G01Y1174454D01*
X1531981Y1174500D01*
X1531949Y1174588D01*
X1531649Y1174875D01*
X1531559Y1174903D01*
X1531513Y1174895D01*
G02X1531299Y1174878I-210J1285D01*
G01X1531022D01*
G03X1530873Y1174812I0J-200D01*
G01X1530646Y1174558D01*
X1530620Y1174478D01*
X1530624Y1174436D01*
G02X1530631Y1174310I-1195J-130D01*
G02X1528227I-1202J0D01*
G02X1528234Y1174435I1202J-5D01*
G01Y1174437D01*
X1528238Y1174478D01*
X1528212Y1174558D01*
X1527985Y1174812D01*
G03X1527836Y1174878I-149J-134D01*
G01X1527559D01*
G02X1527345Y1174895I-4J1302D01*
G01X1527299Y1174903D01*
X1527209Y1174875D01*
X1526942Y1174620D01*
G03X1526882Y1174454I139J-144D01*
G01Y1174453D01*
G02X1526891Y1174310I-1193J-147D01*
G02X1525689Y1175512I-1202J0D01*
G02X1525831Y1175503I-5J-1202D01*
G01X1525833D01*
X1525879Y1175498D01*
X1525967Y1175530D01*
X1526254Y1175830D01*
X1526282Y1175920D01*
X1526274Y1175966D01*
G02X1526256Y1176180I1285J216D01*
G02X1527559Y1177482I1303J-1D01*
G01X1531299D01*
G02X1531513Y1177465I4J-1302D01*
G01X1531560Y1177457D01*
X1531650Y1177485D01*
X1531950Y1177772D01*
X1531982Y1177860D01*
X1531976Y1177907D01*
G02X1531967Y1178051I1193J147D01*
G02X1531988Y1178273I1202J-2D01*
G01X1531997Y1178322D01*
X1531968Y1178415D01*
X1531663Y1178720D01*
X1531570Y1178749D01*
X1531521Y1178740D01*
G02X1531299Y1178719I-224J1181D01*
G37*
G36*
G01X1541317Y1183661D02*
G02X1543721I1202J0D01*
G02X1543700Y1183439I-1202J2D01*
G01X1543691Y1183390D01*
X1543720Y1183297D01*
X1544025Y1182992D01*
X1544118Y1182963D01*
X1544167Y1182972D01*
G02X1544389Y1182993I224J-1181D01*
G02X1543187Y1181791I0J-1202D01*
G02X1543208Y1182013I1202J-2D01*
G01X1543217Y1182062D01*
X1543188Y1182155D01*
X1542883Y1182460D01*
X1542790Y1182489D01*
X1542741Y1182480D01*
G02X1542519Y1182459I-224J1181D01*
G02X1542297Y1182480I2J1202D01*
G01X1542248Y1182489D01*
X1542155Y1182460D01*
X1541850Y1182155D01*
X1541821Y1182062D01*
X1541830Y1182013D01*
G02X1541851Y1181791I-1181J-224D01*
G02X1540649Y1180589I-1202J0D01*
G02X1540427Y1180610I2J1202D01*
G01X1540378Y1180619D01*
X1540285Y1180590D01*
X1539980Y1180285D01*
X1539951Y1180192D01*
X1539960Y1180143D01*
G02X1539981Y1179921I-1181J-224D01*
G02X1539960Y1179698I-1202J1D01*
G01X1539951Y1179649D01*
X1539980Y1179556D01*
X1540249Y1179286D01*
G03X1540426Y1179231I141J142D01*
G01X1540427D01*
G02X1540649Y1179252I224J-1181D01*
G02X1539447Y1178050I0J-1202D01*
G02X1539468Y1178273I1202J-1D01*
G01X1539477Y1178322D01*
X1539448Y1178415D01*
X1539179Y1178685D01*
G03X1539002Y1178740I-141J-142D01*
G01X1539001D01*
G02X1538779Y1178719I-224J1181D01*
G02Y1181123I0J1202D01*
G02X1539001Y1181102I-2J-1202D01*
G01X1539050Y1181093D01*
X1539143Y1181122D01*
X1539448Y1181427D01*
X1539477Y1181520D01*
X1539468Y1181569D01*
G02X1539447Y1181791I1181J224D01*
G02X1539468Y1182013I1202J-2D01*
G01X1539477Y1182062D01*
X1539448Y1182155D01*
X1539143Y1182460D01*
X1539050Y1182489D01*
X1539001Y1182480D01*
G02X1538779Y1182459I-224J1181D01*
G02X1539981Y1183661I0J1202D01*
G02X1539960Y1183439I-1202J2D01*
G01X1539951Y1183390D01*
X1539980Y1183297D01*
X1540285Y1182992D01*
X1540378Y1182963D01*
X1540427Y1182972D01*
G02X1540649Y1182993I224J-1181D01*
G02X1540871Y1182972I-2J-1202D01*
G01X1540920Y1182963D01*
X1541013Y1182992D01*
X1541318Y1183297D01*
X1541347Y1183390D01*
X1541338Y1183439D01*
G02X1541317Y1183661I1181J224D01*
G37*
G36*
G01X1669907Y1193700D02*
G02X1669685Y1193679I-224J1181D01*
G02X1670887Y1194881I0J1202D01*
G02X1670866Y1194659I-1202J2D01*
G03X1671333Y1194192I393J-74D01*
G02X1671555Y1194213I224J-1181D01*
G02X1670353Y1193011I0J-1202D01*
G02X1670374Y1193233I1202J-2D01*
G03X1669907Y1193700I-393J74D01*
G37*
G36*
G01X1664658Y1206102D02*
G02X1665946Y1204814I1287J-1D01*
G01X1665944D01*
G02X1665730Y1204833I6J1288D01*
G03X1665557Y1204780I-34J-197D01*
G01X1665326Y1204557D01*
G03X1665266Y1204387I138J-144D01*
G02X1665276Y1204233I-1192J-155D01*
G01Y1204232D01*
G02X1665255Y1204011I-1202J3D01*
G01Y1204009D01*
G03X1665310Y1203832I197J-36D01*
G01X1665580Y1203563D01*
X1665673Y1203534D01*
X1665722Y1203543D01*
G02X1665945Y1203564I224J-1181D01*
G02X1664743Y1202362I0J-1202D01*
G02X1664764Y1202583I1202J-3D01*
G01Y1202585D01*
G03X1664709Y1202762I-197J36D01*
G01X1664439Y1203031D01*
X1664346Y1203060D01*
X1664297Y1203051D01*
G02X1664074Y1203030I-224J1181D01*
G02Y1205434I0J1202D01*
G01X1664075D01*
G02X1664229Y1205424I-1J-1202D01*
G03X1664399Y1205484I26J198D01*
G01X1664623Y1205716D01*
G03X1664676Y1205887I-144J138D01*
G02X1664658Y1206101I1269J214D01*
G01Y1206102D01*
G37*
G36*
G01X1553962Y1216141D02*
G02X1553740Y1216120I-224J1181D01*
G02X1554942Y1217322I0J1202D01*
G02X1554921Y1217100I-1202J2D01*
G03X1555388Y1216633I393J-74D01*
G02X1555610Y1216654I224J-1181D01*
G02X1554408Y1215452I0J-1202D01*
G02X1554429Y1215674I1202J-2D01*
G03X1553962Y1216141I-393J74D01*
G37*
G36*
G01X1612380Y1217322D02*
G02X1614784I1202J0D01*
G02X1614763Y1217100I-1202J2D01*
G01X1614754Y1217051D01*
X1614783Y1216958D01*
X1615088Y1216653D01*
X1615181Y1216624D01*
X1615230Y1216633D01*
G02X1615452Y1216654I224J-1181D01*
G02X1614250Y1215452I0J-1202D01*
G02X1614271Y1215674I1202J-2D01*
G01X1614280Y1215723D01*
X1614251Y1215816D01*
X1613946Y1216121D01*
X1613853Y1216150D01*
X1613804Y1216141D01*
G02X1613582Y1216120I-224J1181D01*
G02X1613360Y1216141I2J1202D01*
G01X1613311Y1216150D01*
X1613218Y1216121D01*
X1612913Y1215816D01*
X1612884Y1215723D01*
X1612893Y1215674D01*
G02X1612914Y1215452I-1181J-224D01*
G02X1610510I-1202J0D01*
G02X1610531Y1215674I1202J-2D01*
G01X1610540Y1215723D01*
X1610511Y1215816D01*
X1610206Y1216121D01*
X1610113Y1216150D01*
X1610064Y1216141D01*
G02X1609842Y1216120I-224J1181D01*
G02X1609620Y1216141I2J1202D01*
G01X1609571Y1216150D01*
X1609478Y1216121D01*
X1609173Y1215816D01*
X1609144Y1215723D01*
X1609153Y1215674D01*
G02X1609174Y1215452I-1181J-224D01*
G02X1607972Y1216654I-1202J0D01*
G02X1608194Y1216633I-2J-1202D01*
G01X1608243Y1216624D01*
X1608336Y1216653D01*
X1608641Y1216958D01*
X1608670Y1217051D01*
X1608661Y1217100D01*
G02X1608640Y1217322I1181J224D01*
G02X1611044I1202J0D01*
G02X1611023Y1217100I-1202J2D01*
G01X1611014Y1217051D01*
X1611043Y1216958D01*
X1611348Y1216653D01*
X1611441Y1216624D01*
X1611490Y1216633D01*
G02X1611712Y1216654I224J-1181D01*
G02X1611934Y1216633I-2J-1202D01*
G01X1611983Y1216624D01*
X1612076Y1216653D01*
X1612381Y1216958D01*
X1612410Y1217051D01*
X1612401Y1217100D01*
G02X1612380Y1217322I1181J224D01*
G37*
G36*
G01X1567498Y1221062D02*
G02X1568700Y1219860I1202J0D01*
G02X1568478Y1219881I2J1202D01*
G01X1568429Y1219890D01*
X1568336Y1219861D01*
X1568031Y1219556D01*
X1568002Y1219463D01*
X1568011Y1219414D01*
G02X1568032Y1219192I-1181J-224D01*
G02X1565628I-1202J0D01*
G02X1565649Y1219414I1202J-2D01*
G01X1565658Y1219463D01*
X1565629Y1219556D01*
X1565324Y1219861D01*
X1565231Y1219890D01*
X1565182Y1219881D01*
G02X1564960Y1219860I-224J1181D01*
G02X1564738Y1219881I2J1202D01*
G01X1564689Y1219890D01*
X1564596Y1219861D01*
X1564291Y1219556D01*
X1564262Y1219463D01*
X1564271Y1219414D01*
G02X1564292Y1219192I-1181J-224D01*
G02X1561888I-1202J0D01*
G02X1561909Y1219414I1202J-2D01*
G01X1561918Y1219463D01*
X1561889Y1219556D01*
X1561584Y1219861D01*
X1561491Y1219890D01*
X1561442Y1219881D01*
G02X1561220Y1219860I-224J1181D01*
G02X1562422Y1221062I0J1202D01*
G02X1562401Y1220840I-1202J2D01*
G01X1562392Y1220791D01*
X1562421Y1220698D01*
X1562726Y1220393D01*
X1562819Y1220364D01*
X1562868Y1220373D01*
G02X1563090Y1220394I224J-1181D01*
G02X1563312Y1220373I-2J-1202D01*
G01X1563361Y1220364D01*
X1563454Y1220393D01*
X1563759Y1220698D01*
X1563788Y1220791D01*
X1563779Y1220840D01*
G02X1563758Y1221062I1181J224D01*
G02X1566162I1202J0D01*
G02X1566141Y1220840I-1202J2D01*
G01X1566132Y1220791D01*
X1566161Y1220698D01*
X1566466Y1220393D01*
X1566559Y1220364D01*
X1566608Y1220373D01*
G02X1566830Y1220394I224J-1181D01*
G02X1567052Y1220373I-2J-1202D01*
G01X1567101Y1220364D01*
X1567194Y1220393D01*
X1567499Y1220698D01*
X1567528Y1220791D01*
X1567519Y1220840D01*
G02X1567498Y1221062I1181J224D01*
G37*
G36*
G01X1597420D02*
G02X1598622Y1219860I1202J0D01*
G02X1598400Y1219881I2J1202D01*
G01X1598351Y1219890D01*
X1598258Y1219861D01*
X1597953Y1219556D01*
X1597924Y1219463D01*
X1597933Y1219414D01*
G02X1597954Y1219192I-1181J-224D01*
G02X1595550I-1202J0D01*
G02X1595571Y1219414I1202J-2D01*
G01X1595580Y1219463D01*
X1595551Y1219556D01*
X1595246Y1219861D01*
X1595153Y1219890D01*
X1595104Y1219881D01*
G02X1594882Y1219860I-224J1181D01*
G02X1594659Y1219881I1J1202D01*
G01X1594610Y1219890D01*
X1594517Y1219861D01*
X1594247Y1219592D01*
G03X1594192Y1219415I142J-141D01*
G01Y1219414D01*
G02X1594213Y1219192I-1181J-224D01*
G02X1593011Y1217990I-1202J0D01*
G02X1592789Y1218011I2J1202D01*
G01X1592740Y1218020D01*
X1592647Y1217991D01*
X1592342Y1217686D01*
X1592313Y1217593D01*
X1592322Y1217544D01*
G02X1592343Y1217322I-1181J-224D01*
G02X1592322Y1217101I-1202J3D01*
G01Y1217099D01*
G03X1592377Y1216922I197J-36D01*
G01X1592647Y1216653D01*
X1592740Y1216624D01*
X1592789Y1216633D01*
G02X1593012Y1216654I224J-1181D01*
G02X1591810Y1215452I0J-1202D01*
G02X1591831Y1215673I1202J-3D01*
G01Y1215675D01*
G03X1591776Y1215852I-197J36D01*
G01X1591506Y1216121D01*
X1591413Y1216150D01*
X1591364Y1216141D01*
G02X1591141Y1216120I-224J1181D01*
G02X1590919Y1216141I2J1202D01*
G01X1590870Y1216150D01*
X1590777Y1216121D01*
X1590472Y1215816D01*
X1590443Y1215723D01*
X1590452Y1215674D01*
G02X1590473Y1215452I-1181J-224D01*
G02X1589271Y1216654I-1202J0D01*
G02X1589493Y1216633I-2J-1202D01*
G01X1589542Y1216624D01*
X1589635Y1216653D01*
X1589940Y1216958D01*
X1589969Y1217051D01*
X1589960Y1217100D01*
G02X1589939Y1217322I1181J224D01*
G02X1591141Y1218524I1202J0D01*
G02X1591363Y1218503I-2J-1202D01*
G01X1591412Y1218494D01*
X1591505Y1218523D01*
X1591810Y1218828D01*
X1591839Y1218921D01*
X1591830Y1218970D01*
G02X1591809Y1219192I1181J224D01*
G02X1591830Y1219414I1202J-2D01*
G01X1591839Y1219463D01*
X1591810Y1219556D01*
X1591505Y1219861D01*
X1591412Y1219890D01*
X1591363Y1219881D01*
G02X1591141Y1219860I-224J1181D01*
G02X1592343Y1221062I0J1202D01*
G02X1592322Y1220840I-1202J2D01*
G01X1592313Y1220791D01*
X1592342Y1220698D01*
X1592647Y1220393D01*
X1592740Y1220364D01*
X1592789Y1220373D01*
G02X1593011Y1220394I224J-1181D01*
G02X1593234Y1220373I-1J-1202D01*
G01X1593283Y1220364D01*
X1593376Y1220393D01*
X1593646Y1220662D01*
G03X1593701Y1220839I-142J141D01*
G01Y1220840D01*
G02X1593680Y1221062I1181J224D01*
G02X1596084I1202J0D01*
G02X1596063Y1220840I-1202J2D01*
G01X1596054Y1220791D01*
X1596083Y1220698D01*
X1596388Y1220393D01*
X1596481Y1220364D01*
X1596530Y1220373D01*
G02X1596752Y1220394I224J-1181D01*
G02X1596974Y1220373I-2J-1202D01*
G01X1597023Y1220364D01*
X1597116Y1220393D01*
X1597421Y1220698D01*
X1597450Y1220791D01*
X1597441Y1220840D01*
G02X1597420Y1221062I1181J224D01*
G37*
G36*
G01X1640320Y1134362D02*
X1639206D01*
G02X1638883Y1134404I0J1265D01*
G03X1638872Y1134406I-41J-196D01*
G03X1638698Y1134062I-40J-196D01*
G02X1639095Y1133169I-806J-893D01*
G02X1636691I-1202J0D01*
G02X1637088Y1134062I1203J0D01*
G03X1636914Y1134406I-134J148D01*
G03X1636903Y1134404I30J-198D01*
G02X1636580Y1134362I-323J1223D01*
G01X1635466D01*
G02X1635143Y1134404I0J1265D01*
G03X1635132Y1134406I-41J-196D01*
G03X1634958Y1134062I-40J-196D01*
G02X1635355Y1133169I-806J-893D01*
G02X1632951I-1202J0D01*
G02X1633348Y1134062I1203J0D01*
G03X1633174Y1134406I-134J148D01*
G03X1633163Y1134404I30J-198D01*
G02X1632840Y1134362I-323J1223D01*
G01X1631726D01*
G02X1631403Y1134404I0J1265D01*
G03X1631392Y1134406I-41J-196D01*
G03X1631218Y1134062I-40J-196D01*
G02X1631615Y1133169I-806J-893D01*
G02X1629211I-1202J0D01*
G02X1629608Y1134062I1203J0D01*
G03X1629434Y1134406I-134J148D01*
G03X1629423Y1134404I30J-198D01*
G02X1629100Y1134362I-323J1223D01*
G01X1627986D01*
G02X1627663Y1134404I0J1265D01*
G03X1627652Y1134406I-41J-196D01*
G03X1627478Y1134062I-40J-196D01*
G02X1627875Y1133169I-806J-893D01*
G02X1625471I-1202J0D01*
G02X1625868Y1134062I1203J0D01*
G03X1625694Y1134406I-134J148D01*
G03X1625683Y1134404I30J-198D01*
G02X1625360Y1134362I-323J1223D01*
G01X1624246D01*
G02X1623923Y1134404I0J1265D01*
G03X1623912Y1134406I-41J-196D01*
G03X1623738Y1134062I-40J-196D01*
G02X1624135Y1133169I-806J-893D01*
G02X1621731I-1202J0D01*
G02X1622128Y1134062I1203J0D01*
G03X1621954Y1134406I-134J148D01*
G03X1621943Y1134404I30J-198D01*
G02X1621620Y1134362I-323J1223D01*
G01X1620506D01*
G02X1620183Y1134404I0J1265D01*
G03X1620172Y1134406I-41J-196D01*
G03X1619998Y1134062I-40J-196D01*
G02X1620395Y1133169I-806J-893D01*
G02X1617991I-1202J0D01*
G02X1618388Y1134062I1203J0D01*
G03X1618214Y1134406I-134J148D01*
G03X1618203Y1134404I30J-198D01*
G02X1617880Y1134362I-323J1223D01*
G01X1616765D01*
G02X1616442Y1134404I0J1265D01*
G03X1616431Y1134406I-41J-196D01*
G03X1616257Y1134062I-40J-196D01*
G02X1616654Y1133169I-806J-893D01*
G02X1614250I-1202J0D01*
G02X1614647Y1134062I1203J0D01*
G03X1614473Y1134406I-134J148D01*
G03X1614462Y1134404I30J-198D01*
G02X1614139Y1134362I-323J1223D01*
G01X1613025D01*
G02X1612702Y1134404I0J1265D01*
G03X1612691Y1134406I-41J-196D01*
G03X1612517Y1134062I-40J-196D01*
G02X1612914Y1133169I-806J-893D01*
G02X1610510I-1202J0D01*
G02X1610907Y1134062I1203J0D01*
G03X1610733Y1134406I-134J148D01*
G03X1610722Y1134404I30J-198D01*
G02X1610399Y1134362I-323J1223D01*
G01X1609286D01*
G02X1609200Y1134365I1J1265D01*
G03X1609161Y1134364I-14J-200D01*
G03X1609013Y1134065I25J-199D01*
G02X1609174Y1133465I-1040J-601D01*
G01Y1133464D01*
G02X1606770I-1202J0D01*
G01Y1133465D01*
G02X1606931Y1134065I1201J-1D01*
G03X1606783Y1134364I-173J100D01*
G03X1606744Y1134365I-25J-199D01*
G02X1606658Y1134362I-87J1262D01*
G01X1601806D01*
G02X1600808Y1134850I0J1265D01*
G03X1600650Y1134927I-158J-123D01*
G01X1600334D01*
G03X1600176Y1134850I0J-200D01*
G02X1599178Y1134362I-998J777D01*
G01X1598065D01*
G02X1597742Y1134404I0J1265D01*
G03X1597731Y1134406I-41J-196D01*
G03X1597557Y1134062I-40J-196D01*
G02X1597954Y1133169I-806J-893D01*
G02X1595550I-1202J0D01*
G02X1595947Y1134062I1203J0D01*
G03X1595773Y1134406I-134J148D01*
G03X1595762Y1134404I30J-198D01*
G02X1595439Y1134362I-323J1223D01*
G01X1594324D01*
G02X1594001Y1134404I0J1265D01*
G03X1593990Y1134406I-41J-196D01*
G03X1593816Y1134062I-40J-196D01*
G02X1594213Y1133169I-806J-893D01*
G02X1591809I-1202J0D01*
G02X1592206Y1134062I1203J0D01*
G03X1592032Y1134406I-134J148D01*
G03X1592021Y1134404I30J-198D01*
G02X1591698Y1134362I-323J1223D01*
G01X1590584D01*
G02X1590261Y1134404I0J1265D01*
G03X1590250Y1134406I-41J-196D01*
G03X1590076Y1134062I-40J-196D01*
G02X1590473Y1133169I-806J-893D01*
G02X1588069I-1202J0D01*
G02X1588466Y1134062I1203J0D01*
G03X1588292Y1134406I-134J148D01*
G03X1588281Y1134404I30J-198D01*
G02X1587958Y1134362I-323J1223D01*
G01X1586844D01*
G02X1586521Y1134404I0J1265D01*
G03X1586510Y1134406I-41J-196D01*
G03X1586336Y1134062I-40J-196D01*
G02X1586733Y1133169I-806J-893D01*
G02X1584329I-1202J0D01*
G02X1584726Y1134062I1203J0D01*
G03X1584552Y1134406I-134J148D01*
G03X1584541Y1134404I30J-198D01*
G02X1584218Y1134362I-323J1223D01*
G01X1583104D01*
G02X1582781Y1134404I0J1265D01*
G03X1582770Y1134406I-41J-196D01*
G03X1582596Y1134062I-40J-196D01*
G02X1582993Y1133169I-806J-893D01*
G02X1580589I-1202J0D01*
G02X1580986Y1134062I1203J0D01*
G03X1580812Y1134406I-134J148D01*
G03X1580801Y1134404I30J-198D01*
G02X1580478Y1134362I-323J1223D01*
G01X1579364D01*
G02X1579041Y1134404I0J1265D01*
G03X1579030Y1134406I-41J-196D01*
G03X1578856Y1134062I-40J-196D01*
G02X1579253Y1133169I-806J-893D01*
G02X1576849I-1202J0D01*
G02X1577246Y1134062I1203J0D01*
G03X1577072Y1134406I-134J148D01*
G03X1577061Y1134404I30J-198D01*
G02X1576738Y1134362I-323J1223D01*
G01X1575624D01*
G02X1575301Y1134404I0J1265D01*
G03X1575290Y1134406I-41J-196D01*
G03X1575116Y1134062I-40J-196D01*
G02X1575513Y1133169I-806J-893D01*
G02X1573109I-1202J0D01*
G02X1573506Y1134062I1203J0D01*
G03X1573332Y1134406I-134J148D01*
G03X1573321Y1134404I30J-198D01*
G02X1572998Y1134362I-323J1223D01*
G01X1571884D01*
G02X1571561Y1134404I0J1265D01*
G03X1571550Y1134406I-41J-196D01*
G03X1571376Y1134062I-40J-196D01*
G02X1571773Y1133169I-806J-893D01*
G02X1569369I-1202J0D01*
G02X1569766Y1134062I1203J0D01*
G03X1569592Y1134406I-134J148D01*
G03X1569581Y1134404I30J-198D01*
G02X1569258Y1134362I-323J1223D01*
G01X1568435D01*
G02X1567540Y1134733I0J1265D01*
G01X1566866Y1135407D01*
G02X1566808Y1135533I142J142D01*
G01Y1135541D01*
G03X1566640Y1135723I-199J-16D01*
G02X1565644Y1136719I190J1186D01*
G03X1565462Y1136887I-198J-31D01*
G01X1565454D01*
G02X1565328Y1136945I16J200D01*
G01X1564080Y1138193D01*
X1564036Y1138208D01*
G02X1563301Y1138850I400J1200D01*
G01X1563269Y1138915D01*
G03X1563090Y1139026I-179J-89D01*
G01X1563033D01*
X1562936Y1138966D01*
X1562879Y1138850D01*
G02X1561745Y1138142I-1136J558D01*
G01X1560695D01*
G02X1560257Y1138221I2J1266D01*
G03X1560068Y1137873I-70J-187D01*
G02X1560552Y1136909I-718J-964D01*
G02X1558148I-1202J0D01*
G02X1558632Y1137873I1202J0D01*
G03X1558443Y1138221I-119J161D01*
G02X1558005Y1138142I-440J1187D01*
G01X1556955D01*
G02X1556517Y1138221I2J1266D01*
G03X1556328Y1137873I-70J-187D01*
G02X1556812Y1136909I-718J-964D01*
G02X1554408I-1202J0D01*
G02X1554892Y1137873I1202J0D01*
G03X1554703Y1138221I-119J161D01*
G02X1554265Y1138142I-440J1187D01*
G01X1553215D01*
G02X1552777Y1138221I2J1266D01*
G03X1552588Y1137873I-70J-187D01*
G02X1553072Y1136909I-718J-964D01*
G02X1550668I-1202J0D01*
G02X1551152Y1137873I1202J0D01*
G03X1550963Y1138221I-119J161D01*
G02X1550525Y1138142I-440J1187D01*
G01X1549475D01*
G02X1549037Y1138221I2J1266D01*
G03X1548848Y1137873I-70J-187D01*
G02X1549332Y1136909I-718J-964D01*
G02X1546928I-1202J0D01*
G02X1547412Y1137873I1202J0D01*
G03X1547223Y1138221I-119J161D01*
G02X1546785Y1138142I-440J1187D01*
G01X1545734D01*
G02X1545296Y1138221I2J1266D01*
G03X1545107Y1137873I-70J-187D01*
G02X1545591Y1136909I-718J-964D01*
G02X1543187I-1202J0D01*
G02X1543671Y1137873I1202J0D01*
G03X1543482Y1138221I-119J161D01*
G02X1543044Y1138142I-440J1187D01*
G01X1542017D01*
G03X1541843Y1138040I0J-200D01*
G01X1541672Y1137736D01*
G03X1541676Y1137534I175J-98D01*
G02X1541851Y1136909I-1029J-625D01*
G02X1539447I-1202J0D01*
G02X1540585Y1138109I1202J0D01*
G03X1540727Y1138439I-10J200D01*
G03X1540706Y1138459I-148J-134D01*
G02X1540648Y1138514I841J945D01*
G01X1540628Y1138534D01*
G02X1540259Y1139384I896J894D01*
G03X1540143Y1139558I-200J-7D01*
G02X1539447Y1140649I507J1091D01*
G02X1539908Y1141598I1207J0D01*
G03X1539984Y1141755I-124J157D01*
G01Y1142267D01*
G03X1539969Y1142342I-200J-1D01*
G01X1539941Y1142412D01*
G02X1539926Y1142487I185J76D01*
G01Y1142988D01*
G02X1539955Y1143261I1265J4D01*
G03X1539887Y1143459I-195J44D01*
G02Y1145319I762J930D01*
G03X1539955Y1145517I-127J154D01*
G02X1539926Y1145790I1236J269D01*
G01Y1146728D01*
G02X1539955Y1147001I1265J4D01*
G03X1539887Y1147199I-195J44D01*
G02Y1149059I762J930D01*
G03X1539955Y1149257I-127J154D01*
G02X1539926Y1149530I1236J269D01*
G01Y1150469D01*
G02X1539955Y1150742I1265J4D01*
G03X1539887Y1150940I-195J44D01*
G02Y1152800I762J930D01*
G03X1539955Y1152998I-127J154D01*
G02X1539926Y1153271I1236J269D01*
G01Y1154302D01*
G03X1539841Y1154465I-200J-1D01*
G02Y1156755I807J1145D01*
G03X1539926Y1156918I-115J164D01*
G01Y1157949D01*
G02X1539955Y1158222I1265J4D01*
G03X1539887Y1158420I-195J44D01*
G02Y1160280I762J930D01*
G03X1539955Y1160478I-127J154D01*
G02X1539926Y1160751I1236J269D01*
G01Y1169098D01*
G02X1539968Y1169422I1265J1D01*
G03X1539900Y1169629I-193J51D01*
G02X1539447Y1170570I751J941D01*
G02X1540649Y1171772I1202J0D01*
G02X1541474Y1171444I0J-1202D01*
G01X1541475Y1171443D01*
G03X1541753Y1171448I136J146D01*
G01X1541799Y1171494D01*
G02X1542397Y1171830I896J-894D01*
G01X1542658Y1171892D01*
G02X1542753Y1171891I45J-195D01*
G01X1543259Y1171763D01*
G02X1543344Y1171718I-48J-194D01*
G01X1543484Y1171592D01*
G03X1543728Y1171574I134J149D01*
G02X1544389Y1171772I661J-1004D01*
G02X1545051Y1171573I0J-1202D01*
G03X1545287Y1171584I110J167D01*
G02X1546081Y1171866I796J-984D01*
G01X1546637D01*
G02X1546710Y1171852I0J-200D01*
G01X1547077Y1171708D01*
G02X1547137Y1171671I-73J-186D01*
G01X1547227Y1171592D01*
G03X1547469Y1171574I133J149D01*
G02X1548129Y1171772I661J-1004D01*
G01X1548130D01*
G02X1548792Y1171573I0J-1202D01*
G03X1549028Y1171584I110J167D01*
G02X1549822Y1171866I796J-984D01*
G01X1550377D01*
G02X1550450Y1171852I0J-200D01*
G01X1550657Y1171771D01*
G03X1550843Y1171792I73J186D01*
G01X1550885Y1171820D01*
X1550930Y1171906D01*
Y1173218D01*
G02X1550974Y1173343I200J0D01*
G01X1550984Y1173355D01*
X1550983Y1173495D01*
X1550938Y1173551D01*
G02X1550668Y1174309I932J759D01*
G01Y1174311D01*
G02X1550938Y1175070I1202J0D01*
G01X1550982Y1175124D01*
X1550983Y1175266D01*
X1550974Y1175277D01*
G02X1550930Y1175402I156J125D01*
G01Y1176959D01*
G02X1550974Y1177084I200J0D01*
G01X1550984Y1177096D01*
X1550983Y1177236D01*
X1550938Y1177292D01*
G02X1550668Y1178050I932J759D01*
G01Y1178052D01*
G02X1550938Y1178811I1202J0D01*
G01X1550982Y1178865D01*
X1550983Y1179007D01*
X1550974Y1179018D01*
G02X1550930Y1179143I156J125D01*
G01Y1180699D01*
G02X1550974Y1180824I200J0D01*
G01X1550984Y1180836D01*
X1550983Y1180976D01*
X1550938Y1181032D01*
G02X1550668Y1181790I932J759D01*
G01Y1181792D01*
G02X1550938Y1182551I1202J0D01*
G01X1550982Y1182605D01*
X1550983Y1182747D01*
X1550974Y1182758D01*
G02X1550930Y1182883I156J125D01*
G01Y1184439D01*
G02X1550974Y1184564I200J0D01*
G01X1550984Y1184576D01*
X1550983Y1184716D01*
X1550938Y1184772D01*
G02X1550668Y1185530I932J759D01*
G01Y1185531D01*
G02X1550689Y1185751I1202J-4D01*
G01Y1185753D01*
G03X1550634Y1185930I-197J36D01*
G01X1550399Y1186165D01*
G03X1550222Y1186220I-141J-142D01*
G01X1550221D01*
G02X1550001Y1186199I-224J1181D01*
G01X1549999D01*
G02X1549780Y1186220I5J1202D01*
G01X1549778D01*
G03X1549601Y1186165I-36J-197D01*
G01X1549366Y1185930D01*
G03X1549311Y1185753I142J-141D01*
G01Y1185751D01*
G02X1549332Y1185531I-1181J-224D01*
G02X1546928I-1202J0D01*
G02X1546949Y1185752I1202J-3D01*
G01Y1185754D01*
G03X1546894Y1185931I-197J36D01*
G01X1546659Y1186165D01*
G03X1546482Y1186220I-141J-142D01*
G01X1546481D01*
G02X1546259Y1186199I-224J1181D01*
G02X1547461Y1187401I0J1202D01*
G02X1547440Y1187180I-1202J3D01*
G01Y1187178D01*
G03X1547495Y1187001I197J-36D01*
G01X1547730Y1186767D01*
G03X1547907Y1186712I141J142D01*
G01X1547908D01*
G02X1548130Y1186733I224J-1181D01*
G02X1548350Y1186712I-4J-1202D01*
G01X1548352D01*
G03X1548529Y1186767I36J197D01*
G01X1548764Y1187002D01*
G03X1548819Y1187179I-142J141D01*
G01Y1187181D01*
G02X1548798Y1187401I1181J224D01*
G02X1550000Y1188603I1202J0D01*
G02X1550220Y1188582I-4J-1202D01*
G01X1550222D01*
G03X1550399Y1188637I36J197D01*
G01X1550634Y1188872D01*
G03X1550689Y1189049I-142J141D01*
G01Y1189051D01*
G02X1550668Y1189270I1181J224D01*
G01Y1189272D01*
G02X1550689Y1189491I1202J-5D01*
G01Y1189493D01*
G03X1550634Y1189670I-197J36D01*
G01X1550399Y1189905D01*
G03X1550222Y1189960I-141J-142D01*
G01X1550221D01*
G02X1550000Y1189939I-224J1181D01*
G02Y1192343I0J1202D01*
G02X1550220Y1192322I-4J-1202D01*
G01X1550222D01*
G03X1550399Y1192377I36J197D01*
G01X1550634Y1192612D01*
G03X1550689Y1192789I-142J141D01*
G01Y1192791D01*
G02X1550668Y1193010I1181J224D01*
G01Y1193012D01*
G02X1550689Y1193231I1202J-5D01*
G01Y1193233D01*
G03X1550634Y1193410I-197J36D01*
G01X1550399Y1193645D01*
G03X1550222Y1193700I-141J-142D01*
G01X1550221D01*
G02X1550000Y1193679I-224J1181D01*
G02X1551202Y1194881I0J1202D01*
G02X1551181Y1194661I-1202J4D01*
G01Y1194659D01*
G03X1551236Y1194482I197J-36D01*
G01X1551471Y1194247D01*
G03X1551648Y1194192I141J142D01*
G01X1551649D01*
G02X1551870Y1194213I224J-1181D01*
G02Y1191809I0J-1202D01*
G02X1551650Y1191830I4J1202D01*
G01X1551648D01*
G03X1551471Y1191775I-36J-197D01*
G01X1551236Y1191540D01*
G03X1551181Y1191363I142J-141D01*
G01Y1191361D01*
G02X1551202Y1191142I-1181J-224D01*
G01Y1191140D01*
G02X1551181Y1190921I-1202J5D01*
G01Y1190919D01*
G03X1551236Y1190742I197J-36D01*
G01X1551471Y1190507D01*
G03X1551648Y1190452I141J142D01*
G01X1551649D01*
G02X1551870Y1190473I224J-1181D01*
G01X1551871D01*
G02X1552455Y1190322I0J-1203D01*
G01X1552513Y1190289D01*
X1552645Y1190307D01*
X1553407Y1191069D01*
G02X1553415Y1191076I837J-949D01*
G03X1553421Y1191082I-138J144D01*
G02X1554303Y1191442I884J-906D01*
G01X1554515D01*
G03X1554701Y1191569I0J200D01*
G01X1554837Y1191915D01*
G03X1554788Y1192134I-186J73D01*
G02X1554408Y1193011I822J877D01*
G02X1556812I1202J0D01*
G02X1556432Y1192134I-1202J0D01*
G03X1556383Y1191915I137J-146D01*
G01X1556519Y1191569D01*
G03X1556705Y1191442I186J73D01*
G01X1558255D01*
G03X1558441Y1191569I0J200D01*
G01X1558577Y1191915D01*
G03X1558528Y1192134I-186J73D01*
G02X1558148Y1193011I822J877D01*
G02X1560552I1202J0D01*
G02X1560172Y1192134I-1202J0D01*
G03X1560123Y1191915I137J-146D01*
G01X1560259Y1191569D01*
G03X1560445Y1191442I186J73D01*
G01X1564018D01*
G03X1564160Y1191500I1J200D01*
G01X1564747Y1192087D01*
G03X1564777Y1192125I-141J142D01*
G01X1565047Y1192569D01*
G02X1565126Y1192643I171J-103D01*
G01X1565493Y1192833D01*
G02X1565517Y1192845I578J-1126D01*
G03X1565628Y1193022I-89J179D01*
G02X1565637Y1193152I1202J-18D01*
G01Y1193154D01*
G03X1565549Y1193344I-199J23D01*
G01X1565271Y1193528D01*
G02X1564708Y1194580I702J1053D01*
G01Y1195182D01*
G02X1565271Y1196234I1265J-1D01*
G01X1565549Y1196418D01*
G03X1565637Y1196608I-111J167D01*
G01Y1196609D01*
G02X1565628Y1196748I1193J147D01*
G01Y1196751D01*
G02X1566830Y1197953I1202J0D01*
G01X1566845D01*
G03X1567019Y1198051I2J200D01*
G01X1567235Y1198414D01*
G02X1568323Y1199034I1089J-646D01*
G01X1569078D01*
G02X1570166Y1198414I-1J-1266D01*
G01X1570382Y1198051D01*
G03X1570556Y1197953I172J102D01*
G01X1570586D01*
G03X1570760Y1198051I2J200D01*
G01X1570976Y1198414D01*
G02X1572064Y1199034I1089J-646D01*
G01X1572818D01*
G02X1573906Y1198414I-1J-1266D01*
G01X1574122Y1198051D01*
G03X1574296Y1197953I172J102D01*
G01X1574326D01*
G03X1574500Y1198051I2J200D01*
G01X1574716Y1198414D01*
G02X1575804Y1199034I1089J-646D01*
G01X1576558D01*
G02X1577646Y1198414I-1J-1266D01*
G01X1577862Y1198051D01*
G03X1578036Y1197953I172J102D01*
G01X1578066D01*
G03X1578240Y1198051I2J200D01*
G01X1578456Y1198414D01*
G02X1579544Y1199034I1089J-646D01*
G01X1580298D01*
G02X1581386Y1198414I-1J-1266D01*
G01X1581602Y1198051D01*
G03X1581776Y1197953I172J102D01*
G01X1581806D01*
G03X1581980Y1198051I2J200D01*
G01X1582196Y1198414D01*
G02X1583284Y1199034I1089J-646D01*
G01X1584038D01*
G02X1585126Y1198414I-1J-1266D01*
G01X1585342Y1198051D01*
G03X1585516Y1197953I172J102D01*
G01X1585546D01*
G03X1585720Y1198051I2J200D01*
G01X1585936Y1198414D01*
G02X1587024Y1199034I1089J-646D01*
G01X1587778D01*
G02X1588866Y1198414I-1J-1266D01*
G01X1589082Y1198051D01*
G03X1589256Y1197953I172J102D01*
G01X1589286D01*
G03X1589460Y1198051I2J200D01*
G01X1589676Y1198414D01*
G02X1590764Y1199034I1089J-646D01*
G01X1591518D01*
G02X1592606Y1198414I-1J-1266D01*
G01X1592822Y1198051D01*
G03X1592996Y1197953I172J102D01*
G01X1593026D01*
G03X1593200Y1198051I2J200D01*
G01X1593416Y1198414D01*
G02X1594504Y1199034I1089J-646D01*
G01X1595259D01*
G02X1596347Y1198414I-1J-1266D01*
G01X1596563Y1198051D01*
G03X1596737Y1197953I172J102D01*
G01X1596767D01*
G03X1596941Y1198051I2J200D01*
G01X1597157Y1198414D01*
G02X1598245Y1199034I1089J-646D01*
G01X1598999D01*
G02X1600087Y1198414I-1J-1266D01*
G01X1600303Y1198051D01*
G03X1600477Y1197953I172J102D01*
G01X1600507D01*
G03X1600681Y1198051I2J200D01*
G01X1600897Y1198414D01*
G02X1601985Y1199034I1089J-646D01*
G01X1606479D01*
G02X1607567Y1198414I-1J-1266D01*
G01X1607783Y1198051D01*
G03X1607957Y1197953I172J102D01*
G01X1607987D01*
G03X1608161Y1198051I2J200D01*
G01X1608377Y1198414D01*
G02X1609465Y1199034I1089J-646D01*
G01X1610219D01*
G02X1611307Y1198414I-1J-1266D01*
G01X1611523Y1198051D01*
G03X1611697Y1197953I172J102D01*
G01X1611727D01*
G03X1611901Y1198051I2J200D01*
G01X1612117Y1198414D01*
G02X1613205Y1199034I1089J-646D01*
G01X1613959D01*
G02X1615047Y1198414I-1J-1266D01*
G01X1615263Y1198051D01*
G03X1615437Y1197953I172J102D01*
G01X1615467D01*
G03X1615641Y1198051I2J200D01*
G01X1615857Y1198414D01*
G02X1616945Y1199034I1089J-646D01*
G01X1617700D01*
G02X1618788Y1198414I-1J-1266D01*
G01X1619004Y1198051D01*
G03X1619178Y1197953I172J102D01*
G01X1619208D01*
G03X1619382Y1198051I2J200D01*
G01X1619598Y1198414D01*
G02X1620686Y1199034I1089J-646D01*
G01X1621440D01*
G02X1622528Y1198414I-1J-1266D01*
G01X1622744Y1198051D01*
G03X1622918Y1197953I172J102D01*
G01X1622948D01*
G03X1623122Y1198051I2J200D01*
G01X1623338Y1198414D01*
G02X1624426Y1199034I1089J-646D01*
G01X1625180D01*
G02X1626268Y1198414I-1J-1266D01*
G01X1626484Y1198051D01*
G03X1626658Y1197953I172J102D01*
G01X1626688D01*
G03X1626862Y1198051I2J200D01*
G01X1627078Y1198414D01*
G02X1628166Y1199034I1089J-646D01*
G01X1628920D01*
G02X1630008Y1198414I-1J-1266D01*
G01X1630224Y1198051D01*
G03X1630398Y1197953I172J102D01*
G01X1630428D01*
G03X1630602Y1198051I2J200D01*
G01X1630818Y1198414D01*
G02X1631906Y1199034I1089J-646D01*
G01X1632660D01*
G02X1633748Y1198414I-1J-1266D01*
G01X1633964Y1198051D01*
G03X1634138Y1197953I172J102D01*
G01X1634168D01*
G03X1634342Y1198051I2J200D01*
G01X1634558Y1198414D01*
G02X1635646Y1199034I1089J-646D01*
G01X1636400D01*
G02X1637488Y1198414I-1J-1266D01*
G01X1637704Y1198051D01*
G03X1637878Y1197953I172J102D01*
G01X1637908D01*
G03X1638082Y1198051I2J200D01*
G01X1638298Y1198414D01*
G02X1639386Y1199034I1089J-646D01*
G01X1640172D01*
G02X1641263Y1198407I-2J-1266D01*
G01X1641481Y1198035D01*
G03X1641654Y1197936I173J101D01*
G01X1641706D01*
X1641798Y1197989D01*
X1642043Y1198407D01*
G02X1643134Y1199034I1093J-639D01*
G01X1643881D01*
G02X1644969Y1198414I-1J-1266D01*
G01X1645185Y1198051D01*
G03X1645359Y1197953I172J102D01*
G01X1645374D01*
G02X1646552Y1196994I0J-1203D01*
G01X1646562Y1196947D01*
X1646620Y1196873D01*
X1647206Y1196602D01*
G02X1647365Y1196515I-527J-1151D01*
G01X1647410Y1196485D01*
X1647519Y1196481D01*
X1647807Y1196633D01*
G03X1647913Y1196801I-94J177D01*
G01Y1196802D01*
G02X1649114Y1197953I1201J-51D01*
G02Y1195549I0J-1202D01*
G02X1648248Y1195917I0J1203D01*
G03X1647909Y1195735I-144J-139D01*
G02X1647940Y1195457I-1235J-278D01*
G01Y1194340D01*
G03X1648043Y1194165I200J0D01*
G01X1648283Y1194031D01*
G03X1648486Y1194036I97J175D01*
G02X1649114Y1194213I628J-1026D01*
G02Y1191809I0J-1202D01*
G02X1648486Y1191986I0J1203D01*
G03X1648283Y1191991I-106J-170D01*
G01X1648043Y1191857D01*
G03X1647940Y1191682I97J-175D01*
G01Y1190600D01*
G03X1648043Y1190425I200J0D01*
G01X1648283Y1190291D01*
G03X1648486Y1190296I97J175D01*
G02X1649114Y1190473I628J-1026D01*
G02Y1188069I0J-1202D01*
G02X1648486Y1188246I0J1203D01*
G03X1648283Y1188251I-106J-170D01*
G01X1648043Y1188117D01*
G03X1647940Y1187942I97J-175D01*
G01Y1186860D01*
G03X1648043Y1186685I200J0D01*
G01X1648283Y1186551D01*
G03X1648486Y1186556I97J175D01*
G02X1649114Y1186733I628J-1026D01*
G02Y1184329I0J-1202D01*
G02X1648372Y1184586I1J1202D01*
G01X1648371D01*
G03X1648203Y1184623I-123J-158D01*
G01X1647976Y1184570D01*
G03X1647838Y1184454I46J-195D01*
G02X1647569Y1184057I-1163J499D01*
G01X1646336Y1182824D01*
G03X1646277Y1182689I141J-142D01*
G01X1646275Y1182627D01*
X1646297Y1182561D01*
X1646319Y1182533D01*
G02X1646576Y1181791I-945J-743D01*
G02X1644172I-1202J0D01*
G01Y1181793D01*
G02X1644191Y1182005I1202J-1D01*
G01X1644199Y1182049D01*
X1644176Y1182134D01*
X1644003Y1182341D01*
G03X1643850Y1182412I-153J-129D01*
G01X1641186D01*
G03X1640986Y1182212I0J-200D01*
G01Y1179568D01*
G03X1641060Y1179413I200J0D01*
G01X1641235Y1179271D01*
G03X1641399Y1179230I126J155D01*
G01X1641400D01*
G02X1641633Y1179253I234J-1179D01*
G02Y1176849I0J-1202D01*
G02X1641400Y1176872I1J1202D01*
G01X1641399D01*
G03X1641235Y1176831I-38J-196D01*
G01X1641060Y1176689D01*
G03X1640986Y1176534I126J-155D01*
G01Y1175827D01*
G03X1641060Y1175672I200J0D01*
G01X1641235Y1175530D01*
G03X1641399Y1175489I126J155D01*
G01X1641400D01*
G02X1641633Y1175512I234J-1179D01*
G02Y1173108I0J-1202D01*
G02X1641400Y1173131I1J1202D01*
G01X1641399D01*
G03X1641235Y1173090I-38J-196D01*
G01X1641060Y1172948D01*
G03X1640986Y1172793I126J-155D01*
G01Y1172087D01*
G03X1641060Y1171932I200J0D01*
G01X1641235Y1171790D01*
G03X1641399Y1171749I126J155D01*
G01X1641400D01*
G02X1641633Y1171772I234J-1179D01*
G02X1642405Y1171491I0J-1201D01*
G03X1642534Y1171444I129J153D01*
G01X1644285D01*
G02X1644407Y1171403I1J-200D01*
G01X1644506Y1171407D01*
X1644581Y1171472D01*
G02X1645374Y1171772I794J-902D01*
G02X1646146Y1171491I0J-1201D01*
G03X1646275Y1171444I129J153D01*
G01X1648025D01*
G02X1648147Y1171403I1J-200D01*
G01X1648246Y1171407D01*
X1648321Y1171472D01*
G02X1649114Y1171772I794J-902D01*
G02X1650316Y1170570I0J-1202D01*
G02X1650106Y1169891I-1203J0D01*
G01X1650066Y1169834D01*
X1650075Y1169697D01*
X1650147Y1169616D01*
G02X1650198Y1169483I-149J-133D01*
G01Y1167917D01*
G02X1650147Y1167784I-200J0D01*
G01X1650075Y1167703D01*
X1650066Y1167566D01*
X1650106Y1167509D01*
G02Y1166151I-993J-679D01*
G01X1650066Y1166094D01*
X1650075Y1165957D01*
X1650147Y1165876D01*
G02X1650198Y1165743I-149J-133D01*
G01Y1160437D01*
G02X1650147Y1160304I-200J0D01*
G01X1650075Y1160223D01*
X1650066Y1160086D01*
X1650106Y1160029D01*
G02Y1158671I-993J-679D01*
G01X1650066Y1158614D01*
X1650075Y1158477D01*
X1650147Y1158396D01*
G02X1650198Y1158263I-149J-133D01*
G01Y1156697D01*
G02X1650147Y1156564I-200J0D01*
G01X1650075Y1156483D01*
X1650066Y1156346D01*
X1650106Y1156289D01*
G02Y1154931I-993J-679D01*
G01X1650066Y1154874D01*
X1650075Y1154737D01*
X1650147Y1154656D01*
G02X1650198Y1154523I-149J-133D01*
G01Y1152957D01*
G02X1650147Y1152824I-200J0D01*
G01X1650075Y1152743D01*
X1650066Y1152606D01*
X1650106Y1152549D01*
G02Y1151191I-993J-679D01*
G01X1650066Y1151134D01*
X1650075Y1150997D01*
X1650147Y1150916D01*
G02X1650198Y1150783I-149J-133D01*
G01Y1149216D01*
G02X1650147Y1149083I-200J0D01*
G01X1650075Y1149002D01*
X1650066Y1148865D01*
X1650106Y1148808D01*
G02Y1147450I-993J-679D01*
G01X1650066Y1147393D01*
X1650075Y1147256D01*
X1650147Y1147175D01*
G02X1650198Y1147042I-149J-133D01*
G01Y1145476D01*
G02X1650147Y1145343I-200J0D01*
G01X1650075Y1145262D01*
X1650066Y1145125D01*
X1650106Y1145068D01*
G02Y1143710I-993J-679D01*
G01X1650066Y1143653D01*
X1650075Y1143516D01*
X1650147Y1143435D01*
G02X1650198Y1143302I-149J-133D01*
G01Y1141736D01*
G02X1650147Y1141603I-200J0D01*
G01X1650075Y1141522D01*
X1650066Y1141385D01*
X1650106Y1141328D01*
G02Y1139970I-993J-679D01*
G01X1650066Y1139913D01*
X1650075Y1139776D01*
X1650147Y1139695D01*
G02X1650198Y1139562I-149J-133D01*
G01Y1137996D01*
G02X1650147Y1137863I-200J0D01*
G01X1650075Y1137782D01*
X1650066Y1137645D01*
X1650106Y1137588D01*
G02X1650316Y1136909I-993J-679D01*
G02X1649114Y1135707I-1202J0D01*
G01X1649113D01*
G02X1648845Y1135737I-1J1202D01*
G03X1648647Y1135670I-44J-195D01*
G02X1648570Y1135586I-970J812D01*
G01X1647724Y1134740D01*
G03X1647722Y1134738I140J-142D01*
G01X1647575Y1134585D01*
G02X1647505Y1134538I-144J139D01*
G01X1647105Y1134377D01*
G02X1647030Y1134362I-76J185D01*
G01X1642946D01*
G02X1642623Y1134404I0J1265D01*
G03X1642438Y1134062I-51J-193D01*
G02X1642835Y1133169I-806J-893D01*
G02X1640431I-1202J0D01*
G02X1640828Y1134062I1203J0D01*
G03X1640643Y1134404I-134J149D01*
G02X1640320Y1134362I-323J1223D01*
G37*
G36*
G01X1495139Y148717D02*
G02X1498143I1502J0D01*
G02X1497138Y147300I-1501J0D01*
G03X1497018Y147183I67J-188D01*
G01X1496892Y146857D01*
X1496898Y146770D01*
X1496919Y146731D01*
G02X1497102Y146013I-1319J-719D01*
G01Y146012D01*
G02X1496442Y144768I-1502J0D01*
G03X1496354Y144603I112J-166D01*
G01Y144271D01*
G03X1496442Y144106I200J1D01*
G02X1497087Y143074I-842J-1244D01*
G01Y143073D01*
G03X1497155Y142950I198J29D01*
G01X1497355Y142778D01*
G03X1497488Y142730I130J152D01*
G01X1497506D01*
G02Y139726I0J-1502D01*
G02X1496019Y141016I0J1502D01*
G01Y141017D01*
G03X1495951Y141140I-198J-29D01*
G01X1495751Y141312D01*
G03X1495618Y141360I-130J-152D01*
G01X1495600D01*
G02X1494098Y142862I0J1502D01*
G02X1494758Y144106I1502J0D01*
G03X1494846Y144271I-112J166D01*
G01Y144603D01*
G03X1494758Y144768I-200J-1D01*
G02X1494098Y146012I842J1244D01*
G02X1495103Y147429I1501J0D01*
G03X1495223Y147546I-67J188D01*
G01X1495349Y147872D01*
X1495343Y147959D01*
X1495322Y147998D01*
G02X1495139Y148716I1319J719D01*
G01Y148717D01*
G37*
G36*
G01X1495202Y110018D02*
X1495516D01*
G03X1495674Y110095I0J200D01*
G02X1496859Y110674I1185J-923D01*
G02X1498361Y109172I0J-1502D01*
G02X1497398Y107770I-1502J0D01*
G01X1497396D01*
X1497356Y107754D01*
X1497297Y107694D01*
X1497162Y107330D01*
X1497168Y107245D01*
X1497189Y107207D01*
G02X1497368Y106497I-1323J-711D01*
G01Y106495D01*
G02X1494364I-1502J0D01*
G02X1494502Y107123I1502J-1D01*
G01Y107124D01*
G03X1494481Y107327I-182J84D01*
G01X1494236Y107653D01*
X1494135Y107694D01*
X1494080Y107686D01*
G02X1493859Y107670I-219J1486D01*
G02Y110674I0J1502D01*
G02X1495044Y110095I0J-1502D01*
G03X1495202Y110018I158J123D01*
G37*
G36*
G01X1507327Y106561D02*
G02X1510331I1502J0D01*
G02X1509605Y105275I-1502J0D01*
G03X1509509Y105114I104J-171D01*
G01X1509491Y104782D01*
G03X1509571Y104612I200J-10D01*
G02X1510126Y103779I-901J-1202D01*
G03X1510251Y103641I194J50D01*
G01X1510560Y103526D01*
G03X1510744Y103550I69J188D01*
G02X1511610Y103825I866J-1226D01*
G02Y100821I0J-1502D01*
G02X1510154Y101955I0J1502D01*
G03X1510029Y102093I-194J-50D01*
G01X1509720Y102208D01*
G03X1509536Y102184I-69J-188D01*
G02X1508670Y101909I-866J1226D01*
G02X1507168Y103411I0J1502D01*
G02X1507894Y104697I1502J0D01*
G03X1507990Y104858I-104J171D01*
G01X1508008Y105190D01*
G03X1507928Y105360I-200J10D01*
G02X1507327Y106561I901J1202D01*
G37*
G36*
G01X1564239Y102731D02*
G02X1563947Y103621I1210J890D01*
G02X1566951I1502J0D01*
G02X1565726Y102145I-1502J0D01*
G03X1565477Y101515I73J-393D01*
G02X1565769Y100625I-1210J-890D01*
G02X1562765I-1502J0D01*
G02X1563990Y102101I1502J0D01*
G03X1564239Y102731I-73J393D01*
G37*
G36*
G01X1528667Y101849D02*
G02X1528084Y103037I919J1188D01*
G02X1531088I1502J0D01*
G02X1530432Y101796I-1502J0D01*
G03X1530412Y101149I225J-331D01*
G02X1530995Y99961I-919J-1188D01*
G02X1527991I-1502J0D01*
G02X1528647Y101202I1502J0D01*
G03X1528667Y101849I-225J331D01*
G37*
G36*
G01X1523180Y91453D02*
G02X1522626Y91347I-554J1395D01*
G02X1524128Y92849I0J1502D01*
G02X1524082Y92481I-1502J1D01*
G03X1524618Y92011I388J-98D01*
G02X1525172Y92117I554J-1395D01*
G02X1523670Y90615I0J-1502D01*
G02X1523716Y90983I1502J-1D01*
G03X1523180Y91453I-388J98D01*
G37*
G36*
G01X1574019Y90701D02*
G02X1573349Y91951I831J1250D01*
G02X1576353I1502J0D01*
G02X1575703Y90714I-1502J0D01*
G03X1575708Y90051I227J-330D01*
G02X1576378Y88801I-831J-1250D01*
G02X1573374I-1502J0D01*
G02X1574024Y90038I1502J0D01*
G03X1574019Y90701I-227J330D01*
G37*
G36*
G01X1485428Y217133D02*
X1485134D01*
G03X1484987Y217068I1J-200D01*
G02X1483881Y216583I-1106J1019D01*
G02Y219587I0J1502D01*
G02X1484987Y219102I0J-1504D01*
G03X1485134Y219037I148J135D01*
G01X1485428D01*
G03X1485575Y219102I-1J200D01*
G02X1486681Y219587I1106J-1019D01*
G02Y216583I0J-1502D01*
G02X1485575Y217068I0J1504D01*
G03X1485428Y217133I-148J-135D01*
G37*
G36*
G01X1490190Y205336D02*
G02Y208340I0J1502D01*
G02X1491177Y207970I0J-1501D01*
G01X1491178D01*
Y207969D01*
G03X1491308Y207921I130J152D01*
G01X1491572D01*
G03X1491702Y207969I0J200D01*
G01X1491703Y207970D01*
G02X1492690Y208340I987J-1131D01*
G02Y205336I0J-1502D01*
G02X1491703Y205706I0J1501D01*
G01X1491702D01*
Y205707D01*
G03X1491572Y205755I-130J-152D01*
G01X1491308D01*
G03X1491178Y205707I0J-200D01*
G01X1491177Y205706D01*
G02X1490190Y205336I-987J1131D01*
G37*
G36*
G01X1484002Y201891D02*
G02Y204895I0J1502D01*
G02X1484989Y204525I0J-1501D01*
G01X1484990D01*
Y204524D01*
G03X1485120Y204476I130J152D01*
G01X1485384D01*
G03X1485514Y204524I0J200D01*
G01X1485515Y204525D01*
G02X1486502Y204895I987J-1131D01*
G02X1487999Y203517I0J-1502D01*
G01X1488002Y203474D01*
X1488043Y203400D01*
X1488315Y203194D01*
G03X1488474Y203157I121J159D01*
G02X1488761Y203185I289J-1474D01*
G02X1490263Y201683I0J-1502D01*
G02X1489778Y200577I-1504J0D01*
G03X1489713Y200430I135J-148D01*
G01Y200136D01*
G03X1489778Y199989I200J1D01*
G02X1490263Y198883I-1019J-1106D01*
G02X1487259I-1502J0D01*
G02X1487744Y199989I1504J0D01*
G03X1487809Y200136I-135J148D01*
G01Y200430D01*
G03X1487744Y200577I-200J-1D01*
G02X1487264Y201559I1017J1105D01*
G01X1487261Y201602D01*
X1487220Y201676D01*
X1486948Y201882D01*
G03X1486789Y201919I-121J-159D01*
G02X1486502Y201891I-289J1474D01*
G02X1485515Y202261I0J1501D01*
G01X1485514D01*
Y202262D01*
G03X1485384Y202310I-130J-152D01*
G01X1485120D01*
G03X1484990Y202262I0J-200D01*
G01X1484989Y202261D01*
G02X1484002Y201891I-987J1131D01*
G37*
G36*
G01X1489142Y196678D02*
G02X1490248Y196193I0J-1504D01*
G03X1490395Y196128I148J135D01*
G01X1490689D01*
G03X1490836Y196193I-1J200D01*
G02X1491942Y196678I1106J-1019D01*
G02Y193674I0J-1502D01*
G02X1490836Y194159I0J1504D01*
G03X1490689Y194224I-148J-135D01*
G01X1490395D01*
G03X1490248Y194159I1J-200D01*
G02X1489142Y193674I-1106J1019D01*
G02X1488155Y194044I0J1501D01*
G01X1488154D01*
Y194045D01*
G03X1488024Y194093I-130J-152D01*
G01X1487760D01*
G03X1487630Y194045I0J-200D01*
G01X1487629Y194044D01*
G02X1485655I-987J1131D01*
G01X1485654D01*
Y194045D01*
G03X1485524Y194093I-130J-152D01*
G01X1485260D01*
G03X1485130Y194045I0J-200D01*
G01X1485129Y194044D01*
G02X1484142Y193674I-987J1131D01*
G02Y196678I0J1502D01*
G02X1485129Y196308I0J-1501D01*
G01X1485130D01*
Y196307D01*
G03X1485260Y196259I130J152D01*
G01X1485524D01*
G03X1485654Y196307I0J200D01*
G01X1485655Y196308D01*
G02X1487629I987J-1131D01*
G01X1487630D01*
Y196307D01*
G03X1487760Y196259I130J152D01*
G01X1488024D01*
G03X1488154Y196307I0J200D01*
G01X1488155Y196308D01*
G02X1489142Y196678I987J-1131D01*
G37*
G36*
G01X1509310Y123626D02*
G02X1508885Y123677I1J1802D01*
G01X1508882D01*
G03X1508726Y123649I-46J-195D01*
G01X1508445Y123462D01*
X1508400Y123392D01*
X1508394Y123350D01*
G02X1506910Y122081I-1484J233D01*
G01X1506909D01*
G02X1505922Y122451I0J1502D01*
G01X1505895Y122475D01*
X1505827Y122501D01*
X1505491D01*
X1505424Y122476D01*
X1505397Y122452D01*
G02X1504410Y122082I-987J1131D01*
G02X1504142Y122106I-1J1502D01*
G03X1503976Y122060I-35J-197D01*
G01X1503880Y121977D01*
G03X1503810Y121817I130J-152D01*
G02X1503812Y121743I-1800J-86D01*
G01Y118342D01*
G02X1503810Y118263I-1802J6D01*
G03X1503879Y118104I200J-8D01*
G01X1503976Y118020D01*
G03X1504143Y117975I130J152D01*
G02X1504410Y117999I267J-1478D01*
G02X1505397Y117629I0J-1501D01*
G01X1505398D01*
Y117628D01*
G03X1505528Y117580I130J152D01*
G01X1505792D01*
G03X1505922Y117628I0J200D01*
G01X1505923Y117629D01*
G02X1506910Y117999I987J-1131D01*
G02X1508393Y116732I0J-1501D01*
G01X1508400Y116690D01*
X1508444Y116621D01*
X1508760Y116411D01*
X1508843Y116396D01*
X1508883Y116406D01*
G02X1509310Y116458I430J-1751D01*
G02X1509658Y116424I0J-1803D01*
G01X1509698Y116416D01*
X1509777Y116432D01*
X1510080Y116642D01*
X1510122Y116708D01*
X1510129Y116749D01*
G02X1511610Y117998I1481J-254D01*
G02Y114994I0J-1502D01*
G01X1511607D01*
G02X1511429Y115005I3J1502D01*
G03X1511271Y114954I-23J-199D01*
G01X1511177Y114869D01*
G03X1511111Y114715I134J-149D01*
G02X1511112Y114655I-1801J-60D01*
G01Y111255D01*
G02X1511111Y111192I-1802J-3D01*
G03X1511176Y111038I200J-6D01*
G01X1511271Y110952D01*
G03X1511429Y110901I135J148D01*
G02X1511607Y110912I181J-1491D01*
G01X1511610D01*
G02Y107908I0J-1502D01*
G02X1510129Y109160I0J1502D01*
G03X1510045Y109292I-197J-33D01*
G01X1509776Y109478D01*
X1509697Y109494D01*
X1509657Y109486D01*
G02X1509310Y109452I-348J1769D01*
G02X1508885Y109504I5J1802D01*
G01X1508882D01*
G03X1508726Y109476I-46J-195D01*
G01X1508445Y109289D01*
X1508400Y109219D01*
X1508394Y109177D01*
G02X1506910Y107908I-1484J233D01*
G02Y110912I0J1502D01*
G02X1507177Y110888I0J-1502D01*
G03X1507344Y110933I37J197D01*
G01X1507441Y111017D01*
G03X1507510Y111176I-131J151D01*
G02X1507508Y111255I1800J85D01*
G01Y114656D01*
G02X1507510Y114730I1802J-12D01*
G03X1507440Y114890I-200J8D01*
G01X1507344Y114973D01*
G03X1507178Y115019I-131J-151D01*
G02X1506910Y114995I-267J1478D01*
G02X1505923Y115365I0J1501D01*
G01X1505922D01*
Y115366D01*
G03X1505792Y115414I-130J-152D01*
G01X1505528D01*
G03X1505398Y115366I0J-200D01*
G01X1505397Y115365D01*
G02X1504410Y114995I-987J1131D01*
G02X1502926Y116264I0J1502D01*
G01X1502920Y116306D01*
X1502875Y116376D01*
X1502594Y116563D01*
G03X1502438Y116591I-110J-167D01*
G01X1502436D01*
G02X1502010Y116540I-426J1751D01*
G02X1501585Y116591I1J1802D01*
G01X1501582D01*
G03X1501426Y116563I-46J-195D01*
G01X1501145Y116376D01*
X1501100Y116306D01*
X1501094Y116264D01*
G02X1499610Y114995I-1484J233D01*
G02Y117999I0J1502D01*
G02X1499877Y117975I0J-1502D01*
G03X1500044Y118020I37J197D01*
G01X1500141Y118104D01*
G03X1500210Y118263I-131J151D01*
G02X1500208Y118342I1800J85D01*
G01Y121743D01*
G02X1500210Y121817I1802J-12D01*
G03X1500140Y121977I-200J8D01*
G01X1500044Y122060D01*
G03X1499878Y122106I-131J-151D01*
G02X1499610Y122082I-267J1478D01*
G02Y125086I0J1502D01*
G02X1501093Y123819I0J-1501D01*
G01X1501100Y123777D01*
X1501144Y123708D01*
X1501460Y123498D01*
X1501543Y123483D01*
X1501583Y123493D01*
G02X1502010Y123544I426J-1751D01*
G02X1502437Y123493I1J-1802D01*
G01X1502477Y123483D01*
X1502560Y123498D01*
X1502841Y123685D01*
G03X1502927Y123819I-111J166D01*
G02X1504410Y125086I1483J-234D01*
G01X1504411D01*
G02X1505398Y124716I0J-1502D01*
G01X1505425Y124692D01*
X1505493Y124666D01*
X1505829D01*
X1505896Y124691D01*
X1505923Y124715D01*
G02X1506910Y125085I987J-1131D01*
G02X1507177Y125061I0J-1502D01*
G03X1507344Y125106I37J197D01*
G01X1507441Y125190D01*
G03X1507510Y125349I-131J151D01*
G02X1507508Y125428I1800J85D01*
G01Y128829D01*
G02X1507510Y128903I1802J-12D01*
G03X1507440Y129063I-200J8D01*
G01X1507344Y129146D01*
G03X1507178Y129192I-131J-151D01*
G02X1506910Y129168I-267J1478D01*
G02X1505923Y129538I0J1501D01*
G01X1505922D01*
Y129539D01*
G03X1505792Y129587I-130J-152D01*
G01X1505528D01*
G03X1505398Y129539I0J-200D01*
G01X1505397Y129538D01*
G02X1504410Y129168I-987J1131D01*
G02X1502926Y130437I0J1502D01*
G01X1502920Y130479D01*
X1502875Y130549D01*
X1502594Y130736D01*
G03X1502438Y130764I-110J-167D01*
G01X1502436D01*
G02X1502010Y130712I-430J1751D01*
G02X1501585Y130764I5J1802D01*
G01X1501582D01*
G03X1501426Y130736I-46J-195D01*
G01X1501145Y130549D01*
X1501100Y130479D01*
X1501094Y130437D01*
G02X1499610Y129168I-1484J233D01*
G02Y132172I0J1502D01*
G02X1499877Y132148I0J-1502D01*
G03X1500044Y132193I37J197D01*
G01X1500141Y132277D01*
G03X1500210Y132436I-131J151D01*
G02X1500208Y132515I1800J85D01*
G01Y135916D01*
G02X1500210Y135990I1802J-12D01*
G03X1500140Y136150I-200J8D01*
G01X1500044Y136233D01*
G03X1499878Y136279I-131J-151D01*
G02X1499610Y136255I-267J1478D01*
G02Y139259I0J1502D01*
G02X1501093Y137992I0J-1501D01*
G01X1501100Y137950D01*
X1501144Y137881D01*
X1501460Y137671D01*
X1501543Y137656D01*
X1501583Y137666D01*
G02X1502010Y137718I430J-1751D01*
G02X1502437Y137666I-3J-1803D01*
G01X1502477Y137656D01*
X1502560Y137671D01*
X1502841Y137858D01*
G03X1502927Y137992I-111J166D01*
G02X1504410Y139259I1483J-234D01*
G02Y136255I0J-1502D01*
G02X1504142Y136279I-1J1502D01*
G03X1503976Y136233I-35J-197D01*
G01X1503880Y136150D01*
G03X1503810Y135990I130J-152D01*
G02X1503812Y135916I-1800J-86D01*
G01Y132515D01*
G02X1503810Y132436I-1802J6D01*
G03X1503879Y132277I200J-8D01*
G01X1503976Y132193D01*
G03X1504143Y132148I130J152D01*
G02X1504410Y132172I267J-1478D01*
G02X1505397Y131802I0J-1501D01*
G01X1505398D01*
Y131801D01*
G03X1505528Y131753I130J152D01*
G01X1505792D01*
G03X1505922Y131801I0J200D01*
G01X1505923Y131802D01*
G02X1506910Y132172I987J-1131D01*
G02X1508393Y130905I0J-1501D01*
G01X1508400Y130863D01*
X1508444Y130794D01*
X1508760Y130584D01*
X1508843Y130569D01*
X1508883Y130579D01*
G02X1509310Y130630I426J-1751D01*
G02X1509658Y130597I5J-1802D01*
G01X1509698Y130589D01*
X1509777Y130605D01*
X1510080Y130815D01*
X1510122Y130881D01*
X1510129Y130922D01*
G02X1511610Y132172I1481J-252D01*
G02Y129168I0J-1502D01*
G01X1511607D01*
G02X1511429Y129179I3J1502D01*
G03X1511271Y129128I-23J-199D01*
G01X1511177Y129043D01*
G03X1511111Y128889I134J-149D01*
G02X1511112Y128828I-1801J-60D01*
G01Y125428D01*
G02X1511111Y125365I-1802J-3D01*
G03X1511176Y125211I200J-6D01*
G01X1511271Y125125D01*
G03X1511429Y125074I135J148D01*
G02X1511607Y125085I181J-1491D01*
G01X1511610D01*
G02Y122081I0J-1502D01*
G02X1510129Y123333I0J1502D01*
G03X1510045Y123465I-197J-33D01*
G01X1509776Y123651D01*
X1509697Y123667D01*
X1509657Y123659D01*
G02X1509310Y123626I-343J1769D01*
G37*
G36*
G01X1518570Y85584D02*
G02X1521574I1502J0D01*
G02X1521168Y84557I-1502J0D01*
G01X1521142Y84530D01*
X1521114Y84459D01*
Y84109D01*
X1521142Y84038D01*
X1521168Y84011D01*
G02Y81957I-1096J-1027D01*
G01X1521142Y81930D01*
X1521114Y81859D01*
Y81509D01*
X1521142Y81438D01*
X1521168Y81411D01*
G02Y79357I-1096J-1027D01*
G01X1521142Y79330D01*
X1521114Y79259D01*
Y78909D01*
X1521142Y78838D01*
X1521168Y78811D01*
G02Y76757I-1096J-1027D01*
G01X1521142Y76730D01*
X1521114Y76659D01*
Y76309D01*
X1521142Y76238D01*
X1521168Y76211D01*
G02X1521574Y75184I-1096J-1027D01*
G02X1518570I-1502J0D01*
G02X1518976Y76211I1502J0D01*
G01X1519002Y76238D01*
X1519030Y76309D01*
Y76659D01*
X1519002Y76730D01*
X1518976Y76757D01*
G02Y78811I1096J1027D01*
G01X1519002Y78838D01*
X1519030Y78909D01*
Y79259D01*
X1519002Y79330D01*
X1518976Y79357D01*
G02Y81411I1096J1027D01*
G01X1519002Y81438D01*
X1519030Y81509D01*
Y81859D01*
X1519002Y81930D01*
X1518976Y81957D01*
G02Y84011I1096J1027D01*
G01X1519002Y84038D01*
X1519030Y84109D01*
Y84459D01*
X1519002Y84530D01*
X1518976Y84557D01*
G02X1518570Y85584I1096J1027D01*
G37*
G36*
G01X1536905Y85539D02*
G02X1539909I1502J0D01*
G02X1539503Y84512I-1502J0D01*
G01X1539477Y84485D01*
X1539449Y84414D01*
Y84064D01*
X1539477Y83993D01*
X1539503Y83966D01*
G02Y81912I-1096J-1027D01*
G01X1539477Y81885D01*
X1539449Y81814D01*
Y81464D01*
X1539477Y81393D01*
X1539503Y81366D01*
G02Y79312I-1096J-1027D01*
G01X1539477Y79285D01*
X1539449Y79214D01*
Y78864D01*
X1539477Y78793D01*
X1539503Y78766D01*
G02Y76712I-1096J-1027D01*
G01X1539477Y76685D01*
X1539449Y76614D01*
Y76264D01*
X1539477Y76193D01*
X1539503Y76166D01*
G02X1539909Y75139I-1096J-1027D01*
G02X1536905I-1502J0D01*
G02X1537311Y76166I1502J0D01*
G01X1537337Y76193D01*
X1537365Y76264D01*
Y76614D01*
X1537337Y76685D01*
X1537311Y76712D01*
G02Y78766I1096J1027D01*
G01X1537337Y78793D01*
X1537365Y78864D01*
Y79214D01*
X1537337Y79285D01*
X1537311Y79312D01*
G02Y81366I1096J1027D01*
G01X1537337Y81393D01*
X1537365Y81464D01*
Y81814D01*
X1537337Y81885D01*
X1537311Y81912D01*
G02Y83966I1096J1027D01*
G01X1537337Y83993D01*
X1537365Y84064D01*
Y84414D01*
X1537337Y84485D01*
X1537311Y84512D01*
G02X1536905Y85539I1096J1027D01*
G37*
G36*
G01X1560080Y74638D02*
G02Y77642I0J1502D01*
G01X1560081D01*
G02X1561001Y77327I0J-1502D01*
G03X1561156Y77287I123J157D01*
G01X1561444Y77334D01*
G03X1561578Y77420I-32J197D01*
G01X1561579Y77421D01*
G02X1562828Y78089I1249J-834D01*
G02Y75085I0J-1502D01*
G01X1562827D01*
G02X1561907Y75400I0J1502D01*
G03X1561752Y75440I-123J-157D01*
G01X1561464Y75393D01*
G03X1561330Y75307I32J-197D01*
G01X1561329Y75306D01*
G02X1560080Y74638I-1249J834D01*
G37*
G36*
G01X1493650Y236121D02*
G02X1496654I1502J0D01*
G02X1496004Y234884I-1502J0D01*
G03X1496010Y234222I227J-329D01*
G02X1496680Y232971I-833J-1251D01*
G02X1493676I-1502J0D01*
G02X1494326Y234208I1502J0D01*
G03X1494320Y234870I-227J329D01*
G02X1493650Y236121I833J1251D01*
G37*
G36*
G01X1491692Y221970D02*
G02X1494696I1502J0D01*
G02X1494326Y220983I-1501J0D01*
G01Y220982D01*
X1494325D01*
G03X1494277Y220852I152J-130D01*
G01Y220588D01*
G03X1494325Y220458I200J0D01*
G01X1494326Y220457D01*
G02Y218483I-1131J-987D01*
G01Y218482D01*
X1494325D01*
G03X1494277Y218352I152J-130D01*
G01Y218088D01*
G03X1494325Y217958I200J0D01*
G01X1494326Y217957D01*
G02X1494696Y216970I-1131J-987D01*
G02X1493194Y215468I-1502J0D01*
G02X1492339Y215735I0J1502D01*
G01X1492305Y215758D01*
X1492224Y215775D01*
X1491857Y215695D01*
X1491790Y215647D01*
X1491769Y215612D01*
G02X1490481Y214883I-1288J773D01*
G02Y217887I0J1502D01*
G02X1491336Y217620I0J-1502D01*
G01X1491370Y217597D01*
X1491451Y217580D01*
X1491818Y217660D01*
X1491885Y217708D01*
X1491906Y217743D01*
G02X1492062Y217956I1285J-777D01*
G03X1492063Y217958I-173J88D01*
G03X1492111Y218088I-152J130D01*
G01Y218352D01*
G03X1492063Y218482I-200J0D01*
G01X1492062Y218483D01*
G02Y220457I1131J987D01*
G01Y220458D01*
X1492063D01*
G03X1492111Y220588I-152J130D01*
G01Y220852D01*
G03X1492063Y220982I-200J0D01*
G01X1492062Y220983D01*
G02X1491692Y221970I1131J987D01*
G37*
G36*
G01X1549390Y223294D02*
Y223630D01*
X1549365Y223697D01*
X1549341Y223725D01*
G02X1548971Y224712I1131J987D01*
G02X1551975I1502J0D01*
G02X1551605Y223725I-1501J0D01*
G01X1551581Y223697D01*
X1551556Y223630D01*
Y223294D01*
X1551581Y223227D01*
X1551605Y223199D01*
G02X1551975Y222212I-1131J-987D01*
G02X1548971I-1502J0D01*
G02X1549341Y223199I1501J0D01*
G01X1549365Y223227D01*
X1549390Y223294D01*
G37*
G36*
G01X1544065Y225189D02*
X1543771D01*
G03X1543624Y225124I1J-200D01*
G02X1542518Y224639I-1105J1017D01*
G02Y227643I0J1502D01*
G02X1543624Y227158I1J-1502D01*
G03X1543771Y227093I148J135D01*
G01X1544065D01*
G03X1544212Y227158I-1J200D01*
G02X1545318Y227643I1105J-1017D01*
G02Y224639I0J-1502D01*
G02X1544212Y225124I-1J1502D01*
G03X1544065Y225189I-148J-135D01*
G37*
G36*
G01X1527272Y229808D02*
Y230144D01*
X1527247Y230211D01*
X1527223Y230239D01*
G02X1526853Y231226I1131J987D01*
G02X1529857I1502J0D01*
G02X1529487Y230239I-1501J0D01*
G01X1529463Y230211D01*
X1529438Y230144D01*
Y229808D01*
X1529463Y229741D01*
X1529487Y229713D01*
G02Y227739I-1131J-987D01*
G01X1529463Y227711D01*
X1529438Y227644D01*
Y227308D01*
X1529463Y227241D01*
X1529487Y227213D01*
G02Y225239I-1131J-987D01*
G01X1529463Y225211D01*
X1529438Y225144D01*
Y224808D01*
X1529463Y224741D01*
X1529487Y224713D01*
G02X1529857Y223726I-1131J-987D01*
G02X1526853I-1502J0D01*
G02X1527223Y224713I1501J0D01*
G01X1527247Y224741D01*
X1527272Y224808D01*
Y225144D01*
X1527247Y225211D01*
X1527223Y225239D01*
G02Y227213I1131J987D01*
G01X1527247Y227241D01*
X1527272Y227308D01*
Y227644D01*
X1527247Y227711D01*
X1527223Y227739D01*
G02Y229713I1131J987D01*
G01X1527247Y229741D01*
X1527272Y229808D01*
G37*
G36*
G01X1537728Y230043D02*
Y230379D01*
X1537703Y230446D01*
X1537679Y230474D01*
G02X1537309Y231461I1131J987D01*
G02X1540313I1502J0D01*
G02X1539943Y230474I-1501J0D01*
G01X1539919Y230446D01*
X1539894Y230379D01*
Y230043D01*
X1539919Y229976D01*
X1539943Y229948D01*
G02Y227974I-1131J-987D01*
G01X1539919Y227946D01*
X1539894Y227879D01*
Y227543D01*
X1539919Y227476D01*
X1539943Y227448D01*
G02X1540313Y226461I-1131J-987D01*
G02X1539828Y225355I-1502J-1D01*
G03X1539763Y225208I135J-148D01*
G01Y224914D01*
G03X1539828Y224767I200J1D01*
G02X1540313Y223661I-1017J-1105D01*
G02X1537309I-1502J0D01*
G02X1537794Y224767I1502J1D01*
G03X1537859Y224914I-135J148D01*
G01Y225208D01*
G03X1537794Y225355I-200J-1D01*
G02X1537309Y226461I1017J1105D01*
G02X1537679Y227448I1501J0D01*
G01X1537703Y227476D01*
X1537728Y227543D01*
Y227879D01*
X1537703Y227946D01*
X1537679Y227974D01*
G02Y229948I1131J987D01*
G01X1537703Y229976D01*
X1537728Y230043D01*
G37*
G36*
G01X1545697Y230368D02*
Y230704D01*
X1545672Y230771D01*
X1545648Y230799D01*
G02X1545278Y231786I1131J987D01*
G02X1548282I1502J0D01*
G02X1547912Y230799I-1501J0D01*
G01X1547888Y230771D01*
X1547863Y230704D01*
Y230368D01*
X1547888Y230301D01*
X1547912Y230273D01*
G02X1548282Y229286I-1131J-987D01*
G02X1545278I-1502J0D01*
G02X1545648Y230273I1501J0D01*
G01X1545672Y230301D01*
X1545697Y230368D01*
G37*
G36*
G01X1543843Y237694D02*
X1544179D01*
X1544246Y237719D01*
X1544274Y237743D01*
G02X1546248I987J-1131D01*
G01X1546276Y237719D01*
X1546343Y237694D01*
X1546679D01*
X1546746Y237719D01*
X1546774Y237743D01*
G02X1547761Y238113I987J-1131D01*
G02Y235109I0J-1502D01*
G02X1546774Y235479I0J1501D01*
G01X1546746Y235503D01*
X1546679Y235528D01*
X1546343D01*
X1546276Y235503D01*
X1546248Y235479D01*
G02X1544274I-987J1131D01*
G01X1544246Y235503D01*
X1544179Y235528D01*
X1543843D01*
X1543776Y235503D01*
X1543748Y235479D01*
G02X1542761Y235109I-987J1131D01*
G02Y238113I0J1502D01*
G02X1543748Y237743I0J-1501D01*
G01X1543776Y237719D01*
X1543843Y237694D01*
G37*
G36*
G01X1543545Y249974D02*
X1543881D01*
X1543948Y249999D01*
X1543976Y250023D01*
G02X1545950I987J-1131D01*
G01X1545978Y249999D01*
X1546045Y249974D01*
X1546381D01*
X1546448Y249999D01*
X1546476Y250023D01*
G02X1547463Y250393I987J-1131D01*
G02Y247389I0J-1502D01*
G02X1546476Y247759I0J1501D01*
G01X1546448Y247783D01*
X1546381Y247808D01*
X1546045D01*
X1545978Y247783D01*
X1545950Y247759D01*
G02X1543976I-987J1131D01*
G01X1543948Y247783D01*
X1543881Y247808D01*
X1543545D01*
X1543478Y247783D01*
X1543450Y247759D01*
G02X1542463Y247389I-987J1131D01*
G02Y250393I0J1502D01*
G02X1543450Y250023I0J-1501D01*
G01X1543478Y249999D01*
X1543545Y249974D01*
G37*
G36*
G01X1547840Y190705D02*
G02X1547192Y191941I855J1236D01*
G02X1550196I1502J0D01*
G02X1549443Y190639I-1502J0D01*
G03X1549415Y189963I199J-347D01*
G02X1550063Y188727I-855J-1236D01*
G02X1547059I-1502J0D01*
G02X1547812Y190029I1502J0D01*
G03X1547840Y190705I-199J347D01*
G37*
G36*
G01X1506965Y1023237D02*
X1506959Y1023646D01*
X1506918Y1023727D01*
X1506881Y1023756D01*
G02X1506284Y1024954I905J1199D01*
G02X1509288I1502J0D01*
G02X1508727Y1023783I-1503J0D01*
G01X1508691Y1023754D01*
X1508652Y1023671D01*
X1508658Y1023262D01*
X1508699Y1023181D01*
X1508736Y1023152D01*
G02X1509333Y1021954I-905J-1199D01*
G02X1506329I-1502J0D01*
G02X1506890Y1023125I1503J0D01*
G01X1506926Y1023154D01*
X1506965Y1023237D01*
G37*
G36*
G01X1495319Y1103374D02*
X1495313Y1103783D01*
X1495272Y1103864D01*
X1495235Y1103893D01*
G02X1494638Y1105091I905J1199D01*
G02X1497642I1502J0D01*
G02X1497081Y1103920I-1503J0D01*
G01X1497045Y1103891D01*
X1497006Y1103808D01*
X1497012Y1103399D01*
X1497053Y1103318D01*
X1497090Y1103289D01*
G02X1497687Y1102091I-905J-1199D01*
G02X1494683I-1502J0D01*
G02X1495244Y1103262I1503J0D01*
G01X1495280Y1103291D01*
X1495319Y1103374D01*
G37*
G36*
G01Y1115974D02*
X1495313Y1116383D01*
X1495272Y1116464D01*
X1495235Y1116493D01*
G02X1494638Y1117691I905J1199D01*
G02X1497642I1502J0D01*
G02X1497081Y1116520I-1503J0D01*
G01X1497045Y1116491D01*
X1497006Y1116408D01*
X1497012Y1115999D01*
X1497053Y1115918D01*
X1497090Y1115889D01*
G02X1497687Y1114691I-905J-1199D01*
G02X1494683I-1502J0D01*
G02X1495244Y1115862I1503J0D01*
G01X1495280Y1115891D01*
X1495319Y1115974D01*
G37*
G36*
G01Y1128574D02*
X1495313Y1128983D01*
X1495272Y1129064D01*
X1495235Y1129093D01*
G02X1494638Y1130291I905J1199D01*
G02X1497642I1502J0D01*
G02X1497081Y1129120I-1503J0D01*
G01X1497045Y1129091D01*
X1497006Y1129008D01*
X1497012Y1128599D01*
X1497053Y1128518D01*
X1497090Y1128489D01*
G02X1497687Y1127291I-905J-1199D01*
G02X1494683I-1502J0D01*
G02X1495244Y1128462I1503J0D01*
G01X1495280Y1128491D01*
X1495319Y1128574D01*
G37*
G36*
G01Y1141174D02*
X1495313Y1141583D01*
X1495272Y1141664D01*
X1495235Y1141693D01*
G02X1494638Y1142891I905J1199D01*
G02X1497642I1502J0D01*
G02X1497081Y1141720I-1503J0D01*
G01X1497045Y1141691D01*
X1497006Y1141608D01*
X1497012Y1141199D01*
X1497053Y1141118D01*
X1497090Y1141089D01*
G02X1497687Y1139891I-905J-1199D01*
G02X1494683I-1502J0D01*
G02X1495244Y1141062I1503J0D01*
G01X1495280Y1141091D01*
X1495319Y1141174D01*
G37*
G36*
G01Y1153774D02*
X1495313Y1154183D01*
X1495272Y1154264D01*
X1495235Y1154293D01*
G02X1494638Y1155491I905J1199D01*
G02X1497642I1502J0D01*
G02X1497081Y1154320I-1503J0D01*
G01X1497045Y1154291D01*
X1497006Y1154208D01*
X1497012Y1153799D01*
X1497053Y1153718D01*
X1497090Y1153689D01*
G02X1497687Y1152491I-905J-1199D01*
G02X1494683I-1502J0D01*
G02X1495244Y1153662I1503J0D01*
G01X1495280Y1153691D01*
X1495319Y1153774D01*
G37*
G36*
G01X1571883Y185330D02*
X1572018Y185710D01*
X1572008Y185800D01*
X1571984Y185839D01*
G02X1571759Y186629I1277J791D01*
G02X1574763I1502J0D01*
G02X1573760Y185212I-1502J0D01*
G01X1573716Y185197D01*
X1573653Y185133D01*
X1573518Y184753D01*
X1573528Y184663D01*
X1573552Y184624D01*
G02X1573777Y183834I-1277J-791D01*
G02X1570773I-1502J0D01*
G02X1571776Y185251I1502J0D01*
G01X1571820Y185266D01*
X1571883Y185330D01*
G37*
G36*
G01X1683376Y1224588D02*
G02X1683358Y1224802I1269J214D01*
G01Y1224803D01*
G02X1684645Y1223516I1287J0D01*
G01X1684644D01*
G02X1684430Y1223534I0J1287D01*
G03X1683967Y1223087I-66J-395D01*
G02X1683977Y1222933I-1192J-155D01*
G01Y1222932D01*
G02X1682775Y1224134I-1202J0D01*
G01X1682776D01*
G02X1682930Y1224124I-1J-1202D01*
G03X1683376Y1224588I52J397D01*
G37*
G36*
G01X1802710Y1466164D02*
G02X1802260Y1467236I1052J1072D01*
G02X1805264I1502J0D01*
G02X1804064Y1465765I-1502J0D01*
G03X1803865Y1465087I81J-392D01*
G02X1804315Y1464015I-1052J-1072D01*
G02X1801311I-1502J0D01*
G02X1802511Y1465486I1502J0D01*
G03X1802710Y1466164I-81J392D01*
G37*
G36*
G01X1597705Y147959D02*
X1597684Y147998D01*
G02X1597501Y148717I1319J719D01*
G02X1600505I1502J0D01*
G02X1599500Y147300I-1501J0D01*
G01X1599458Y147285D01*
X1599395Y147224D01*
X1599254Y146857D01*
X1599260Y146770D01*
X1599281Y146731D01*
G02X1599464Y146012I-1319J-719D01*
G02X1598804Y144768I-1502J0D01*
G03X1598716Y144603I112J-166D01*
G01Y144271D01*
G03X1598804Y144106I200J1D01*
G02X1599449Y143074I-842J-1244D01*
G01X1599454Y143037D01*
X1599488Y142974D01*
X1599746Y142754D01*
X1599812Y142729D01*
X1599850Y142730D01*
X1599868D01*
G02Y139726I0J-1502D01*
G02X1598381Y141016I0J1502D01*
G01X1598376Y141053D01*
X1598342Y141116D01*
X1598084Y141336D01*
X1598018Y141361D01*
X1597980Y141360D01*
X1597962D01*
G02X1596460Y142862I0J1502D01*
G02X1597120Y144106I1502J0D01*
G03X1597208Y144271I-112J166D01*
G01Y144603D01*
G03X1597120Y144768I-200J-1D01*
G02X1596460Y146012I842J1244D01*
G02X1597465Y147429I1501J0D01*
G01X1597507Y147444D01*
X1597570Y147505D01*
X1597711Y147872D01*
X1597705Y147959D01*
G37*
G36*
G01X1597563Y110018D02*
X1597879D01*
G03X1598036Y110095I-1J200D01*
G02X1599221Y110674I1185J-923D01*
G02X1600723Y109172I0J-1502D01*
G02X1599759Y107770I-1502J0D01*
G01X1599719Y107754D01*
X1599659Y107693D01*
X1599524Y107331D01*
X1599530Y107245D01*
X1599551Y107207D01*
G02X1599730Y106495I-1323J-711D01*
G02X1596726I-1502J0D01*
G02X1596864Y107123I1502J-1D01*
G01X1596887Y107173D01*
X1596875Y107283D01*
X1596598Y107653D01*
X1596496Y107694D01*
X1596442Y107686D01*
G02X1596221Y107670I-219J1486D01*
G02Y110674I0J1502D01*
G02X1597406Y110095I0J-1502D01*
G03X1597563Y110018I158J123D01*
G37*
G36*
G01X1610330Y105329D02*
X1610290Y105360D01*
G02X1609689Y106561I901J1202D01*
G02X1612693I1502J0D01*
G02X1611967Y105275I-1502J0D01*
G01X1611924Y105249D01*
X1611873Y105164D01*
X1611851Y104732D01*
X1611893Y104643D01*
X1611933Y104612D01*
G02X1612488Y103779I-901J-1202D01*
G01X1612500Y103731D01*
X1612566Y103658D01*
X1612969Y103509D01*
X1613065Y103522D01*
X1613106Y103550D01*
G02X1613972Y103825I866J-1226D01*
G02Y100821I0J-1502D01*
G02X1612516Y101955I0J1502D01*
G01X1612504Y102003D01*
X1612438Y102076D01*
X1612035Y102225D01*
X1611939Y102212D01*
X1611898Y102184D01*
G02X1611032Y101909I-866J1226D01*
G02X1609530Y103411I0J1502D01*
G02X1610256Y104697I1502J0D01*
G01X1610299Y104723D01*
X1610350Y104808D01*
X1610372Y105240D01*
X1610330Y105329D01*
G37*
G36*
G01X1666601Y102731D02*
G02X1666309Y103621I1210J890D01*
G02X1669313I1502J0D01*
G02X1668088Y102145I-1502J0D01*
G03X1667839Y101515I73J-393D01*
G02X1668131Y100625I-1210J-890D01*
G02X1665127I-1502J0D01*
G02X1666352Y102101I1502J0D01*
G03X1666601Y102731I-73J393D01*
G37*
G36*
G01X1631029Y101849D02*
G02X1630446Y103037I919J1188D01*
G02X1633450I1502J0D01*
G02X1632794Y101796I-1502J0D01*
G03X1632774Y101149I225J-331D01*
G02X1633357Y99961I-919J-1188D01*
G02X1630353I-1502J0D01*
G02X1631009Y101202I1502J0D01*
G03X1631029Y101849I-225J331D01*
G37*
G36*
G01X1625542Y91453D02*
G02X1624988Y91347I-554J1395D01*
G02X1626490Y92849I0J1502D01*
G02X1626444Y92481I-1502J1D01*
G03X1626980Y92011I388J-98D01*
G02X1627534Y92117I554J-1395D01*
G02X1626032Y90615I0J-1502D01*
G02X1626078Y90983I1502J-1D01*
G03X1625542Y91453I-388J98D01*
G37*
G36*
G01X1676381Y90701D02*
G02X1675711Y91951I831J1250D01*
G02X1678715I1502J0D01*
G02X1678065Y90714I-1502J0D01*
G03X1678070Y90051I227J-330D01*
G02X1678740Y88801I-831J-1250D01*
G02X1675736I-1502J0D01*
G02X1676386Y90038I1502J0D01*
G03X1676381Y90701I-227J330D01*
G37*
G36*
G01X1587790Y217133D02*
X1587496D01*
G03X1587349Y217068I1J-200D01*
G02X1586243Y216583I-1105J1017D01*
G02Y219587I0J1502D01*
G02X1587349Y219102I1J-1502D01*
G03X1587496Y219037I148J135D01*
G01X1587790D01*
G03X1587937Y219102I-1J200D01*
G02X1589043Y219587I1105J-1017D01*
G02Y216583I0J-1502D01*
G02X1587937Y217068I-1J1502D01*
G03X1587790Y217133I-148J-135D01*
G37*
G36*
G01X1593970Y205755D02*
X1593634D01*
X1593567Y205730D01*
X1593539Y205706D01*
G02X1592552Y205336I-987J1131D01*
G02Y208340I0J1502D01*
G02X1593539Y207970I0J-1501D01*
G01X1593567Y207946D01*
X1593634Y207921D01*
X1593970D01*
X1594037Y207946D01*
X1594065Y207970D01*
G02X1595052Y208340I987J-1131D01*
G02Y205336I0J-1502D01*
G02X1594065Y205706I0J1501D01*
G01X1594037Y205730D01*
X1593970Y205755D01*
G37*
G36*
G01X1587782Y202310D02*
X1587446D01*
X1587379Y202285D01*
X1587351Y202261D01*
G02X1586364Y201891I-987J1131D01*
G02Y204895I0J1502D01*
G02X1587351Y204525I0J-1501D01*
G01X1587379Y204501D01*
X1587446Y204476D01*
X1587782D01*
X1587849Y204501D01*
X1587877Y204525D01*
G02X1588864Y204895I987J-1131D01*
G02X1590361Y203517I0J-1502D01*
G01X1590364Y203474D01*
X1590405Y203400D01*
X1590712Y203168D01*
X1590793Y203149D01*
X1590836Y203157D01*
G02X1591123Y203185I289J-1474D01*
G02X1592625Y201683I0J-1502D01*
G02X1592140Y200577I-1502J-1D01*
G03X1592075Y200430I135J-148D01*
G01Y200136D01*
G03X1592140Y199989I200J1D01*
G02X1592625Y198883I-1017J-1105D01*
G02X1589621I-1502J0D01*
G02X1590106Y199989I1502J1D01*
G03X1590171Y200136I-135J148D01*
G01Y200430D01*
G03X1590106Y200577I-200J-1D01*
G02X1589626Y201559I1017J1105D01*
G01X1589623Y201602D01*
X1589582Y201676D01*
X1589275Y201908D01*
X1589194Y201927D01*
X1589151Y201919D01*
G02X1588864Y201891I-289J1474D01*
G02X1587877Y202261I0J1501D01*
G01X1587849Y202285D01*
X1587782Y202310D01*
G37*
G36*
G01X1590086Y196259D02*
X1590422D01*
X1590489Y196284D01*
X1590517Y196308D01*
G02X1591504Y196678I987J-1131D01*
G02X1592610Y196193I1J-1502D01*
G03X1592757Y196128I148J135D01*
G01X1593051D01*
G03X1593198Y196193I-1J200D01*
G02X1594304Y196678I1105J-1017D01*
G02Y193674I0J-1502D01*
G02X1593198Y194159I-1J1502D01*
G03X1593051Y194224I-148J-135D01*
G01X1592757D01*
G03X1592610Y194159I1J-200D01*
G02X1591504Y193674I-1105J1017D01*
G02X1590517Y194044I0J1501D01*
G01X1590489Y194068D01*
X1590422Y194093D01*
X1590086D01*
X1590019Y194068D01*
X1589991Y194044D01*
G02X1588017I-987J1131D01*
G01X1587989Y194068D01*
X1587922Y194093D01*
X1587586D01*
X1587519Y194068D01*
X1587491Y194044D01*
G02X1586504Y193674I-987J1131D01*
G02Y196678I0J1502D01*
G02X1587491Y196308I0J-1501D01*
G01X1587519Y196284D01*
X1587586Y196259D01*
X1587922D01*
X1587989Y196284D01*
X1588017Y196308D01*
G02X1589991I987J-1131D01*
G01X1590019Y196284D01*
X1590086Y196259D01*
G37*
G36*
G01X1604921Y137670D02*
X1605237Y137881D01*
X1605282Y137950D01*
X1605289Y137992D01*
G02X1606772Y139259I1483J-234D01*
G02Y136255I0J-1502D01*
G02X1606504Y136279I-1J1502D01*
G03X1606338Y136234I-36J-197D01*
G01X1606242Y136151D01*
G03X1606173Y135991I131J-151D01*
G02X1606174Y135915I-1801J-62D01*
G01Y132515D01*
G02X1606173Y132436I-1802J-17D01*
G03X1606242Y132276I200J-9D01*
G01X1606338Y132193D01*
G03X1606504Y132148I130J152D01*
G02X1606772Y132172I267J-1478D01*
G02X1607759Y131802I0J-1501D01*
G01X1607787Y131778D01*
X1607854Y131753D01*
X1608190D01*
X1608257Y131778D01*
X1608285Y131802D01*
G02X1609272Y132172I987J-1131D01*
G02X1610755Y130905I0J-1501D01*
G01X1610762Y130863D01*
X1610807Y130794D01*
X1611123Y130583D01*
X1611204Y130569D01*
X1611245Y130579D01*
G02X1611672Y130630I426J-1751D01*
G02X1612020Y130597I5J-1802D01*
G01X1612060Y130589D01*
X1612138Y130605D01*
X1612442Y130814D01*
X1612484Y130881D01*
X1612491Y130922D01*
G02X1613972Y132172I1481J-252D01*
G02Y129168I0J-1502D01*
G02X1613791Y129179I0J1502D01*
G03X1613633Y129128I-23J-199D01*
G01X1613539Y129043D01*
G03X1613473Y128888I134J-149D01*
G02X1613474Y128828I-1801J-60D01*
G01Y125428D01*
G02X1613473Y125365I-1802J-3D01*
G03X1613539Y125210I200J-6D01*
G01X1613633Y125125D01*
G03X1613791Y125074I135J148D01*
G02X1613972Y125085I181J-1491D01*
G02Y122081I0J-1502D01*
G02X1612491Y123333I0J1502D01*
G01X1612484Y123374D01*
X1612441Y123441D01*
X1612138Y123651D01*
X1612060Y123667D01*
X1612019Y123659D01*
G02X1611672Y123626I-343J1769D01*
G02X1611246Y123677I0J1802D01*
G01X1611204Y123687D01*
X1611123Y123672D01*
X1610807Y123462D01*
X1610762Y123392D01*
X1610756Y123350D01*
G02X1609272Y122081I-1484J233D01*
G02X1608284Y122451I-1J1502D01*
G01X1608257Y122476D01*
X1608190Y122501D01*
X1607853D01*
X1607787Y122476D01*
X1607759Y122452D01*
G02X1606772Y122082I-987J1131D01*
G02X1606504Y122106I-1J1502D01*
G03X1606338Y122061I-36J-197D01*
G01X1606242Y121978D01*
G03X1606173Y121818I131J-151D01*
G02X1606174Y121742I-1801J-62D01*
G01Y118342D01*
G02X1606173Y118263I-1802J-17D01*
G03X1606242Y118103I200J-9D01*
G01X1606338Y118020D01*
G03X1606504Y117975I130J152D01*
G02X1606772Y117999I267J-1478D01*
G02X1607759Y117629I0J-1501D01*
G01X1607787Y117605D01*
X1607854Y117580D01*
X1608190D01*
X1608257Y117605D01*
X1608285Y117629D01*
G02X1609272Y117999I987J-1131D01*
G02X1610755Y116732I0J-1501D01*
G01X1610762Y116690D01*
X1610807Y116621D01*
X1611123Y116410D01*
X1611204Y116396D01*
X1611245Y116406D01*
G02X1611672Y116458I430J-1751D01*
G02X1612020Y116424I0J-1803D01*
G01X1612060Y116416D01*
X1612138Y116432D01*
X1612442Y116641D01*
X1612484Y116708D01*
X1612491Y116749D01*
G02X1613972Y117998I1481J-254D01*
G02Y114994I0J-1502D01*
G02X1613791Y115005I0J1502D01*
G03X1613633Y114954I-23J-199D01*
G01X1613539Y114869D01*
G03X1613474Y114714I135J-148D01*
G01Y111255D01*
G02X1613473Y111192I-1802J-3D01*
G03X1613539Y111037I200J-6D01*
G01X1613633Y110952D01*
G03X1613791Y110901I135J148D01*
G02X1613972Y110912I181J-1491D01*
G02Y107908I0J-1502D01*
G02X1612491Y109160I0J1502D01*
G01X1612484Y109201D01*
X1612441Y109268D01*
X1612138Y109478D01*
X1612060Y109494D01*
X1612019Y109486D01*
G02X1611672Y109452I-348J1769D01*
G02X1611246Y109504I4J1803D01*
G01X1611204Y109514D01*
X1611123Y109499D01*
X1610807Y109289D01*
X1610762Y109219D01*
X1610756Y109177D01*
G02X1609272Y107908I-1484J233D01*
G02Y110912I0J1502D01*
G02X1609540Y110888I1J-1502D01*
G03X1609706Y110933I36J197D01*
G01X1609802Y111016D01*
G03X1609871Y111176I-131J151D01*
G02X1609870Y111255I1801J62D01*
G01Y114655D01*
G02X1609871Y114731I1802J14D01*
G03X1609802Y114891I-200J9D01*
G01X1609706Y114974D01*
G03X1609540Y115019I-130J-152D01*
G02X1609272Y114995I-267J1478D01*
G02X1608285Y115365I0J1501D01*
G01X1608257Y115389D01*
X1608190Y115414D01*
X1607854D01*
X1607787Y115389D01*
X1607759Y115365D01*
G02X1606772Y114995I-987J1131D01*
G02X1605288Y116264I0J1502D01*
G01X1605282Y116306D01*
X1605237Y116376D01*
X1604921Y116586D01*
X1604840Y116601D01*
X1604798Y116591D01*
G02X1604372Y116540I-426J1751D01*
G02X1603946Y116591I0J1802D01*
G01X1603904Y116601D01*
X1603823Y116586D01*
X1603507Y116376D01*
X1603462Y116306D01*
X1603456Y116264D01*
G02X1601972Y114995I-1484J233D01*
G02Y117999I0J1502D01*
G02X1602240Y117975I1J-1502D01*
G03X1602406Y118020I36J197D01*
G01X1602502Y118103D01*
G03X1602571Y118263I-131J151D01*
G02X1602570Y118342I1801J62D01*
G01Y121742D01*
G02X1602571Y121818I1802J14D01*
G03X1602502Y121978I-200J9D01*
G01X1602406Y122061D01*
G03X1602240Y122106I-130J-152D01*
G02X1601972Y122082I-267J1478D01*
G02Y125086I0J1502D01*
G02X1603455Y123819I0J-1501D01*
G01X1603462Y123777D01*
X1603507Y123708D01*
X1603823Y123497D01*
X1603904Y123483D01*
X1603945Y123493D01*
G02X1604372Y123544I426J-1751D01*
G02X1604799Y123493I1J-1802D01*
G01X1604840Y123483D01*
X1604921Y123497D01*
X1605237Y123708D01*
X1605282Y123777D01*
X1605289Y123819D01*
G02X1606772Y125086I1483J-234D01*
G02X1607760Y124716I1J-1502D01*
G01X1607787Y124691D01*
X1607854Y124666D01*
X1608191D01*
X1608257Y124691D01*
X1608285Y124715D01*
G02X1609272Y125085I987J-1131D01*
G02X1609540Y125061I1J-1502D01*
G03X1609706Y125106I36J197D01*
G01X1609802Y125189D01*
G03X1609871Y125349I-131J151D01*
G02X1609870Y125428I1801J62D01*
G01Y128828D01*
G02X1609871Y128904I1802J14D01*
G03X1609802Y129064I-200J9D01*
G01X1609706Y129147D01*
G03X1609540Y129192I-130J-152D01*
G02X1609272Y129168I-267J1478D01*
G02X1608285Y129538I0J1501D01*
G01X1608257Y129562D01*
X1608190Y129587D01*
X1607854D01*
X1607787Y129562D01*
X1607759Y129538D01*
G02X1606772Y129168I-987J1131D01*
G02X1605288Y130437I0J1502D01*
G01X1605282Y130479D01*
X1605237Y130549D01*
X1604921Y130759D01*
X1604840Y130774D01*
X1604798Y130764D01*
G02X1604372Y130712I-430J1751D01*
G02X1603946Y130764I4J1803D01*
G01X1603904Y130774D01*
X1603823Y130759D01*
X1603507Y130549D01*
X1603462Y130479D01*
X1603456Y130437D01*
G02X1601972Y129168I-1484J233D01*
G02Y132172I0J1502D01*
G02X1602240Y132148I1J-1502D01*
G03X1602406Y132193I36J197D01*
G01X1602502Y132276D01*
G03X1602571Y132436I-131J151D01*
G02X1602570Y132515I1801J62D01*
G01Y135915D01*
G02X1602571Y135991I1802J14D01*
G03X1602502Y136151I-200J9D01*
G01X1602406Y136234D01*
G03X1602240Y136279I-130J-152D01*
G02X1601972Y136255I-267J1478D01*
G02Y139259I0J1502D01*
G02X1603455Y137992I0J-1501D01*
G01X1603462Y137950D01*
X1603507Y137881D01*
X1603823Y137670D01*
X1603904Y137656D01*
X1603945Y137666D01*
G02X1604372Y137718I430J-1751D01*
G02X1604799Y137666I-3J-1803D01*
G01X1604840Y137656D01*
X1604921Y137670D01*
G37*
G36*
G01X1621392Y84108D02*
Y84460D01*
X1621364Y84529D01*
X1621338Y84557D01*
G02X1620932Y85584I1096J1027D01*
G02X1623936I1502J0D01*
G02X1623530Y84557I-1502J0D01*
G01X1623504Y84529D01*
X1623476Y84460D01*
Y84108D01*
X1623504Y84039D01*
X1623530Y84011D01*
G02Y81957I-1096J-1027D01*
G01X1623504Y81929D01*
X1623476Y81860D01*
Y81508D01*
X1623504Y81439D01*
X1623530Y81411D01*
G02Y79357I-1096J-1027D01*
G01X1623504Y79329D01*
X1623476Y79260D01*
Y78908D01*
X1623504Y78839D01*
X1623530Y78811D01*
G02Y76757I-1096J-1027D01*
G01X1623504Y76729D01*
X1623476Y76660D01*
Y76308D01*
X1623504Y76239D01*
X1623530Y76211D01*
G02X1623936Y75184I-1096J-1027D01*
G02X1620932I-1502J0D01*
G02X1621338Y76211I1502J0D01*
G01X1621364Y76239D01*
X1621392Y76308D01*
Y76660D01*
X1621364Y76729D01*
X1621338Y76757D01*
G02Y78811I1096J1027D01*
G01X1621364Y78839D01*
X1621392Y78908D01*
Y79260D01*
X1621364Y79329D01*
X1621338Y79357D01*
G02Y81411I1096J1027D01*
G01X1621364Y81439D01*
X1621392Y81508D01*
Y81860D01*
X1621364Y81929D01*
X1621338Y81957D01*
G02Y84011I1096J1027D01*
G01X1621364Y84039D01*
X1621392Y84108D01*
G37*
G36*
G01X1639727Y84063D02*
Y84415D01*
X1639699Y84484D01*
X1639673Y84512D01*
G02X1639267Y85539I1096J1027D01*
G02X1642271I1502J0D01*
G02X1641865Y84512I-1502J0D01*
G01X1641839Y84484D01*
X1641811Y84415D01*
Y84063D01*
X1641839Y83994D01*
X1641865Y83966D01*
G02Y81912I-1096J-1027D01*
G01X1641839Y81884D01*
X1641811Y81815D01*
Y81463D01*
X1641839Y81394D01*
X1641865Y81366D01*
G02Y79312I-1096J-1027D01*
G01X1641839Y79284D01*
X1641811Y79215D01*
Y78863D01*
X1641839Y78794D01*
X1641865Y78766D01*
G02Y76712I-1096J-1027D01*
G01X1641839Y76684D01*
X1641811Y76615D01*
Y76263D01*
X1641839Y76194D01*
X1641865Y76166D01*
G02X1642271Y75139I-1096J-1027D01*
G02X1639267I-1502J0D01*
G02X1639673Y76166I1502J0D01*
G01X1639699Y76194D01*
X1639727Y76263D01*
Y76615D01*
X1639699Y76684D01*
X1639673Y76712D01*
G02Y78766I1096J1027D01*
G01X1639699Y78794D01*
X1639727Y78863D01*
Y79215D01*
X1639699Y79284D01*
X1639673Y79312D01*
G02Y81366I1096J1027D01*
G01X1639699Y81394D01*
X1639727Y81463D01*
Y81815D01*
X1639699Y81884D01*
X1639673Y81912D01*
G02Y83966I1096J1027D01*
G01X1639699Y83994D01*
X1639727Y84063D01*
G37*
G36*
G01X1664156Y75446D02*
X1663784Y75386D01*
X1663715Y75341D01*
X1663691Y75306D01*
G02X1662442Y74638I-1249J834D01*
G02Y77642I0J1502D01*
G02X1663363Y77327I1J-1502D01*
G01X1663396Y77301D01*
X1663476Y77281D01*
X1663848Y77341D01*
X1663917Y77386D01*
X1663941Y77421D01*
G02X1665190Y78089I1249J-834D01*
G02Y75085I0J-1502D01*
G02X1664269Y75400I-1J1502D01*
G01X1664236Y75426D01*
X1664156Y75446D01*
G37*
G36*
G01X1596012Y236121D02*
G02X1599016I1502J0D01*
G02X1598366Y234884I-1502J0D01*
G03X1598372Y234222I227J-329D01*
G02X1599042Y232971I-833J-1251D01*
G02X1596038I-1502J0D01*
G02X1596688Y234208I1502J0D01*
G03X1596682Y234870I-227J329D01*
G02X1596012Y236121I833J1251D01*
G37*
G36*
G01X1594054Y221970D02*
G02X1597058I1502J0D01*
G02X1596688Y220983I-1501J0D01*
G01X1596664Y220955D01*
X1596639Y220888D01*
Y220552D01*
X1596664Y220485D01*
X1596688Y220457D01*
G02Y218483I-1131J-987D01*
G01X1596664Y218455D01*
X1596639Y218388D01*
Y218052D01*
X1596664Y217985D01*
X1596688Y217957D01*
G02X1597058Y216970I-1131J-987D01*
G02X1595556Y215468I-1502J0D01*
G02X1594701Y215735I0J1502D01*
G01X1594667Y215759D01*
X1594586Y215775D01*
X1594219Y215696D01*
X1594152Y215648D01*
X1594131Y215612D01*
G02X1592843Y214883I-1288J773D01*
G02Y217887I0J1502D01*
G02X1593698Y217620I0J-1502D01*
G01X1593732Y217596D01*
X1593813Y217580D01*
X1594180Y217659D01*
X1594247Y217707D01*
X1594268Y217743D01*
G02X1594424Y217957I1287J-774D01*
G01X1594448Y217985D01*
X1594473Y218052D01*
Y218388D01*
X1594448Y218455D01*
X1594424Y218483D01*
G02Y220457I1131J987D01*
G01X1594448Y220485D01*
X1594473Y220552D01*
Y220888D01*
X1594448Y220955D01*
X1594424Y220983D01*
G02X1594054Y221970I1131J987D01*
G37*
G36*
G01X1651752Y223294D02*
Y223630D01*
X1651727Y223697D01*
X1651703Y223725D01*
G02X1651333Y224712I1131J987D01*
G02X1654337I1502J0D01*
G02X1653967Y223725I-1501J0D01*
G01X1653943Y223697D01*
X1653918Y223630D01*
Y223294D01*
X1653943Y223227D01*
X1653967Y223199D01*
G02X1654337Y222212I-1131J-987D01*
G02X1651333I-1502J0D01*
G02X1651703Y223199I1501J0D01*
G01X1651727Y223227D01*
X1651752Y223294D01*
G37*
G36*
G01X1646427Y225189D02*
X1646133D01*
G03X1645986Y225124I1J-200D01*
G02X1644880Y224639I-1105J1017D01*
G02Y227643I0J1502D01*
G02X1645986Y227158I1J-1502D01*
G03X1646133Y227093I148J135D01*
G01X1646427D01*
G03X1646574Y227158I-1J200D01*
G02X1647680Y227643I1105J-1017D01*
G02Y224639I0J-1502D01*
G02X1646574Y225124I-1J1502D01*
G03X1646427Y225189I-148J-135D01*
G37*
G36*
G01X1629634Y229808D02*
Y230144D01*
X1629609Y230211D01*
X1629585Y230239D01*
G02X1629215Y231226I1131J987D01*
G02X1632219I1502J0D01*
G02X1631849Y230239I-1501J0D01*
G01X1631825Y230211D01*
X1631800Y230144D01*
Y229808D01*
X1631825Y229741D01*
X1631849Y229713D01*
G02Y227739I-1131J-987D01*
G01X1631825Y227711D01*
X1631800Y227644D01*
Y227308D01*
X1631825Y227241D01*
X1631849Y227213D01*
G02Y225239I-1131J-987D01*
G01X1631825Y225211D01*
X1631800Y225144D01*
Y224808D01*
X1631825Y224741D01*
X1631849Y224713D01*
G02X1632219Y223726I-1131J-987D01*
G02X1629215I-1502J0D01*
G02X1629585Y224713I1501J0D01*
G01X1629609Y224741D01*
X1629634Y224808D01*
Y225144D01*
X1629609Y225211D01*
X1629585Y225239D01*
G02Y227213I1131J987D01*
G01X1629609Y227241D01*
X1629634Y227308D01*
Y227644D01*
X1629609Y227711D01*
X1629585Y227739D01*
G02Y229713I1131J987D01*
G01X1629609Y229741D01*
X1629634Y229808D01*
G37*
G36*
G01X1640090Y230043D02*
Y230379D01*
X1640065Y230446D01*
X1640041Y230474D01*
G02X1639671Y231461I1131J987D01*
G02X1642675I1502J0D01*
G02X1642305Y230474I-1501J0D01*
G01X1642281Y230446D01*
X1642256Y230379D01*
Y230043D01*
X1642281Y229976D01*
X1642305Y229948D01*
G02Y227974I-1131J-987D01*
G01X1642281Y227946D01*
X1642256Y227879D01*
Y227543D01*
X1642281Y227476D01*
X1642305Y227448D01*
G02X1642675Y226461I-1131J-987D01*
G02X1642190Y225355I-1502J-1D01*
G03X1642125Y225208I135J-148D01*
G01Y224914D01*
G03X1642190Y224767I200J1D01*
G02X1642675Y223661I-1017J-1105D01*
G02X1639671I-1502J0D01*
G02X1640156Y224767I1502J1D01*
G03X1640221Y224914I-135J148D01*
G01Y225208D01*
G03X1640156Y225355I-200J-1D01*
G02X1639671Y226461I1017J1105D01*
G02X1640041Y227448I1501J0D01*
G01X1640065Y227476D01*
X1640090Y227543D01*
Y227879D01*
X1640065Y227946D01*
X1640041Y227974D01*
G02Y229948I1131J987D01*
G01X1640065Y229976D01*
X1640090Y230043D01*
G37*
G36*
G01X1648059Y230368D02*
Y230704D01*
X1648034Y230771D01*
X1648010Y230799D01*
G02X1647640Y231786I1131J987D01*
G02X1650644I1502J0D01*
G02X1650274Y230799I-1501J0D01*
G01X1650250Y230771D01*
X1650225Y230704D01*
Y230368D01*
X1650250Y230301D01*
X1650274Y230273D01*
G02X1650644Y229286I-1131J-987D01*
G02X1647640I-1502J0D01*
G02X1648010Y230273I1501J0D01*
G01X1648034Y230301D01*
X1648059Y230368D01*
G37*
G36*
G01X1646205Y237694D02*
X1646541D01*
X1646608Y237719D01*
X1646636Y237743D01*
G02X1648610I987J-1131D01*
G01X1648638Y237719D01*
X1648705Y237694D01*
X1649041D01*
X1649108Y237719D01*
X1649136Y237743D01*
G02X1650123Y238113I987J-1131D01*
G02Y235109I0J-1502D01*
G02X1649136Y235479I0J1501D01*
G01X1649108Y235503D01*
X1649041Y235528D01*
X1648705D01*
X1648638Y235503D01*
X1648610Y235479D01*
G02X1646636I-987J1131D01*
G01X1646608Y235503D01*
X1646541Y235528D01*
X1646205D01*
X1646138Y235503D01*
X1646110Y235479D01*
G02X1645123Y235109I-987J1131D01*
G02Y238113I0J1502D01*
G02X1646110Y237743I0J-1501D01*
G01X1646138Y237719D01*
X1646205Y237694D01*
G37*
G36*
G01X1645907Y249974D02*
X1646243D01*
X1646310Y249999D01*
X1646338Y250023D01*
G02X1648312I987J-1131D01*
G01X1648340Y249999D01*
X1648407Y249974D01*
X1648743D01*
X1648810Y249999D01*
X1648838Y250023D01*
G02X1649825Y250393I987J-1131D01*
G02Y247389I0J-1502D01*
G02X1648838Y247759I0J1501D01*
G01X1648810Y247783D01*
X1648743Y247808D01*
X1648407D01*
X1648340Y247783D01*
X1648312Y247759D01*
G02X1646338I-987J1131D01*
G01X1646310Y247783D01*
X1646243Y247808D01*
X1645907D01*
X1645840Y247783D01*
X1645812Y247759D01*
G02X1644825Y247389I-987J1131D01*
G02Y250393I0J1502D01*
G02X1645812Y250023I0J-1501D01*
G01X1645840Y249999D01*
X1645907Y249974D01*
G37*
G36*
G01X1650202Y190705D02*
G02X1649554Y191941I855J1236D01*
G02X1652558I1502J0D01*
G02X1651805Y190639I-1502J0D01*
G03X1651777Y189963I199J-347D01*
G02X1652425Y188727I-855J-1236D01*
G02X1649421I-1502J0D01*
G02X1650174Y190029I1502J0D01*
G03X1650202Y190705I-199J347D01*
G37*
G36*
G01X1714728Y330489D02*
G02X1714088Y331719I862J1230D01*
G02X1717092I1502J0D01*
G02X1716544Y330558I-1502J-1D01*
G01X1716507Y330529D01*
X1716469Y330444D01*
X1716482Y330078D01*
G03X1716507Y329989I200J8D01*
G03X1716567Y329922I175J97D01*
G02X1717207Y328692I-862J-1230D01*
G02X1717087Y328104I-1501J0D01*
G01X1717071Y328066D01*
Y327987D01*
X1717213Y327647D01*
X1717270Y327591D01*
X1717308Y327576D01*
G02X1718257Y326179I-554J-1397D01*
G02X1715253I-1502J0D01*
G02X1715373Y326767I1501J0D01*
G01X1715389Y326805D01*
Y326884D01*
X1715247Y327224D01*
X1715190Y327280D01*
X1715152Y327295D01*
G02X1714203Y328692I554J1397D01*
G02X1714751Y329853I1502J1D01*
G01X1714788Y329882D01*
X1714826Y329967D01*
X1714813Y330333D01*
G03X1714788Y330422I-200J-8D01*
G03X1714728Y330489I-175J-97D01*
G37*
G36*
G01X1672361Y330773D02*
G02X1671701Y332017I842J1244D01*
G02X1674705I1502J0D01*
G02X1674045Y330773I-1502J0D01*
G03Y330111I224J-331D01*
G02X1674705Y328867I-842J-1244D01*
G02X1671701I-1502J0D01*
G02X1672361Y330111I1502J0D01*
G03Y330773I-224J331D01*
G37*
G36*
G01X1607346Y330950D02*
G02X1606445Y332326I600J1376D01*
G02X1609449I1502J0D01*
G02X1608780Y331076I-1502J0D01*
G03X1608841Y330376I221J-333D01*
G02X1609742Y329000I-600J-1376D01*
G02X1606738I-1502J0D01*
G02X1607407Y330250I1502J0D01*
G03X1607346Y330950I-221J333D01*
G37*
G36*
G01X1628354Y333236D02*
X1628324Y333262D01*
G02X1627800Y334402I978J1140D01*
G02X1630804I1502J0D01*
G02X1630447Y333430I-1502J0D01*
G01X1630446Y333429D01*
G03X1630400Y333285I154J-128D01*
G01X1630426Y332962D01*
X1630462Y332893D01*
X1630492Y332867D01*
G02X1630987Y332022I-978J-1140D01*
G01X1630996Y331976D01*
X1631053Y331902D01*
X1631337Y331763D01*
G03X1631425Y331743I87J180D01*
G01X1631557D01*
X1631597Y331762D01*
G02X1632230Y331902I633J-1362D01*
G02Y328898I0J-1502D01*
G02X1631588Y329043I2J1502D01*
G01X1631546Y329063D01*
X1631456Y329062D01*
X1631089Y328881D01*
X1631033Y328807D01*
X1631024Y328762D01*
G02X1629553Y327565I-1471J305D01*
G02X1628051Y329067I0J1502D01*
G02X1628463Y330101I1504J0D01*
G01X1628464Y330102D01*
X1628465Y330103D01*
G03X1628519Y330242I-146J137D01*
G01X1628515Y330522D01*
G03X1628456Y330661I-200J-3D01*
G02X1628012Y331727I1058J1066D01*
G02X1628369Y332699I1502J0D01*
G01X1628370Y332700D01*
G03X1628416Y332844I-154J128D01*
G01X1628390Y333167D01*
X1628354Y333236D01*
G37*
G36*
G01X1713889Y341495D02*
G03X1714561Y341586I308J256D01*
G02X1715930Y342471I1369J-616D01*
G02Y339467I0J-1502D01*
G01X1715929D01*
G02X1714775Y340008I0J1502D01*
G03X1714103Y339917I-308J-256D01*
G02X1712734Y339032I-1369J616D01*
G02Y342036I0J1502D01*
G01X1712735D01*
G02X1713889Y341495I0J-1502D01*
G37*
G36*
G01X1593607Y342663D02*
G02X1595109Y341161I1502J0D01*
G02X1595000Y341165I1J1502D01*
G03X1594818Y341075I-15J-199D01*
G01X1594596Y340736D01*
X1594591Y340628D01*
X1594617Y340579D01*
G02X1594792Y339876I-1327J-704D01*
G01Y339875D01*
G02X1594712Y339392I-1502J1D01*
G01X1594696Y339345D01*
X1594710Y339252D01*
X1594953Y338907D01*
X1595037Y338864D01*
X1595086Y338863D01*
G02X1596571Y337361I-17J-1502D01*
G02X1593567I-1502J0D01*
G01Y337362D01*
G02X1593647Y337845I1502J-1D01*
G01X1593663Y337892D01*
X1593649Y337985D01*
X1593406Y338330D01*
X1593322Y338373D01*
X1593273Y338374D01*
G02X1591788Y339876I17J1502D01*
G02X1593290Y341378I1502J0D01*
G02X1593399Y341374I-1J-1502D01*
G03X1593581Y341464I15J199D01*
G01X1593803Y341803D01*
X1593808Y341911D01*
X1593782Y341960D01*
G02X1593607Y342663I1327J704D01*
G37*
G36*
G01X1604550Y344294D02*
Y344296D01*
G02X1605966Y345296I1416J-503D01*
G02Y342292I0J-1502D01*
G02X1605565Y342347I2J1502D01*
G01X1605563D01*
G03X1605418Y342332I-53J-193D01*
G01X1605176Y342205D01*
G03X1605080Y342096I92J-178D01*
G01Y342094D01*
G02X1603664Y341094I-1416J503D01*
G02Y344098I0J1502D01*
G02X1604065Y344043I-2J-1502D01*
G01X1604067D01*
G03X1604212Y344058I53J193D01*
G01X1604454Y344185D01*
G03X1604550Y344294I-92J178D01*
G37*
G36*
G01X1635382Y344557D02*
G02X1634966Y345595I1087J1038D01*
G02X1637970I1502J0D01*
G02X1637627Y344640I-1501J0D01*
G03X1637582Y344505I155J-127D01*
G01X1637592Y344240D01*
G03X1637647Y344110I200J8D01*
G02X1638063Y343072I-1087J-1038D01*
G02X1635059I-1502J0D01*
G02X1635402Y344027I1501J0D01*
G03X1635447Y344162I-155J127D01*
G01X1635437Y344427D01*
G03X1635382Y344557I-200J-8D01*
G37*
G36*
G01X1629900Y349385D02*
G02X1629201Y350655I804J1270D01*
G02X1632205I1502J0D01*
G02X1631496Y349379I-1503J0D01*
G03X1631494Y348702I211J-339D01*
G02X1632193Y347432I-804J-1270D01*
G02X1629189I-1502J0D01*
G02X1629898Y348708I1503J0D01*
G03X1629900Y349385I-211J339D01*
G37*
G36*
G01X1689827Y354326D02*
G03X1690490Y354334I329J228D01*
G02X1691743Y355008I1253J-828D01*
G02Y352004I0J-1502D01*
G02X1690509Y352650I0J1502D01*
G03X1689846Y352642I-329J-228D01*
G02X1688593Y351968I-1253J828D01*
G02Y354972I0J1502D01*
G02X1689827Y354326I0J-1502D01*
G37*
G36*
G01X1664825Y354219D02*
G03X1665500Y354298I313J249D01*
G02X1666860Y355163I1360J-637D01*
G02Y352159I0J-1502D01*
G02X1665685Y352725I0J1503D01*
G03X1665010Y352646I-313J-249D01*
G02X1663650Y351781I-1360J637D01*
G02Y354785I0J1502D01*
G02X1664825Y354219I0J-1503D01*
G37*
G36*
G01X1596253Y374131D02*
G02Y377135I0J1502D01*
G01X1596254D01*
G02X1597404Y376599I0J-1502D01*
G01X1597433Y376565D01*
X1597510Y376528D01*
X1597901Y376522D01*
X1597979Y376557D01*
X1598008Y376589D01*
G02X1599127Y377089I1119J-1002D01*
G02Y374085I0J-1502D01*
G01X1599126D01*
G02X1597976Y374621I0J1502D01*
G01X1597947Y374655D01*
X1597870Y374692D01*
X1597479Y374698D01*
X1597401Y374663D01*
X1597372Y374631D01*
G02X1596253Y374131I-1119J1002D01*
G37*
G36*
G01X1735794Y377648D02*
G03X1736416Y377789I258J306D01*
G02X1737786Y378675I1370J-616D01*
G02Y375671I0J-1502D01*
G01X1737785D01*
G02X1736818Y376024I0J1502D01*
G03X1736196Y375883I-258J-306D01*
G02X1734826Y374997I-1370J616D01*
G02Y378001I0J1502D01*
G01X1734827D01*
G02X1735794Y377648I0J-1502D01*
G37*
G36*
G01X1653735Y373017D02*
X1653726Y373035D01*
G02X1658026Y370692I3784J1827D01*
G03X1657941Y370661I24J-198D01*
G01X1657940D01*
G03X1657877Y370595I110J-168D01*
G01X1657716Y370322D01*
G03X1657689Y370233I173J-101D01*
G01X1657686Y370188D01*
X1657703Y370145D01*
Y370144D01*
G02X1657972Y368760I-3433J-1385D01*
G02X1654270Y365058I-3702J0D01*
G01X1646970D01*
G02Y372462I0J3702D01*
G01X1653365D01*
G03X1653535Y372555I1J200D01*
G01X1653715Y372842D01*
G03X1653740Y372997I-169J107D01*
G01X1653735Y373017D01*
G37*
G36*
G01X1763995Y379589D02*
Y379591D01*
G02X1765497Y378089I1502J0D01*
G01X1765496D01*
G02X1765016Y378168I1J1502D01*
G03X1764490Y377746I-128J-379D01*
G02X1764499Y377583I-1493J-164D01*
G01Y377581D01*
G02X1762997Y379083I-1502J0D01*
G01X1762998D01*
G02X1763478Y379004I-1J-1502D01*
G03X1764004Y379426I128J379D01*
G02X1763995Y379589I1493J164D01*
G37*
G36*
G01X1639618Y380325D02*
G03X1640307Y380338I341J210D01*
G02X1641615Y381102I1308J-738D01*
G02Y378098I0J-1502D01*
G02X1640337Y378811I0J1502D01*
G03X1639648Y378798I-341J-210D01*
G02X1638340Y378034I-1308J738D01*
G02Y381038I0J1502D01*
G02X1639618Y380325I0J-1502D01*
G37*
G36*
G01X1595862Y381766D02*
G02X1595212Y383003I852J1237D01*
G02X1598216I1502J0D01*
G02X1597424Y381679I-1503J0D01*
G03X1597386Y380997I189J-353D01*
G02X1598036Y379760I-852J-1237D01*
G02X1595032I-1502J0D01*
G02X1595824Y381084I1503J0D01*
G03X1595862Y381766I-189J353D01*
G37*
G36*
G01X1732089Y385969D02*
X1732403D01*
G03X1732561Y386046I0J200D01*
G02X1733746Y386625I1185J-923D01*
G02Y383621I0J-1502D01*
G02X1732561Y384200I0J1502D01*
G03X1732403Y384277I-158J-123D01*
G01X1732089D01*
G03X1731931Y384200I0J-200D01*
G02X1730746Y383621I-1185J923D01*
G02Y386625I0J1502D01*
G02X1731931Y386046I0J-1502D01*
G03X1732089Y385969I158J123D01*
G37*
G36*
G01X1776573Y386136D02*
X1776549Y386164D01*
G02X1776179Y387151I1131J987D01*
G02X1779183I1502J0D01*
G02X1778856Y386216I-1500J0D01*
G01X1778835Y386189D01*
X1778813Y386127D01*
Y385963D01*
X1778764D01*
Y385732D01*
X1778789Y385666D01*
X1778813Y385638D01*
G02X1778856Y383716I-1132J-987D01*
G01X1778835Y383689D01*
X1778813Y383627D01*
Y383463D01*
X1778764D01*
Y383232D01*
X1778789Y383166D01*
X1778813Y383138D01*
G02X1779183Y382151I-1131J-987D01*
G02X1776179I-1502J0D01*
G02X1776506Y383086I1500J0D01*
G01X1776527Y383113D01*
X1776549Y383175D01*
Y383339D01*
X1776598D01*
Y383570D01*
X1776573Y383636D01*
X1776549Y383664D01*
G02X1776506Y385586I1132J987D01*
G01X1776527Y385613D01*
X1776549Y385675D01*
Y385839D01*
X1776598D01*
Y386070D01*
X1776573Y386136D01*
G37*
G36*
G01X1770967Y388654D02*
X1771259D01*
G03X1771407Y388719I0J200D01*
G02X1772513Y389204I1106J-1019D01*
G02Y386200I0J-1502D01*
G02X1771407Y386685I0J1504D01*
G03X1771259Y386750I-148J-135D01*
G01X1770967D01*
G03X1770819Y386685I0J-200D01*
G02X1769713Y386200I-1106J1019D01*
G02Y389204I0J1502D01*
G02X1770819Y388719I0J-1504D01*
G03X1770967Y388654I148J135D01*
G37*
G36*
G01X1764212Y390021D02*
X1764537Y390092D01*
X1764604Y390140D01*
X1764625Y390176D01*
G02X1765913Y390904I1288J-775D01*
G02Y387900I0J-1502D01*
G02X1765059Y388166I0J1503D01*
G01X1765058Y388167D01*
X1765024Y388190D01*
X1764985Y388198D01*
G03X1764901I-42J-196D01*
G01X1764575Y388127D01*
X1764510Y388080D01*
X1764488Y388044D01*
G02X1764333Y387832I-1285J777D01*
G01X1764309Y387804D01*
X1764295Y387768D01*
G03X1764283Y387699I188J-68D01*
G01Y387398D01*
X1764308Y387332D01*
X1764332Y387304D01*
G02X1764375Y385382I-1132J-987D01*
G01X1764354Y385355D01*
X1764332Y385293D01*
Y385129D01*
X1764283D01*
Y384898D01*
X1764308Y384832D01*
X1764332Y384804D01*
G02X1764702Y383817I-1131J-987D01*
G02X1761698I-1502J0D01*
G02X1762025Y384752I1500J0D01*
G01X1762046Y384779D01*
X1762068Y384841D01*
Y385005D01*
X1762117D01*
Y385236D01*
X1762092Y385302D01*
X1762068Y385330D01*
G02X1762025Y387252I1132J987D01*
G01X1762046Y387279D01*
X1762068Y387341D01*
Y387505D01*
X1762117D01*
Y387736D01*
X1762092Y387802D01*
X1762068Y387830D01*
G02X1761698Y388817I1131J987D01*
G02X1763200Y390319I1502J0D01*
G02X1764054Y390053I0J-1503D01*
G01X1764055Y390052D01*
X1764089Y390029D01*
X1764128Y390021D01*
G03X1764212I42J196D01*
G37*
G36*
G01X1646929Y391342D02*
G03X1647591I331J224D01*
G02X1648835Y392002I1244J-842D01*
G02Y388998I0J-1502D01*
G02X1647591Y389658I0J1502D01*
G03X1646929I-331J-224D01*
G02X1645685Y388998I-1244J842D01*
G02Y392002I0J1502D01*
G02X1646929Y391342I0J-1502D01*
G37*
G36*
G01X1755812Y399361D02*
X1756043D01*
X1756109Y399386D01*
X1756137Y399410D01*
G02X1757124Y399780I987J-1131D01*
G02Y396776I0J-1502D01*
G02X1756189Y397103I0J1500D01*
G01X1756162Y397124D01*
X1756100Y397146D01*
X1755936D01*
Y397195D01*
X1755705D01*
X1755639Y397170D01*
X1755611Y397146D01*
G02X1754624Y396776I-987J1131D01*
G02Y399780I0J1502D01*
G02X1755559Y399453I0J-1500D01*
G01X1755586Y399432D01*
X1755648Y399410D01*
X1755812D01*
Y399361D01*
G37*
G36*
G01X1776995Y400646D02*
X1776971Y400674D01*
G02X1776601Y401661I1131J987D01*
G02X1779605I1502J0D01*
G02X1779278Y400726I-1500J0D01*
G01X1779257Y400699D01*
X1779235Y400637D01*
Y400473D01*
X1779186D01*
Y400242D01*
X1779211Y400176D01*
X1779235Y400148D01*
G02X1779278Y398226I-1132J-987D01*
G01X1779257Y398199D01*
X1779235Y398137D01*
Y397973D01*
X1779186D01*
Y397742D01*
X1779211Y397676D01*
X1779235Y397648D01*
G02X1779605Y396661I-1131J-987D01*
G02X1776601I-1502J0D01*
G02X1776928Y397596I1500J0D01*
G01X1776949Y397623D01*
X1776971Y397685D01*
Y397849D01*
X1777020D01*
Y398080D01*
X1776995Y398146D01*
X1776971Y398174D01*
G02X1776928Y400096I1132J987D01*
G01X1776949Y400123D01*
X1776971Y400185D01*
Y400349D01*
X1777020D01*
Y400580D01*
X1776995Y400646D01*
G37*
G36*
G01X1754039Y403064D02*
X1754270D01*
X1754336Y403089D01*
X1754364Y403113D01*
G02X1755351Y403483I987J-1131D01*
G02Y400479I0J-1502D01*
G02X1754416Y400806I0J1500D01*
G01X1754389Y400827D01*
X1754327Y400849D01*
X1754163D01*
Y400898D01*
X1753932D01*
X1753866Y400873D01*
X1753838Y400849D01*
G02X1752851Y400479I-987J1131D01*
G02Y403483I0J1502D01*
G02X1753786Y403156I0J-1500D01*
G01X1753813Y403135D01*
X1753875Y403113D01*
X1754039D01*
Y403064D01*
G37*
G36*
G01X1771966Y403725D02*
X1772197D01*
X1772263Y403750D01*
X1772291Y403774D01*
G02X1773278Y404144I987J-1131D01*
G02Y401140I0J-1502D01*
G02X1772343Y401467I0J1500D01*
G01X1772316Y401488D01*
X1772254Y401510D01*
X1772090D01*
Y401559D01*
X1771859D01*
X1771793Y401534D01*
X1771765Y401510D01*
G02X1770778Y401140I-987J1131D01*
G02Y404144I0J1502D01*
G02X1771713Y403817I0J-1500D01*
G01X1771740Y403796D01*
X1771802Y403774D01*
X1771966D01*
Y403725D01*
G37*
G36*
G01X1784109Y409323D02*
X1784447D01*
X1784513Y409348D01*
X1784541Y409372D01*
G02X1785528Y409742I987J-1131D01*
G02Y406738I0J-1502D01*
G02X1784593Y407065I0J1500D01*
G01X1784566Y407086D01*
X1784504Y407108D01*
X1784340D01*
Y407157D01*
X1784109D01*
X1784043Y407132D01*
X1784015Y407108D01*
G02X1782093Y407065I-987J1132D01*
G01X1782066Y407086D01*
X1782004Y407108D01*
X1781840D01*
Y407157D01*
X1781609D01*
X1781543Y407132D01*
X1781515Y407108D01*
G02X1780528Y406738I-987J1131D01*
G02Y409742I0J1502D01*
G02X1781463Y409415I0J-1500D01*
G01X1781490Y409394D01*
X1781552Y409372D01*
X1781716D01*
Y409323D01*
X1781947D01*
X1782013Y409348D01*
X1782041Y409372D01*
G02X1784015I987J-1131D01*
G01X1784043Y409348D01*
X1784109Y409323D01*
G37*
G36*
G01X1751530Y410385D02*
X1751844D01*
G03X1752002Y410462I0J200D01*
G02X1753187Y411041I1185J-923D01*
G02X1754689Y409539I0J-1502D01*
G02X1754362Y408604I-1500J0D01*
G01X1754341Y408577D01*
X1754319Y408515D01*
Y408351D01*
X1754270D01*
Y408120D01*
X1754295Y408054D01*
X1754319Y408026D01*
G02X1754689Y407039I-1131J-987D01*
G02X1753187Y405537I-1502J0D01*
G02X1752096Y406007I0J1501D01*
G01X1752094Y406009D01*
X1752090Y406013D01*
G03X1751929Y406071I-142J-141D01*
G01X1751614Y406040D01*
G03X1751463Y405947I19J-199D01*
G02X1750187Y405237I-1276J792D01*
G02X1748685Y406739I0J1502D01*
G02X1749170Y407845I1504J0D01*
G03X1749235Y407993I-135J148D01*
G01Y408285D01*
G03X1749170Y408433I-200J0D01*
G02X1748685Y409539I1019J1106D01*
G02X1750187Y411041I1502J0D01*
G02X1751372Y410462I0J-1502D01*
G03X1751530Y410385I158J123D01*
G37*
G36*
G01X1766616Y408798D02*
G02X1766131Y409904I1019J1106D01*
G02X1769135I1502J0D01*
G02X1768650Y408798I-1504J0D01*
G03X1768585Y408650I135J-148D01*
G01Y408358D01*
G03X1768650Y408210I200J0D01*
G02X1769135Y407104I-1019J-1106D01*
G02X1766131I-1502J0D01*
G02X1766616Y408210I1504J0D01*
G03X1766681Y408358I-135J148D01*
G01Y408650D01*
G03X1766616Y408798I-200J0D01*
G37*
G36*
G01X1755786Y414694D02*
X1756124D01*
X1756190Y414719D01*
X1756218Y414743D01*
G02X1757205Y415113I987J-1131D01*
G02Y412109I0J-1502D01*
G02X1756270Y412436I0J1500D01*
G01X1756243Y412457D01*
X1756181Y412479D01*
X1756017D01*
Y412528D01*
X1755786D01*
X1755720Y412503D01*
X1755692Y412479D01*
G02X1753770Y412436I-987J1132D01*
G01X1753743Y412457D01*
X1753681Y412479D01*
X1753517D01*
Y412528D01*
X1753286D01*
X1753220Y412503D01*
X1753192Y412479D01*
G02X1751270Y412436I-987J1132D01*
G01X1751243Y412457D01*
X1751181Y412479D01*
X1751017D01*
Y412528D01*
X1750786D01*
X1750720Y412503D01*
X1750692Y412479D01*
G02X1749705Y412109I-987J1131D01*
G02Y415113I0J1502D01*
G02X1750640Y414786I0J-1500D01*
G01X1750667Y414765D01*
X1750729Y414743D01*
X1750893D01*
Y414694D01*
X1751124D01*
X1751190Y414719D01*
X1751218Y414743D01*
G02X1753140Y414786I987J-1132D01*
G01X1753167Y414765D01*
X1753229Y414743D01*
X1753393D01*
Y414694D01*
X1753624D01*
X1753690Y414719D01*
X1753718Y414743D01*
G02X1755692I987J-1131D01*
G01X1755720Y414719D01*
X1755786Y414694D01*
G37*
G36*
G01X1771534D02*
X1771872D01*
X1771938Y414719D01*
X1771966Y414743D01*
G02X1772953Y415113I987J-1131D01*
G02Y412109I0J-1502D01*
G02X1772018Y412436I0J1500D01*
G01X1771991Y412457D01*
X1771929Y412479D01*
X1771765D01*
Y412528D01*
X1771534D01*
X1771468Y412503D01*
X1771440Y412479D01*
G02X1769518Y412436I-987J1132D01*
G01X1769491Y412457D01*
X1769429Y412479D01*
X1769265D01*
Y412528D01*
X1769034D01*
X1768968Y412503D01*
X1768940Y412479D01*
G02X1767953Y412109I-987J1131D01*
G02X1766847Y412594I0J1504D01*
G03X1766699Y412659I-148J-135D01*
G01X1766407D01*
G03X1766259Y412594I0J-200D01*
G02X1765153Y412109I-1106J1019D01*
G02Y415113I0J1502D01*
G02X1766259Y414628I0J-1504D01*
G03X1766407Y414563I148J135D01*
G01X1766699D01*
G03X1766847Y414628I0J200D01*
G02X1767953Y415113I1106J-1019D01*
G02X1768888Y414786I0J-1500D01*
G01X1768915Y414765D01*
X1768977Y414743D01*
X1769141D01*
Y414694D01*
X1769372D01*
X1769438Y414719D01*
X1769466Y414743D01*
G02X1771440I987J-1131D01*
G01X1771468Y414719D01*
X1771534Y414694D01*
G37*
G36*
G01X1784227Y421476D02*
X1784565D01*
X1784631Y421501D01*
X1784659Y421525D01*
G02X1785646Y421895I987J-1131D01*
G02Y418891I0J-1502D01*
G02X1784711Y419218I0J1500D01*
G01X1784684Y419239D01*
X1784622Y419261D01*
X1784458D01*
Y419310D01*
X1784227D01*
X1784161Y419285D01*
X1784133Y419261D01*
G02X1782211Y419218I-987J1132D01*
G01X1782184Y419239D01*
X1782122Y419261D01*
X1781958D01*
Y419310D01*
X1781727D01*
X1781661Y419285D01*
X1781633Y419261D01*
G02X1780646Y418891I-987J1131D01*
G02Y421895I0J1502D01*
G02X1781581Y421568I0J-1500D01*
G01X1781608Y421547D01*
X1781670Y421525D01*
X1781834D01*
Y421476D01*
X1782065D01*
X1782131Y421501D01*
X1782159Y421525D01*
G02X1784133I987J-1131D01*
G01X1784161Y421501D01*
X1784227Y421476D01*
G37*
G36*
G01X1724346Y420434D02*
X1724319Y420462D01*
G02X1723913Y421489I1096J1027D01*
G02X1726917I1502J0D01*
G02X1726511Y420462I-1502J0D01*
G01X1726484Y420434D01*
X1726457Y420364D01*
Y420014D01*
X1726484Y419944D01*
X1726511Y419916D01*
G02Y417862I-1096J-1027D01*
G01X1726484Y417834D01*
X1726457Y417764D01*
Y417414D01*
X1726484Y417344D01*
X1726511Y417316D01*
G02X1726917Y416289I-1096J-1027D01*
G02X1723913I-1502J0D01*
G02X1724319Y417316I1502J0D01*
G01X1724346Y417344D01*
X1724373Y417414D01*
Y417764D01*
X1724346Y417834D01*
X1724319Y417862D01*
G02Y419916I1096J1027D01*
G01X1724346Y419944D01*
X1724373Y420014D01*
Y420364D01*
X1724346Y420434D01*
G37*
G36*
G01X1646970Y417854D02*
G02Y425256I0J3701D01*
G01X1654270D01*
G02Y417854I0J-3701D01*
G01X1646970D01*
G37*
G36*
G01X1771474Y425027D02*
X1771812D01*
X1771878Y425052D01*
X1771906Y425076D01*
G02X1772893Y425446I987J-1131D01*
G02Y422442I0J-1502D01*
G02X1771958Y422769I0J1500D01*
G01X1771931Y422790D01*
X1771869Y422812D01*
X1771705D01*
Y422861D01*
X1771474D01*
X1771408Y422836D01*
X1771380Y422812D01*
G02X1769458Y422769I-987J1132D01*
G01X1769431Y422790D01*
X1769369Y422812D01*
X1769205D01*
Y422861D01*
X1768974D01*
X1768908Y422836D01*
X1768880Y422812D01*
G02X1767893Y422442I-987J1131D01*
G02X1766787Y422927I0J1504D01*
G03X1766639Y422992I-148J-135D01*
G01X1766347D01*
G03X1766199Y422927I0J-200D01*
G02X1765093Y422442I-1106J1019D01*
G02Y425446I0J1502D01*
G02X1766199Y424961I0J-1504D01*
G03X1766347Y424896I148J135D01*
G01X1766639D01*
G03X1766787Y424961I0J200D01*
G02X1767893Y425446I1106J-1019D01*
G02X1768828Y425119I0J-1500D01*
G01X1768855Y425098D01*
X1768917Y425076D01*
X1769081D01*
Y425027D01*
X1769312D01*
X1769378Y425052D01*
X1769406Y425076D01*
G02X1771380I987J-1131D01*
G01X1771408Y425052D01*
X1771474Y425027D01*
G37*
G36*
G01X1755551Y425150D02*
X1755889D01*
X1755955Y425175D01*
X1755983Y425199D01*
G02X1756970Y425569I987J-1131D01*
G02Y422565I0J-1502D01*
G02X1756035Y422892I0J1500D01*
G01X1756008Y422913D01*
X1755946Y422935D01*
X1755782D01*
Y422984D01*
X1755551D01*
X1755485Y422959D01*
X1755457Y422935D01*
G02X1753535Y422892I-987J1132D01*
G01X1753508Y422913D01*
X1753446Y422935D01*
X1753282D01*
Y422984D01*
X1753051D01*
X1752985Y422959D01*
X1752957Y422935D01*
G02X1751035Y422892I-987J1132D01*
G01X1751008Y422913D01*
X1750946Y422935D01*
X1750782D01*
Y422984D01*
X1750551D01*
X1750485Y422959D01*
X1750457Y422935D01*
G02X1749470Y422565I-987J1131D01*
G02Y425569I0J1502D01*
G02X1750405Y425242I0J-1500D01*
G01X1750432Y425221D01*
X1750494Y425199D01*
X1750658D01*
Y425150D01*
X1750889D01*
X1750955Y425175D01*
X1750983Y425199D01*
G02X1752905Y425242I987J-1132D01*
G01X1752932Y425221D01*
X1752994Y425199D01*
X1753158D01*
Y425150D01*
X1753389D01*
X1753455Y425175D01*
X1753483Y425199D01*
G02X1755457I987J-1131D01*
G01X1755485Y425175D01*
X1755551Y425150D01*
G37*
G36*
G01X1727846Y425634D02*
X1727819Y425662D01*
G02X1727413Y426689I1096J1027D01*
G02X1730417I1502J0D01*
G02X1730011Y425662I-1502J0D01*
G01X1729984Y425634D01*
X1729957Y425564D01*
Y425214D01*
X1729984Y425144D01*
X1730011Y425116D01*
G02Y423062I-1096J-1027D01*
G01X1729984Y423034D01*
X1729957Y422964D01*
Y422614D01*
X1729984Y422544D01*
X1730011Y422516D01*
G02Y420462I-1096J-1027D01*
G01X1729984Y420434D01*
X1729957Y420364D01*
Y420014D01*
X1729984Y419944D01*
X1730011Y419916D01*
G02Y417862I-1096J-1027D01*
G01X1729984Y417834D01*
X1729957Y417764D01*
Y417414D01*
X1729984Y417344D01*
X1730011Y417316D01*
G02Y415262I-1096J-1027D01*
G01X1729984Y415234D01*
X1729957Y415164D01*
Y414814D01*
X1729984Y414744D01*
X1730011Y414716D01*
G02Y412662I-1096J-1027D01*
G01X1729984Y412634D01*
X1729957Y412564D01*
Y412214D01*
X1729984Y412144D01*
X1730011Y412116D01*
G02Y410062I-1096J-1027D01*
G01X1729984Y410034D01*
X1729957Y409964D01*
Y409614D01*
X1729984Y409544D01*
X1730011Y409516D01*
G02Y407462I-1096J-1027D01*
G01X1729984Y407434D01*
X1729957Y407364D01*
Y407014D01*
X1729984Y406944D01*
X1730011Y406916D01*
G02X1730417Y405889I-1096J-1027D01*
G02X1730223Y405152I-1502J1D01*
G01X1730210Y405129D01*
X1730197Y405080D01*
Y404877D01*
G03X1730202Y404832I200J-1D01*
G01X1730245Y404646D01*
X1730290Y404583D01*
X1730323Y404562D01*
G02X1730818Y404034I-816J-1261D01*
G01X1730841Y403993D01*
X1730916Y403941D01*
X1731277Y403888D01*
G03X1731445Y403942I29J198D01*
G01X1731446Y403943D01*
G02X1732494Y404369I1048J-1076D01*
G02Y401365I0J-1502D01*
G02X1731184Y402133I0J1501D01*
G01X1731161Y402174D01*
X1731086Y402226D01*
X1730725Y402279D01*
G03X1730557Y402225I-29J-198D01*
G01X1730556Y402224D01*
G02X1729508Y401798I-1048J1076D01*
G02X1728006Y403300I0J1502D01*
G02X1728200Y404037I1502J-1D01*
G01X1728213Y404060D01*
X1728226Y404109D01*
Y404312D01*
G03X1728221Y404357I-200J1D01*
G01X1728178Y404543D01*
X1728133Y404606D01*
X1728100Y404627D01*
G02X1727413Y405889I816J1262D01*
G02X1727819Y406916I1502J0D01*
G01X1727846Y406944D01*
X1727873Y407014D01*
Y407364D01*
X1727846Y407434D01*
X1727819Y407462D01*
G02Y409516I1096J1027D01*
G01X1727846Y409544D01*
X1727873Y409614D01*
Y409964D01*
X1727846Y410034D01*
X1727819Y410062D01*
G02Y412116I1096J1027D01*
G01X1727846Y412144D01*
X1727873Y412214D01*
Y412564D01*
X1727846Y412634D01*
X1727819Y412662D01*
G02Y414716I1096J1027D01*
G01X1727846Y414744D01*
X1727873Y414814D01*
Y415164D01*
X1727846Y415234D01*
X1727819Y415262D01*
G02Y417316I1096J1027D01*
G01X1727846Y417344D01*
X1727873Y417414D01*
Y417764D01*
X1727846Y417834D01*
X1727819Y417862D01*
G02Y419916I1096J1027D01*
G01X1727846Y419944D01*
X1727873Y420014D01*
Y420364D01*
X1727846Y420434D01*
X1727819Y420462D01*
G02Y422516I1096J1027D01*
G01X1727846Y422544D01*
X1727873Y422614D01*
Y422964D01*
X1727846Y423034D01*
X1727819Y423062D01*
G02Y425116I1096J1027D01*
G01X1727846Y425144D01*
X1727873Y425214D01*
Y425564D01*
X1727846Y425634D01*
G37*
G36*
G01X1781999Y425725D02*
X1781975Y425753D01*
G02X1781605Y426740I1131J987D01*
G02X1784609I1502J0D01*
G02X1784282Y425805I-1500J0D01*
G01X1784261Y425778D01*
X1784239Y425716D01*
Y425552D01*
X1784190D01*
Y425321D01*
X1784215Y425255D01*
X1784239Y425227D01*
G02X1784609Y424240I-1131J-987D01*
G02X1781605I-1502J0D01*
G02X1781932Y425175I1500J0D01*
G01X1781953Y425202D01*
X1781975Y425264D01*
Y425428D01*
X1782024D01*
Y425659D01*
X1781999Y425725D01*
G37*
G36*
G01X1654587Y432439D02*
X1654555Y432468D01*
G02X1654074Y433570I1022J1102D01*
G02X1657078I1502J0D01*
G02X1656580Y432453I-1502J0D01*
G01X1656548Y432425D01*
X1656514Y432348D01*
X1656512Y431967D01*
X1656544Y431891D01*
X1656576Y431862D01*
G02X1657057Y430760I-1022J-1102D01*
G02X1654053I-1502J0D01*
G02X1654551Y431877I1502J0D01*
G01X1654583Y431905D01*
X1654617Y431982D01*
X1654619Y432363D01*
X1654587Y432439D01*
G37*
G36*
G01X1728285Y434412D02*
G02X1727800Y435518I1019J1106D01*
G02X1730804I1502J0D01*
G02X1730319Y434412I-1504J0D01*
G03X1730254Y434264I135J-148D01*
G01Y433972D01*
G03X1730319Y433824I200J0D01*
G02X1730804Y432718I-1019J-1106D01*
G02X1727800I-1502J0D01*
G02X1728285Y433824I1504J0D01*
G03X1728350Y433972I-135J148D01*
G01Y434264D01*
G03X1728285Y434412I-200J0D01*
G37*
G36*
G01X1636097Y439083D02*
X1636073Y439111D01*
G02X1635703Y440098I1131J987D01*
G02X1638707I1502J0D01*
G02X1638380Y439163I-1500J0D01*
G01X1638359Y439136D01*
X1638337Y439074D01*
Y438910D01*
X1638288D01*
Y438679D01*
X1638313Y438613D01*
X1638337Y438585D01*
G02X1638380Y436663I-1132J-987D01*
G01X1638359Y436636D01*
X1638337Y436574D01*
Y436410D01*
X1638288D01*
Y436179D01*
X1638313Y436113D01*
X1638337Y436085D01*
G02X1638380Y434163I-1132J-987D01*
G01X1638359Y434136D01*
X1638337Y434074D01*
Y433910D01*
X1638288D01*
Y433679D01*
X1638313Y433613D01*
X1638337Y433585D01*
G02X1638380Y431663I-1132J-987D01*
G01X1638359Y431636D01*
X1638337Y431574D01*
Y431410D01*
X1638288D01*
Y431179D01*
X1638313Y431113D01*
X1638337Y431085D01*
G02X1638707Y430098I-1131J-987D01*
G02X1635703I-1502J0D01*
G02X1636030Y431033I1500J0D01*
G01X1636051Y431060D01*
X1636073Y431122D01*
Y431286D01*
X1636122D01*
Y431517D01*
X1636097Y431583D01*
X1636073Y431611D01*
G02X1636030Y433533I1132J987D01*
G01X1636051Y433560D01*
X1636073Y433622D01*
Y433786D01*
X1636122D01*
Y434017D01*
X1636097Y434083D01*
X1636073Y434111D01*
G02X1636030Y436033I1132J987D01*
G01X1636051Y436060D01*
X1636073Y436122D01*
Y436286D01*
X1636122D01*
Y436517D01*
X1636097Y436583D01*
X1636073Y436611D01*
G02X1636030Y438533I1132J987D01*
G01X1636051Y438560D01*
X1636073Y438622D01*
Y438786D01*
X1636122D01*
Y439017D01*
X1636097Y439083D01*
G37*
G36*
G01X1664967Y441821D02*
X1665259D01*
G03X1665407Y441886I0J200D01*
G02X1666513Y442371I1106J-1019D01*
G02X1668015Y440869I0J-1502D01*
G02X1667609Y439842I-1502J0D01*
G01X1667582Y439814D01*
X1667555Y439744D01*
Y439394D01*
X1667582Y439324D01*
X1667609Y439296D01*
G02Y437242I-1096J-1027D01*
G01X1667582Y437214D01*
X1667555Y437144D01*
Y436794D01*
X1667582Y436724D01*
X1667609Y436696D01*
G02Y434642I-1096J-1027D01*
G01X1667582Y434614D01*
X1667555Y434544D01*
Y434194D01*
X1667582Y434124D01*
X1667609Y434096D01*
G02Y432042I-1096J-1027D01*
G01X1667582Y432014D01*
X1667555Y431944D01*
Y431594D01*
X1667582Y431524D01*
X1667609Y431496D01*
G02X1668015Y430469I-1096J-1027D01*
G02X1666513Y428967I-1502J0D01*
G02X1665407Y429452I0J1504D01*
G03X1665259Y429517I-148J-135D01*
G01X1664967D01*
G03X1664819Y429452I0J-200D01*
G02X1663713Y428967I-1106J1019D01*
G02X1662211Y430469I0J1502D01*
G02X1662617Y431496I1502J0D01*
G01X1662644Y431524D01*
X1662671Y431594D01*
Y431944D01*
X1662644Y432014D01*
X1662617Y432042D01*
G02Y434096I1096J1027D01*
G01X1662644Y434124D01*
X1662671Y434194D01*
Y434544D01*
X1662644Y434614D01*
X1662617Y434642D01*
G02Y436696I1096J1027D01*
G01X1662644Y436724D01*
X1662671Y436794D01*
Y437144D01*
X1662644Y437214D01*
X1662617Y437242D01*
G02Y439296I1096J1027D01*
G01X1662644Y439324D01*
X1662671Y439394D01*
Y439744D01*
X1662644Y439814D01*
X1662617Y439842D01*
G02X1662211Y440869I1096J1027D01*
G02X1663713Y442371I1502J0D01*
G02X1664819Y441886I0J-1504D01*
G03X1664967Y441821I148J135D01*
G37*
G36*
G01X1738162Y441012D02*
G02X1737677Y442118I1019J1106D01*
G02X1740681I1502J0D01*
G02X1740196Y441012I-1504J0D01*
G03X1740131Y440864I135J-148D01*
G01Y440572D01*
G03X1740196Y440424I200J0D01*
G02X1740681Y439318I-1019J-1106D01*
G02X1737677I-1502J0D01*
G02X1738162Y440424I1504J0D01*
G03X1738227Y440572I-135J148D01*
G01Y440864D01*
G03X1738162Y441012I-200J0D01*
G37*
G36*
G01X1746162D02*
G02X1745677Y442118I1019J1106D01*
G02X1748681I1502J0D01*
G02X1748196Y441012I-1504J0D01*
G03X1748131Y440864I135J-148D01*
G01Y440572D01*
G03X1748196Y440424I200J0D01*
G02X1748681Y439318I-1019J-1106D01*
G02X1745677I-1502J0D01*
G02X1746162Y440424I1504J0D01*
G03X1746227Y440572I-135J148D01*
G01Y440864D01*
G03X1746162Y441012I-200J0D01*
G37*
G36*
G01X1728285Y441412D02*
G02X1727800Y442518I1019J1106D01*
G02X1730804I1502J0D01*
G02X1730319Y441412I-1504J0D01*
G03X1730254Y441264I135J-148D01*
G01Y440972D01*
G03X1730319Y440824I200J0D01*
G02X1730804Y439718I-1019J-1106D01*
G02X1727800I-1502J0D01*
G02X1728285Y440824I1504J0D01*
G03X1728350Y440972I-135J148D01*
G01Y441264D01*
G03X1728285Y441412I-200J0D01*
G37*
G36*
G01X1654829Y441939D02*
X1654787Y441970D01*
G02X1654175Y443180I890J1210D01*
G02X1657179I1502J0D01*
G02X1656375Y441850I-1502J0D01*
G01X1656329Y441826D01*
X1656272Y441740D01*
X1656238Y441298D01*
X1656281Y441204D01*
X1656323Y441173D01*
G02X1656935Y439963I-890J-1210D01*
G02X1656393Y438808I-1502J0D01*
G01X1656359Y438780D01*
X1656322Y438701D01*
X1656316Y438354D01*
G03X1656317Y438327I200J-6D01*
G03X1656384Y438200I199J24D01*
G02X1656894Y437072I-992J-1128D01*
G02X1653890I-1502J0D01*
G02X1654432Y438227I1502J0D01*
G01X1654466Y438255D01*
X1654503Y438334D01*
X1654509Y438681D01*
G03X1654508Y438708I-200J6D01*
G03X1654441Y438835I-199J-24D01*
G02X1653931Y439963I992J1128D01*
G02X1654735Y441293I1502J0D01*
G01X1654781Y441317D01*
X1654838Y441403D01*
X1654872Y441845D01*
X1654829Y441939D01*
G37*
G36*
G01X1784638Y444673D02*
X1784930D01*
G03X1785078Y444738I0J200D01*
G02X1786184Y445223I1106J-1019D01*
G02X1787686Y443721I0J-1502D01*
G02X1787201Y442615I-1504J0D01*
G03X1787136Y442467I135J-148D01*
G01Y442175D01*
G03X1787201Y442027I200J0D01*
G02Y439815I-1017J-1106D01*
G03X1787136Y439667I135J-148D01*
G01Y439375D01*
G03X1787201Y439227I200J0D01*
G02Y437015I-1017J-1106D01*
G03X1787136Y436867I135J-148D01*
G01Y436575D01*
G03X1787201Y436427I200J0D01*
G02X1787686Y435321I-1019J-1106D01*
G02X1786184Y433819I-1502J0D01*
G02X1785078Y434304I0J1504D01*
G03X1784930Y434369I-148J-135D01*
G01X1784638D01*
G03X1784490Y434304I0J-200D01*
G02X1783384Y433819I-1106J1019D01*
G02X1781882Y435321I0J1502D01*
G02X1782367Y436427I1504J0D01*
G03X1782432Y436575I-135J148D01*
G01Y436867D01*
G03X1782367Y437015I-200J0D01*
G02Y439227I1017J1106D01*
G03X1782432Y439375I-135J148D01*
G01Y439667D01*
G03X1782367Y439815I-200J0D01*
G02Y442027I1017J1106D01*
G03X1782432Y442175I-135J148D01*
G01Y442467D01*
G03X1782367Y442615I-200J0D01*
G02X1781882Y443721I1019J1106D01*
G02X1783384Y445223I1502J0D01*
G02X1784490Y444738I0J-1504D01*
G03X1784638Y444673I148J135D01*
G37*
G36*
G01X1755827Y442787D02*
G02X1755342Y443893I1019J1106D01*
G02X1758346I1502J0D01*
G02X1757861Y442787I-1504J0D01*
G03X1757796Y442639I135J-148D01*
G01Y442347D01*
G03X1757861Y442199I200J0D01*
G02Y439987I-1017J-1106D01*
G03X1757796Y439839I135J-148D01*
G01Y439547D01*
G03X1757861Y439399I200J0D01*
G02X1758346Y438293I-1019J-1106D01*
G02X1755342I-1502J0D01*
G02X1755827Y439399I1504J0D01*
G03X1755892Y439547I-135J148D01*
G01Y439839D01*
G03X1755827Y439987I-200J0D01*
G02Y442199I1017J1106D01*
G03X1755892Y442347I-135J148D01*
G01Y442639D01*
G03X1755827Y442787I-200J0D01*
G37*
G36*
G01X1765820D02*
G02X1765335Y443893I1019J1106D01*
G02X1768339I1502J0D01*
G02X1767854Y442787I-1504J0D01*
G03X1767789Y442639I135J-148D01*
G01Y442347D01*
G03X1767854Y442199I200J0D01*
G02Y439987I-1017J-1106D01*
G03X1767789Y439839I135J-148D01*
G01Y439547D01*
G03X1767854Y439399I200J0D01*
G02X1768339Y438293I-1019J-1106D01*
G02X1765335I-1502J0D01*
G02X1765820Y439399I1504J0D01*
G03X1765885Y439547I-135J148D01*
G01Y439839D01*
G03X1765820Y439987I-200J0D01*
G02Y442199I1017J1106D01*
G03X1765885Y442347I-135J148D01*
G01Y442639D01*
G03X1765820Y442787I-200J0D01*
G37*
G36*
G01X1746162Y448012D02*
G02X1745677Y449118I1019J1106D01*
G02X1748681I1502J0D01*
G02X1748196Y448012I-1504J0D01*
G03X1748131Y447864I135J-148D01*
G01Y447572D01*
G03X1748196Y447424I200J0D01*
G02X1748681Y446318I-1019J-1106D01*
G02X1745677I-1502J0D01*
G02X1746162Y447424I1504J0D01*
G03X1746227Y447572I-135J148D01*
G01Y447864D01*
G03X1746162Y448012I-200J0D01*
G37*
G36*
G01X1734807Y450813D02*
G03X1734951Y450903I-24J199D01*
G02X1736214Y451593I1263J-811D01*
G02X1737653Y450523I0J-1503D01*
G01X1737667Y450476D01*
X1737735Y450406D01*
X1738141Y450273D01*
X1738237Y450289D01*
X1738277Y450319D01*
G02X1739179Y450620I902J-1201D01*
G02X1740681Y449118I0J-1502D01*
G02X1740196Y448012I-1504J0D01*
G03X1740131Y447864I135J-148D01*
G01Y447572D01*
G03X1740196Y447424I200J0D01*
G02X1740681Y446318I-1019J-1106D01*
G02X1737677I-1502J0D01*
G02X1738162Y447424I1504J0D01*
G03X1738227Y447572I-135J148D01*
G01Y447864D01*
G03X1738162Y448012I-200J0D01*
G02X1737740Y448686I1017J1106D01*
G01X1737726Y448733D01*
X1737658Y448803D01*
X1737252Y448936D01*
X1737156Y448920D01*
X1737116Y448890D01*
G02X1736214Y448589I-902J1201D01*
G02X1734951Y449279I0J1501D01*
G03X1734807Y449369I-168J-109D01*
G03X1734783Y449371I-29J-198D01*
G01X1734445D01*
G03X1734421Y449369I5J-200D01*
G03X1734277Y449279I24J-199D01*
G02X1733014Y448589I-1263J811D01*
G02X1731829Y449168I0J1502D01*
G03X1731671Y449245I-158J-123D01*
G01X1731357D01*
G03X1731199Y449168I0J-200D01*
G02X1731128Y449084I-1182J927D01*
G01X1731097Y449050D01*
X1731071Y448966D01*
X1731125Y448574D01*
X1731172Y448500D01*
X1731210Y448476D01*
G02X1731906Y447209I-805J-1267D01*
G02X1730404Y445707I-1502J0D01*
G02X1729219Y446286I0J1502D01*
G03X1729061Y446363I-158J-123D01*
G01X1728747D01*
G03X1728589Y446286I0J-200D01*
G02X1727404Y445707I-1185J923D01*
G02X1725902Y447209I0J1502D01*
G01Y447231D01*
G03X1725821Y447392I-200J0D01*
G01X1725561Y447585D01*
G03X1725381Y447614I-118J-161D01*
G01X1725380D01*
G02X1724924Y447543I-456J1431D01*
G01X1724923D01*
G02X1726425Y449045I0J1502D01*
G01Y449023D01*
G03X1726506Y448862I200J0D01*
G01X1726766Y448669D01*
G03X1726946Y448640I118J161D01*
G01X1726947D01*
G02X1727403Y448711I456J-1431D01*
G01X1727404D01*
G02X1728589Y448132I0J-1502D01*
G03X1728747Y448055I158J123D01*
G01X1729061D01*
G03X1729219Y448132I0J200D01*
G02X1729290Y448216I1182J-927D01*
G01X1729321Y448250D01*
X1729347Y448334D01*
X1729293Y448726D01*
X1729246Y448800D01*
X1729208Y448824D01*
G02X1728512Y450091I805J1267D01*
G02X1730014Y451593I1502J0D01*
G02X1731199Y451014I0J-1502D01*
G03X1731357Y450937I158J123D01*
G01X1731671D01*
G03X1731829Y451014I0J200D01*
G02X1733014Y451593I1185J-923D01*
G02X1734277Y450903I0J-1501D01*
G03X1734421Y450813I168J109D01*
G03X1734445Y450811I29J198D01*
G01X1734783D01*
G03X1734807Y450813I-5J200D01*
G37*
G36*
G01X1636018Y452400D02*
X1635974Y452409D01*
G02X1634769Y453881I297J1472D01*
G02X1637773I1502J0D01*
G02X1637668Y453330I-1502J1D01*
G01X1637652Y453289D01*
X1637657Y453200D01*
X1637847Y452852D01*
X1637918Y452800D01*
X1637962Y452791D01*
G02X1639167Y451319I-297J-1472D01*
G02X1636163I-1502J0D01*
G02X1636268Y451870I1502J-1D01*
G01X1636284Y451911D01*
X1636279Y452000D01*
X1636089Y452348D01*
X1636018Y452400D01*
G37*
G36*
G01X1654656Y453661D02*
X1654627Y453690D01*
G02X1654195Y454744I1070J1054D01*
G02X1657199I1502J0D01*
G02X1656721Y453645I-1502J0D01*
G01X1656691Y453617D01*
X1656658Y453543D01*
X1656651Y453175D01*
X1656680Y453101D01*
X1656709Y453072D01*
G02X1657141Y452018I-1070J-1054D01*
G02X1654137I-1502J0D01*
G02X1654615Y453117I1502J0D01*
G01X1654645Y453145D01*
X1654678Y453219D01*
X1654685Y453587D01*
X1654656Y453661D01*
G37*
G36*
G01X1755827Y454535D02*
G02X1755342Y455641I1019J1106D01*
G02X1758346I1502J0D01*
G02X1757861Y454535I-1504J0D01*
G03X1757796Y454387I135J-148D01*
G01Y454095D01*
G03X1757861Y453947I200J0D01*
G02Y451735I-1017J-1106D01*
G03X1757796Y451587I135J-148D01*
G01Y451295D01*
G03X1757861Y451147I200J0D01*
G02X1758346Y450041I-1019J-1106D01*
G02X1755342I-1502J0D01*
G02X1755827Y451147I1504J0D01*
G03X1755892Y451295I-135J148D01*
G01Y451587D01*
G03X1755827Y451735I-200J0D01*
G02Y453947I1017J1106D01*
G03X1755892Y454095I-135J148D01*
G01Y454387D01*
G03X1755827Y454535I-200J0D01*
G37*
G36*
G01X1765820D02*
G02X1765335Y455641I1019J1106D01*
G02X1768339I1502J0D01*
G02X1767854Y454535I-1504J0D01*
G03X1767789Y454387I135J-148D01*
G01Y454095D01*
G03X1767854Y453947I200J0D01*
G02Y451735I-1017J-1106D01*
G03X1767789Y451587I135J-148D01*
G01Y451295D01*
G03X1767854Y451147I200J0D01*
G02X1768339Y450041I-1019J-1106D01*
G02X1765335I-1502J0D01*
G02X1765820Y451147I1504J0D01*
G03X1765885Y451295I-135J148D01*
G01Y451587D01*
G03X1765820Y451735I-200J0D01*
G02Y453947I1017J1106D01*
G03X1765885Y454095I-135J148D01*
G01Y454387D01*
G03X1765820Y454535I-200J0D01*
G37*
G36*
G01X1738073Y454733D02*
G02X1737322Y456034I751J1301D01*
G02X1740326I1502J0D01*
G02X1739575Y454733I-1502J0D01*
G03Y454041I200J-346D01*
G02X1740326Y452740I-751J-1301D01*
G02X1737322I-1502J0D01*
G02X1738073Y454041I1502J0D01*
G03Y454733I-200J346D01*
G37*
G36*
G01X1653774Y460047D02*
G03X1654247Y460400I75J393D01*
G02X1655742Y461752I1495J-151D01*
G02Y458748I0J-1502D01*
G01X1655741D01*
G02X1655458Y458775I1J1502D01*
G03X1654985Y458422I-75J-393D01*
G02X1653490Y457070I-1495J151D01*
G02Y460074I0J1502D01*
G01X1653491D01*
G02X1653774Y460047I-1J-1502D01*
G37*
G36*
G01X1663576Y463990D02*
G02Y466994I0J1502D01*
G02X1665071Y465633I0J-1502D01*
G01X1665076Y465586D01*
X1665125Y465507D01*
X1665437Y465314D01*
G03X1665615Y465298I105J170D01*
G02X1666271Y465422I657J-1679D01*
G02X1668074Y463619I0J-1803D01*
G01Y460219D01*
G02X1666271Y458416I-1803J0D01*
G02X1665611Y458542I2J1803D01*
G01X1665609D01*
Y458543D01*
G03X1665434Y458528I-72J-187D01*
G01X1665122Y458342D01*
X1665072Y458265D01*
X1665066Y458219D01*
G02X1663576Y456904I-1490J187D01*
G02Y459908I0J1502D01*
G01X1663577D01*
G02X1664105Y459812I-1J-1503D01*
G01X1664153Y459794D01*
X1664253Y459808D01*
X1664435Y459942D01*
X1664477Y460034D01*
X1664473Y460086D01*
G02X1664468Y460219I1798J134D01*
G01Y463619D01*
G02X1664469Y463643I1801J-63D01*
G01X1664471Y463692D01*
X1664430Y463779D01*
X1664140Y464006D01*
G03X1663966Y464041I-122J-158D01*
G01X1663965D01*
G02X1663578Y463990I-388J1451D01*
G01X1663576D01*
G37*
G36*
G01X1645820Y467516D02*
X1646109Y467697D01*
X1646153Y467755D01*
X1646163Y467790D01*
G02X1647604Y468869I1441J-423D01*
G02Y465865I0J-1502D01*
G02X1647357Y465886I3J1502D01*
G01X1647320Y465892D01*
X1647249Y465878D01*
X1646960Y465697D01*
X1646916Y465639D01*
X1646906Y465603D01*
G02X1646876Y465513I-1439J430D01*
G01X1646860Y465468D01*
X1646871Y465375D01*
X1647072Y465068D01*
G03X1647226Y464978I167J110D01*
G01X1647227D01*
G02X1648635Y463479I-94J-1499D01*
G02X1645631I-1502J0D01*
G01Y463481D01*
G02X1645721Y463993I1502J0D01*
G01X1645738Y464038D01*
X1645727Y464130D01*
X1645526Y464438D01*
G03X1645372Y464528I-167J-110D01*
G01X1645371D01*
G02X1643963Y466027I94J1499D01*
G02X1645465Y467529I1502J0D01*
G02X1645712Y467508I-3J-1502D01*
G01X1645749Y467502D01*
X1645820Y467516D01*
G37*
G36*
G01X1739525Y466982D02*
G02X1739040Y468088I1019J1106D01*
G02X1742044I1502J0D01*
G02X1741559Y466982I-1504J0D01*
G03X1741494Y466834I135J-148D01*
G01Y466542D01*
G03X1741559Y466394I200J0D01*
G02X1742044Y465288I-1019J-1106D01*
G02X1739040I-1502J0D01*
G02X1739525Y466394I1504J0D01*
G03X1739590Y466542I-135J148D01*
G01Y466834D01*
G03X1739525Y466982I-200J0D01*
G37*
G36*
G01X1745994Y471084D02*
X1746225D01*
X1746291Y471109D01*
X1746319Y471133D01*
G02X1747306Y471503I987J-1131D01*
G02Y468499I0J-1502D01*
G02X1746371Y468826I0J1500D01*
G01X1746344Y468847D01*
X1746282Y468869D01*
X1746118D01*
Y468918D01*
X1745887D01*
X1745821Y468893D01*
X1745793Y468869D01*
G02X1744806Y468499I-987J1131D01*
G02Y471503I0J1502D01*
G02X1745741Y471176I0J-1500D01*
G01X1745768Y471155D01*
X1745830Y471133D01*
X1745994D01*
Y471084D01*
G37*
G36*
G01X1654274Y472577D02*
Y472579D01*
G02X1655776Y471077I1502J0D01*
G01X1655774D01*
G02X1655410Y471122I1J1502D01*
G03X1654933Y470609I-97J-388D01*
G02X1655009Y470138I-1426J-472D01*
G01Y470136D01*
G02X1653507Y471638I-1502J0D01*
G01X1653509D01*
G02X1653873Y471593I-1J-1502D01*
G03X1654350Y472106I97J388D01*
G02X1654274Y472577I1426J472D01*
G37*
G36*
G01X1746673Y486663D02*
X1747011D01*
X1747077Y486688D01*
X1747105Y486712D01*
G02X1748092Y487082I987J-1131D01*
G02Y484078I0J-1502D01*
G02X1747157Y484405I0J1500D01*
G01X1747130Y484426D01*
X1747068Y484448D01*
X1746904D01*
Y484497D01*
X1746673D01*
X1746607Y484472D01*
X1746579Y484448D01*
G02X1744657Y484405I-987J1132D01*
G01X1744630Y484426D01*
X1744568Y484448D01*
X1744404D01*
Y484497D01*
X1744173D01*
X1744107Y484472D01*
X1744079Y484448D01*
G02X1743092Y484078I-987J1131D01*
G02Y487082I0J1502D01*
G02X1744027Y486755I0J-1500D01*
G01X1744054Y486734D01*
X1744116Y486712D01*
X1744280D01*
Y486663D01*
X1744511D01*
X1744577Y486688D01*
X1744605Y486712D01*
G02X1746579I987J-1131D01*
G01X1746607Y486688D01*
X1746673Y486663D01*
G37*
G36*
G01X1756391Y485880D02*
G02X1757893Y487382I0J1502D01*
G01Y487381D01*
G02X1757814Y486901I-1502J1D01*
G03X1758236Y486375I379J-128D01*
G02X1758399Y486384I164J-1493D01*
G01X1758401D01*
G02X1756899Y484882I0J-1502D01*
G01Y484883D01*
G02X1756978Y485363I1502J-1D01*
G03X1756556Y485889I-379J128D01*
G02X1756393Y485880I-164J1493D01*
G01X1756391D01*
G37*
G36*
G01X1674245Y185330D02*
X1674380Y185710D01*
X1674370Y185800D01*
X1674346Y185839D01*
G02X1674121Y186629I1277J791D01*
G02X1677125I1502J0D01*
G02X1676122Y185212I-1502J0D01*
G01X1676078Y185197D01*
X1676015Y185133D01*
X1675880Y184753D01*
X1675890Y184663D01*
X1675914Y184624D01*
G02X1676139Y183834I-1277J-791D01*
G02X1673135I-1502J0D01*
G02X1674138Y185251I1502J0D01*
G01X1674182Y185266D01*
X1674245Y185330D01*
G37*
G36*
G01X1766518Y75446D02*
X1766146Y75386D01*
X1766077Y75341D01*
X1766053Y75306D01*
G02X1764804Y74638I-1249J834D01*
G02Y77642I0J1502D01*
G02X1765725Y77327I1J-1502D01*
G01X1765758Y77301D01*
X1765838Y77281D01*
X1766210Y77341D01*
X1766279Y77386D01*
X1766303Y77421D01*
G02X1767552Y78089I1249J-834D01*
G02Y75085I0J-1502D01*
G02X1766631Y75400I-1J1502D01*
G01X1766598Y75426D01*
X1766518Y75446D01*
G37*
G36*
G01X1742089Y84063D02*
Y84415D01*
X1742061Y84484D01*
X1742035Y84512D01*
G02X1741629Y85539I1096J1027D01*
G02X1744633I1502J0D01*
G02X1744227Y84512I-1502J0D01*
G01X1744201Y84484D01*
X1744173Y84415D01*
Y84063D01*
X1744201Y83994D01*
X1744227Y83966D01*
G02Y81912I-1096J-1027D01*
G01X1744201Y81884D01*
X1744173Y81815D01*
Y81463D01*
X1744201Y81394D01*
X1744227Y81366D01*
G02Y79312I-1096J-1027D01*
G01X1744201Y79284D01*
X1744173Y79215D01*
Y78863D01*
X1744201Y78794D01*
X1744227Y78766D01*
G02Y76712I-1096J-1027D01*
G01X1744201Y76684D01*
X1744173Y76615D01*
Y76263D01*
X1744201Y76194D01*
X1744227Y76166D01*
G02X1744633Y75139I-1096J-1027D01*
G02X1741629I-1502J0D01*
G02X1742035Y76166I1502J0D01*
G01X1742061Y76194D01*
X1742089Y76263D01*
Y76615D01*
X1742061Y76684D01*
X1742035Y76712D01*
G02Y78766I1096J1027D01*
G01X1742061Y78794D01*
X1742089Y78863D01*
Y79215D01*
X1742061Y79284D01*
X1742035Y79312D01*
G02Y81366I1096J1027D01*
G01X1742061Y81394D01*
X1742089Y81463D01*
Y81815D01*
X1742061Y81884D01*
X1742035Y81912D01*
G02Y83966I1096J1027D01*
G01X1742061Y83994D01*
X1742089Y84063D01*
G37*
G36*
G01X1723754Y84108D02*
Y84460D01*
X1723726Y84529D01*
X1723700Y84557D01*
G02X1723294Y85584I1096J1027D01*
G02X1726298I1502J0D01*
G02X1725892Y84557I-1502J0D01*
G01X1725866Y84529D01*
X1725838Y84460D01*
Y84108D01*
X1725866Y84039D01*
X1725892Y84011D01*
G02Y81957I-1096J-1027D01*
G01X1725866Y81929D01*
X1725838Y81860D01*
Y81508D01*
X1725866Y81439D01*
X1725892Y81411D01*
G02Y79357I-1096J-1027D01*
G01X1725866Y79329D01*
X1725838Y79260D01*
Y78908D01*
X1725866Y78839D01*
X1725892Y78811D01*
G02Y76757I-1096J-1027D01*
G01X1725866Y76729D01*
X1725838Y76660D01*
Y76308D01*
X1725866Y76239D01*
X1725892Y76211D01*
G02X1726298Y75184I-1096J-1027D01*
G02X1723294I-1502J0D01*
G02X1723700Y76211I1502J0D01*
G01X1723726Y76239D01*
X1723754Y76308D01*
Y76660D01*
X1723726Y76729D01*
X1723700Y76757D01*
G02Y78811I1096J1027D01*
G01X1723726Y78839D01*
X1723754Y78908D01*
Y79260D01*
X1723726Y79329D01*
X1723700Y79357D01*
G02Y81411I1096J1027D01*
G01X1723726Y81439D01*
X1723754Y81508D01*
Y81860D01*
X1723726Y81929D01*
X1723700Y81957D01*
G02Y84011I1096J1027D01*
G01X1723726Y84039D01*
X1723754Y84108D01*
G37*
G36*
G01X1707283Y137670D02*
X1707599Y137881D01*
X1707644Y137950D01*
X1707651Y137992D01*
G02X1709134Y139259I1483J-234D01*
G02Y136255I0J-1502D01*
G02X1708866Y136279I-1J1502D01*
G03X1708700Y136234I-36J-197D01*
G01X1708604Y136151D01*
G03X1708535Y135991I131J-151D01*
G02X1708536Y135915I-1801J-62D01*
G01Y132515D01*
G02X1708535Y132436I-1802J-17D01*
G03X1708604Y132276I200J-9D01*
G01X1708700Y132193D01*
G03X1708866Y132148I130J152D01*
G02X1709134Y132172I267J-1478D01*
G02X1710121Y131802I0J-1501D01*
G01X1710149Y131778D01*
X1710216Y131753D01*
X1710552D01*
X1710619Y131778D01*
X1710647Y131802D01*
G02X1711634Y132172I987J-1131D01*
G02X1713117Y130905I0J-1501D01*
G01X1713124Y130863D01*
X1713169Y130794D01*
X1713485Y130583D01*
X1713566Y130569D01*
X1713607Y130579D01*
G02X1714034Y130630I426J-1751D01*
G02X1714382Y130597I5J-1802D01*
G01X1714422Y130589D01*
X1714500Y130605D01*
X1714804Y130814D01*
X1714846Y130881D01*
X1714853Y130922D01*
G02X1716334Y132172I1481J-252D01*
G02Y129168I0J-1502D01*
G02X1716153Y129179I0J1502D01*
G03X1715995Y129128I-23J-199D01*
G01X1715901Y129043D01*
G03X1715835Y128888I134J-149D01*
G02X1715836Y128828I-1801J-60D01*
G01Y125428D01*
G02X1715835Y125365I-1802J-3D01*
G03X1715901Y125210I200J-6D01*
G01X1715995Y125125D01*
G03X1716153Y125074I135J148D01*
G02X1716334Y125085I181J-1491D01*
G02Y122081I0J-1502D01*
G02X1714853Y123333I0J1502D01*
G01X1714846Y123374D01*
X1714803Y123441D01*
X1714500Y123651D01*
X1714422Y123667D01*
X1714381Y123659D01*
G02X1714034Y123626I-343J1769D01*
G02X1713608Y123677I0J1802D01*
G01X1713566Y123687D01*
X1713485Y123672D01*
X1713169Y123462D01*
X1713124Y123392D01*
X1713118Y123350D01*
G02X1711634Y122081I-1484J233D01*
G02X1710646Y122451I-1J1502D01*
G01X1710619Y122476D01*
X1710552Y122501D01*
X1710215D01*
X1710149Y122476D01*
X1710121Y122452D01*
G02X1709134Y122082I-987J1131D01*
G02X1708866Y122106I-1J1502D01*
G03X1708700Y122061I-36J-197D01*
G01X1708604Y121978D01*
G03X1708535Y121818I131J-151D01*
G02X1708536Y121742I-1801J-62D01*
G01Y118342D01*
G02X1708535Y118263I-1802J-17D01*
G03X1708604Y118103I200J-9D01*
G01X1708700Y118020D01*
G03X1708866Y117975I130J152D01*
G02X1709134Y117999I267J-1478D01*
G02X1710121Y117629I0J-1501D01*
G01X1710149Y117605D01*
X1710216Y117580D01*
X1710552D01*
X1710619Y117605D01*
X1710647Y117629D01*
G02X1711634Y117999I987J-1131D01*
G02X1713117Y116732I0J-1501D01*
G01X1713124Y116690D01*
X1713169Y116621D01*
X1713485Y116410D01*
X1713566Y116396D01*
X1713607Y116406D01*
G02X1714034Y116458I430J-1751D01*
G02X1714382Y116424I0J-1803D01*
G01X1714422Y116416D01*
X1714500Y116432D01*
X1714804Y116641D01*
X1714846Y116708D01*
X1714853Y116749D01*
G02X1716334Y117998I1481J-254D01*
G02Y114994I0J-1502D01*
G02X1716153Y115005I0J1502D01*
G03X1715995Y114954I-23J-199D01*
G01X1715901Y114869D01*
G03X1715836Y114714I135J-148D01*
G01Y111255D01*
G02X1715835Y111192I-1802J-3D01*
G03X1715901Y111037I200J-6D01*
G01X1715995Y110952D01*
G03X1716153Y110901I135J148D01*
G02X1716334Y110912I181J-1491D01*
G02Y107908I0J-1502D01*
G02X1714853Y109160I0J1502D01*
G01X1714846Y109201D01*
X1714803Y109268D01*
X1714500Y109478D01*
X1714422Y109494D01*
X1714381Y109486D01*
G02X1714034Y109452I-348J1769D01*
G02X1713608Y109504I4J1803D01*
G01X1713566Y109514D01*
X1713485Y109499D01*
X1713169Y109289D01*
X1713124Y109219D01*
X1713118Y109177D01*
G02X1711634Y107908I-1484J233D01*
G02Y110912I0J1502D01*
G02X1711902Y110888I1J-1502D01*
G03X1712068Y110933I36J197D01*
G01X1712164Y111016D01*
G03X1712233Y111176I-131J151D01*
G02X1712232Y111255I1801J62D01*
G01Y114655D01*
G02X1712233Y114731I1802J14D01*
G03X1712164Y114891I-200J9D01*
G01X1712068Y114974D01*
G03X1711902Y115019I-130J-152D01*
G02X1711634Y114995I-267J1478D01*
G02X1710647Y115365I0J1501D01*
G01X1710619Y115389D01*
X1710552Y115414D01*
X1710216D01*
X1710149Y115389D01*
X1710121Y115365D01*
G02X1709134Y114995I-987J1131D01*
G02X1707650Y116264I0J1502D01*
G01X1707644Y116306D01*
X1707599Y116376D01*
X1707283Y116586D01*
X1707202Y116601D01*
X1707160Y116591D01*
G02X1706734Y116540I-426J1751D01*
G02X1706308Y116591I0J1802D01*
G01X1706266Y116601D01*
X1706185Y116586D01*
X1705869Y116376D01*
X1705824Y116306D01*
X1705818Y116264D01*
G02X1704334Y114995I-1484J233D01*
G02Y117999I0J1502D01*
G02X1704602Y117975I1J-1502D01*
G03X1704768Y118020I36J197D01*
G01X1704864Y118103D01*
G03X1704933Y118263I-131J151D01*
G02X1704932Y118342I1801J62D01*
G01Y121742D01*
G02X1704933Y121818I1802J14D01*
G03X1704864Y121978I-200J9D01*
G01X1704768Y122061D01*
G03X1704602Y122106I-130J-152D01*
G02X1704334Y122082I-267J1478D01*
G02Y125086I0J1502D01*
G02X1705817Y123819I0J-1501D01*
G01X1705824Y123777D01*
X1705869Y123708D01*
X1706185Y123497D01*
X1706266Y123483D01*
X1706307Y123493D01*
G02X1706734Y123544I426J-1751D01*
G02X1707161Y123493I1J-1802D01*
G01X1707202Y123483D01*
X1707283Y123497D01*
X1707599Y123708D01*
X1707644Y123777D01*
X1707651Y123819D01*
G02X1709134Y125086I1483J-234D01*
G02X1710122Y124716I1J-1502D01*
G01X1710149Y124691D01*
X1710216Y124666D01*
X1710553D01*
X1710619Y124691D01*
X1710647Y124715D01*
G02X1711634Y125085I987J-1131D01*
G02X1711902Y125061I1J-1502D01*
G03X1712068Y125106I36J197D01*
G01X1712164Y125189D01*
G03X1712233Y125349I-131J151D01*
G02X1712232Y125428I1801J62D01*
G01Y128828D01*
G02X1712233Y128904I1802J14D01*
G03X1712164Y129064I-200J9D01*
G01X1712068Y129147D01*
G03X1711902Y129192I-130J-152D01*
G02X1711634Y129168I-267J1478D01*
G02X1710647Y129538I0J1501D01*
G01X1710619Y129562D01*
X1710552Y129587D01*
X1710216D01*
X1710149Y129562D01*
X1710121Y129538D01*
G02X1709134Y129168I-987J1131D01*
G02X1707650Y130437I0J1502D01*
G01X1707644Y130479D01*
X1707599Y130549D01*
X1707283Y130759D01*
X1707202Y130774D01*
X1707160Y130764D01*
G02X1706734Y130712I-430J1751D01*
G02X1706308Y130764I4J1803D01*
G01X1706266Y130774D01*
X1706185Y130759D01*
X1705869Y130549D01*
X1705824Y130479D01*
X1705818Y130437D01*
G02X1704334Y129168I-1484J233D01*
G02Y132172I0J1502D01*
G02X1704602Y132148I1J-1502D01*
G03X1704768Y132193I36J197D01*
G01X1704864Y132276D01*
G03X1704933Y132436I-131J151D01*
G02X1704932Y132515I1801J62D01*
G01Y135915D01*
G02X1704933Y135991I1802J14D01*
G03X1704864Y136151I-200J9D01*
G01X1704768Y136234D01*
G03X1704602Y136279I-130J-152D01*
G02X1704334Y136255I-267J1478D01*
G02Y139259I0J1502D01*
G02X1705817Y137992I0J-1501D01*
G01X1705824Y137950D01*
X1705869Y137881D01*
X1706185Y137670D01*
X1706266Y137656D01*
X1706307Y137666D01*
G02X1706734Y137718I430J-1751D01*
G02X1707161Y137666I-3J-1803D01*
G01X1707202Y137656D01*
X1707283Y137670D01*
G37*
G36*
G01X1692448Y196259D02*
X1692784D01*
X1692851Y196284D01*
X1692879Y196308D01*
G02X1693866Y196678I987J-1131D01*
G02X1694972Y196193I1J-1502D01*
G03X1695119Y196128I148J135D01*
G01X1695413D01*
G03X1695560Y196193I-1J200D01*
G02X1696666Y196678I1105J-1017D01*
G02Y193674I0J-1502D01*
G02X1695560Y194159I-1J1502D01*
G03X1695413Y194224I-148J-135D01*
G01X1695119D01*
G03X1694972Y194159I1J-200D01*
G02X1693866Y193674I-1105J1017D01*
G02X1692879Y194044I0J1501D01*
G01X1692851Y194068D01*
X1692784Y194093D01*
X1692448D01*
X1692381Y194068D01*
X1692353Y194044D01*
G02X1690379I-987J1131D01*
G01X1690351Y194068D01*
X1690284Y194093D01*
X1689948D01*
X1689881Y194068D01*
X1689853Y194044D01*
G02X1688866Y193674I-987J1131D01*
G02Y196678I0J1502D01*
G02X1689853Y196308I0J-1501D01*
G01X1689881Y196284D01*
X1689948Y196259D01*
X1690284D01*
X1690351Y196284D01*
X1690379Y196308D01*
G02X1692353I987J-1131D01*
G01X1692381Y196284D01*
X1692448Y196259D01*
G37*
G36*
G01X1690144Y202310D02*
X1689808D01*
X1689741Y202285D01*
X1689713Y202261D01*
G02X1688726Y201891I-987J1131D01*
G02Y204895I0J1502D01*
G02X1689713Y204525I0J-1501D01*
G01X1689741Y204501D01*
X1689808Y204476D01*
X1690144D01*
X1690211Y204501D01*
X1690239Y204525D01*
G02X1691226Y204895I987J-1131D01*
G02X1692723Y203517I0J-1502D01*
G01X1692726Y203474D01*
X1692767Y203400D01*
X1693074Y203168D01*
X1693155Y203149D01*
X1693198Y203157D01*
G02X1693485Y203185I289J-1474D01*
G02X1694987Y201683I0J-1502D01*
G02X1694502Y200577I-1502J-1D01*
G03X1694437Y200430I135J-148D01*
G01Y200136D01*
G03X1694502Y199989I200J1D01*
G02X1694987Y198883I-1017J-1105D01*
G02X1691983I-1502J0D01*
G02X1692468Y199989I1502J1D01*
G03X1692533Y200136I-135J148D01*
G01Y200430D01*
G03X1692468Y200577I-200J-1D01*
G02X1691988Y201559I1017J1105D01*
G01X1691985Y201602D01*
X1691944Y201676D01*
X1691637Y201908D01*
X1691556Y201927D01*
X1691513Y201919D01*
G02X1691226Y201891I-289J1474D01*
G02X1690239Y202261I0J1501D01*
G01X1690211Y202285D01*
X1690144Y202310D01*
G37*
G36*
G01X1696332Y205755D02*
X1695996D01*
X1695929Y205730D01*
X1695901Y205706D01*
G02X1694914Y205336I-987J1131D01*
G02Y208340I0J1502D01*
G02X1695901Y207970I0J-1501D01*
G01X1695929Y207946D01*
X1695996Y207921D01*
X1696332D01*
X1696399Y207946D01*
X1696427Y207970D01*
G02X1697414Y208340I987J-1131D01*
G02Y205336I0J-1502D01*
G02X1696427Y205706I0J1501D01*
G01X1696399Y205730D01*
X1696332Y205755D01*
G37*
G36*
G01X1690152Y217133D02*
X1689858D01*
G03X1689711Y217068I1J-200D01*
G02X1688605Y216583I-1105J1017D01*
G02Y219587I0J1502D01*
G02X1689711Y219102I1J-1502D01*
G03X1689858Y219037I148J135D01*
G01X1690152D01*
G03X1690299Y219102I-1J200D01*
G02X1691405Y219587I1105J-1017D01*
G02Y216583I0J-1502D01*
G02X1690299Y217068I-1J1502D01*
G03X1690152Y217133I-148J-135D01*
G37*
G36*
G01X1696835Y220552D02*
Y220888D01*
X1696810Y220955D01*
X1696786Y220983D01*
G02X1696416Y221970I1131J987D01*
G02X1699420I1502J0D01*
G02X1699050Y220983I-1501J0D01*
G01X1699026Y220955D01*
X1699001Y220888D01*
Y220552D01*
X1699026Y220485D01*
X1699050Y220457D01*
G02Y218483I-1131J-987D01*
G01X1699026Y218455D01*
X1699001Y218388D01*
Y218052D01*
X1699026Y217985D01*
X1699050Y217957D01*
G02X1699420Y216970I-1131J-987D01*
G02X1697918Y215468I-1502J0D01*
G02X1697063Y215735I0J1502D01*
G01X1697029Y215759D01*
X1696948Y215775D01*
X1696581Y215696D01*
X1696514Y215648D01*
X1696493Y215612D01*
G02X1695205Y214883I-1288J773D01*
G02Y217887I0J1502D01*
G02X1696060Y217620I0J-1502D01*
G01X1696094Y217596D01*
X1696175Y217580D01*
X1696542Y217659D01*
X1696609Y217707D01*
X1696630Y217743D01*
G02X1696786Y217957I1287J-774D01*
G01X1696810Y217985D01*
X1696835Y218052D01*
Y218388D01*
X1696810Y218455D01*
X1696786Y218483D01*
G02Y220457I1131J987D01*
G01X1696810Y220485D01*
X1696835Y220552D01*
G37*
G36*
G01X1778743Y90701D02*
G02X1778073Y91951I831J1250D01*
G02X1781077I1502J0D01*
G02X1780427Y90714I-1502J0D01*
G03X1780432Y90051I227J-330D01*
G02X1781102Y88801I-831J-1250D01*
G02X1778098I-1502J0D01*
G02X1778748Y90038I1502J0D01*
G03X1778743Y90701I-227J330D01*
G37*
G36*
G01X1727904Y91453D02*
G02X1727350Y91347I-554J1395D01*
G02X1728852Y92849I0J1502D01*
G02X1728806Y92481I-1502J1D01*
G03X1729342Y92011I388J-98D01*
G02X1729896Y92117I554J-1395D01*
G02X1728394Y90615I0J-1502D01*
G02X1728440Y90983I1502J-1D01*
G03X1727904Y91453I-388J98D01*
G37*
G36*
G01X1733391Y101849D02*
G02X1732808Y103037I919J1188D01*
G02X1735812I1502J0D01*
G02X1735156Y101796I-1502J0D01*
G03X1735136Y101149I225J-331D01*
G02X1735719Y99961I-919J-1188D01*
G02X1732715I-1502J0D01*
G02X1733371Y101202I1502J0D01*
G03X1733391Y101849I-225J331D01*
G37*
G36*
G01X1768963Y102731D02*
G02X1768671Y103621I1210J890D01*
G02X1771675I1502J0D01*
G02X1770450Y102145I-1502J0D01*
G03X1770201Y101515I73J-393D01*
G02X1770493Y100625I-1210J-890D01*
G02X1767489I-1502J0D01*
G02X1768714Y102101I1502J0D01*
G03X1768963Y102731I-73J393D01*
G37*
G36*
G01X1712692Y105329D02*
X1712652Y105360D01*
G02X1712051Y106561I901J1202D01*
G02X1715055I1502J0D01*
G02X1714329Y105275I-1502J0D01*
G01X1714286Y105249D01*
X1714235Y105164D01*
X1714213Y104732D01*
X1714255Y104643D01*
X1714295Y104612D01*
G02X1714850Y103779I-901J-1202D01*
G01X1714862Y103731D01*
X1714928Y103658D01*
X1715331Y103509D01*
X1715427Y103522D01*
X1715468Y103550D01*
G02X1716334Y103825I866J-1226D01*
G02Y100821I0J-1502D01*
G02X1714878Y101955I0J1502D01*
G01X1714866Y102003D01*
X1714800Y102076D01*
X1714397Y102225D01*
X1714301Y102212D01*
X1714260Y102184D01*
G02X1713394Y101909I-866J1226D01*
G02X1711892Y103411I0J1502D01*
G02X1712618Y104697I1502J0D01*
G01X1712661Y104723D01*
X1712712Y104808D01*
X1712734Y105240D01*
X1712692Y105329D01*
G37*
G36*
G01X1699925Y110018D02*
X1700241D01*
G03X1700398Y110095I-1J200D01*
G02X1701583Y110674I1185J-923D01*
G02X1703085Y109172I0J-1502D01*
G02X1702121Y107770I-1502J0D01*
G01X1702081Y107754D01*
X1702021Y107693D01*
X1701886Y107331D01*
X1701892Y107245D01*
X1701913Y107207D01*
G02X1702092Y106495I-1323J-711D01*
G02X1699088I-1502J0D01*
G02X1699226Y107123I1502J-1D01*
G01X1699249Y107173D01*
X1699237Y107283D01*
X1698960Y107653D01*
X1698858Y107694D01*
X1698804Y107686D01*
G02X1698583Y107670I-219J1486D01*
G02Y110674I0J1502D01*
G02X1699768Y110095I0J-1502D01*
G03X1699925Y110018I158J123D01*
G37*
G36*
G01X1700067Y147959D02*
X1700046Y147998D01*
G02X1699863Y148717I1319J719D01*
G02X1702867I1502J0D01*
G02X1701862Y147300I-1501J0D01*
G01X1701820Y147285D01*
X1701757Y147224D01*
X1701616Y146857D01*
X1701622Y146770D01*
X1701643Y146731D01*
G02X1701826Y146012I-1319J-719D01*
G02X1701166Y144768I-1502J0D01*
G03X1701078Y144603I112J-166D01*
G01Y144271D01*
G03X1701166Y144106I200J1D01*
G02X1701811Y143074I-842J-1244D01*
G01X1701816Y143037D01*
X1701850Y142974D01*
X1702108Y142754D01*
X1702174Y142729D01*
X1702212Y142730D01*
X1702230D01*
G02Y139726I0J-1502D01*
G02X1700743Y141016I0J1502D01*
G01X1700738Y141053D01*
X1700704Y141116D01*
X1700446Y141336D01*
X1700380Y141361D01*
X1700342Y141360D01*
X1700324D01*
G02X1698822Y142862I0J1502D01*
G02X1699482Y144106I1502J0D01*
G03X1699570Y144271I-112J166D01*
G01Y144603D01*
G03X1699482Y144768I-200J-1D01*
G02X1698822Y146012I842J1244D01*
G02X1699827Y147429I1501J0D01*
G01X1699869Y147444D01*
X1699932Y147505D01*
X1700073Y147872D01*
X1700067Y147959D01*
G37*
G36*
G01X1699044Y234870D02*
G02X1698374Y236121I833J1251D01*
G02X1701378I1502J0D01*
G02X1700728Y234884I-1502J0D01*
G03X1700734Y234222I227J-329D01*
G02X1701404Y232971I-833J-1251D01*
G02X1698400I-1502J0D01*
G02X1699050Y234208I1502J0D01*
G03X1699044Y234870I-227J329D01*
G37*
G36*
G01X1754114Y223294D02*
Y223630D01*
X1754089Y223697D01*
X1754065Y223725D01*
G02X1753695Y224712I1131J987D01*
G02X1756699I1502J0D01*
G02X1756329Y223725I-1501J0D01*
G01X1756305Y223697D01*
X1756280Y223630D01*
Y223294D01*
X1756305Y223227D01*
X1756329Y223199D01*
G02X1756699Y222212I-1131J-987D01*
G02X1753695I-1502J0D01*
G02X1754065Y223199I1501J0D01*
G01X1754089Y223227D01*
X1754114Y223294D01*
G37*
G36*
G01X1748789Y225189D02*
X1748495D01*
G03X1748348Y225124I1J-200D01*
G02X1747242Y224639I-1105J1017D01*
G02Y227643I0J1502D01*
G02X1748348Y227158I1J-1502D01*
G03X1748495Y227093I148J135D01*
G01X1748789D01*
G03X1748936Y227158I-1J200D01*
G02X1750042Y227643I1105J-1017D01*
G02Y224639I0J-1502D01*
G02X1748936Y225124I-1J1502D01*
G03X1748789Y225189I-148J-135D01*
G37*
G36*
G01X1731996Y229808D02*
Y230144D01*
X1731971Y230211D01*
X1731947Y230239D01*
G02X1731577Y231226I1131J987D01*
G02X1734581I1502J0D01*
G02X1734211Y230239I-1501J0D01*
G01X1734187Y230211D01*
X1734162Y230144D01*
Y229808D01*
X1734187Y229741D01*
X1734211Y229713D01*
G02Y227739I-1131J-987D01*
G01X1734187Y227711D01*
X1734162Y227644D01*
Y227308D01*
X1734187Y227241D01*
X1734211Y227213D01*
G02Y225239I-1131J-987D01*
G01X1734187Y225211D01*
X1734162Y225144D01*
Y224808D01*
X1734187Y224741D01*
X1734211Y224713D01*
G02X1734581Y223726I-1131J-987D01*
G02X1731577I-1502J0D01*
G02X1731947Y224713I1501J0D01*
G01X1731971Y224741D01*
X1731996Y224808D01*
Y225144D01*
X1731971Y225211D01*
X1731947Y225239D01*
G02Y227213I1131J987D01*
G01X1731971Y227241D01*
X1731996Y227308D01*
Y227644D01*
X1731971Y227711D01*
X1731947Y227739D01*
G02Y229713I1131J987D01*
G01X1731971Y229741D01*
X1731996Y229808D01*
G37*
G36*
G01X1742452Y230043D02*
Y230379D01*
X1742427Y230446D01*
X1742403Y230474D01*
G02X1742033Y231461I1131J987D01*
G02X1745037I1502J0D01*
G02X1744667Y230474I-1501J0D01*
G01X1744643Y230446D01*
X1744618Y230379D01*
Y230043D01*
X1744643Y229976D01*
X1744667Y229948D01*
G02Y227974I-1131J-987D01*
G01X1744643Y227946D01*
X1744618Y227879D01*
Y227543D01*
X1744643Y227476D01*
X1744667Y227448D01*
G02X1745037Y226461I-1131J-987D01*
G02X1744552Y225355I-1502J-1D01*
G03X1744487Y225208I135J-148D01*
G01Y224914D01*
G03X1744552Y224767I200J1D01*
G02X1745037Y223661I-1017J-1105D01*
G02X1742033I-1502J0D01*
G02X1742518Y224767I1502J1D01*
G03X1742583Y224914I-135J148D01*
G01Y225208D01*
G03X1742518Y225355I-200J-1D01*
G02X1742033Y226461I1017J1105D01*
G02X1742403Y227448I1501J0D01*
G01X1742427Y227476D01*
X1742452Y227543D01*
Y227879D01*
X1742427Y227946D01*
X1742403Y227974D01*
G02Y229948I1131J987D01*
G01X1742427Y229976D01*
X1742452Y230043D01*
G37*
G36*
G01X1750421Y230368D02*
Y230704D01*
X1750396Y230771D01*
X1750372Y230799D01*
G02X1750002Y231786I1131J987D01*
G02X1753006I1502J0D01*
G02X1752636Y230799I-1501J0D01*
G01X1752612Y230771D01*
X1752587Y230704D01*
Y230368D01*
X1752612Y230301D01*
X1752636Y230273D01*
G02X1753006Y229286I-1131J-987D01*
G02X1750002I-1502J0D01*
G02X1750372Y230273I1501J0D01*
G01X1750396Y230301D01*
X1750421Y230368D01*
G37*
G36*
G01X1748567Y237694D02*
X1748903D01*
X1748970Y237719D01*
X1748998Y237743D01*
G02X1750972I987J-1131D01*
G01X1751000Y237719D01*
X1751067Y237694D01*
X1751403D01*
X1751470Y237719D01*
X1751498Y237743D01*
G02X1752485Y238113I987J-1131D01*
G02Y235109I0J-1502D01*
G02X1751498Y235479I0J1501D01*
G01X1751470Y235503D01*
X1751403Y235528D01*
X1751067D01*
X1751000Y235503D01*
X1750972Y235479D01*
G02X1748998I-987J1131D01*
G01X1748970Y235503D01*
X1748903Y235528D01*
X1748567D01*
X1748500Y235503D01*
X1748472Y235479D01*
G02X1747485Y235109I-987J1131D01*
G02Y238113I0J1502D01*
G02X1748472Y237743I0J-1501D01*
G01X1748500Y237719D01*
X1748567Y237694D01*
G37*
G36*
G01X1748269Y249974D02*
X1748605D01*
X1748672Y249999D01*
X1748700Y250023D01*
G02X1750674I987J-1131D01*
G01X1750702Y249999D01*
X1750769Y249974D01*
X1751105D01*
X1751172Y249999D01*
X1751200Y250023D01*
G02X1752187Y250393I987J-1131D01*
G02Y247389I0J-1502D01*
G02X1751200Y247759I0J1501D01*
G01X1751172Y247783D01*
X1751105Y247808D01*
X1750769D01*
X1750702Y247783D01*
X1750674Y247759D01*
G02X1748700I-987J1131D01*
G01X1748672Y247783D01*
X1748605Y247808D01*
X1748269D01*
X1748202Y247783D01*
X1748174Y247759D01*
G02X1747187Y247389I-987J1131D01*
G02Y250393I0J1502D01*
G02X1748174Y250023I0J-1501D01*
G01X1748202Y249999D01*
X1748269Y249974D01*
G37*
G36*
G01X1752564Y190705D02*
G02X1751916Y191941I855J1236D01*
G02X1754920I1502J0D01*
G02X1754167Y190639I-1502J0D01*
G03X1754139Y189963I199J-347D01*
G02X1754787Y188727I-855J-1236D01*
G02X1751783I-1502J0D01*
G02X1752536Y190029I1502J0D01*
G03X1752564Y190705I-199J347D01*
G37*
G36*
G01X1711219Y1195283D02*
X1711322Y1195656D01*
X1711309Y1195741D01*
X1711285Y1195777D01*
G02X1711040Y1196600I1257J822D01*
G02X1714044I1502J0D01*
G02X1713199Y1195249I-1503J0D01*
G01X1713160Y1195230D01*
X1713106Y1195165D01*
X1713003Y1194792D01*
X1713016Y1194707D01*
X1713040Y1194671D01*
G02X1713285Y1193848I-1257J-822D01*
G02X1710281I-1502J0D01*
G02X1711126Y1195199I1503J0D01*
G01X1711165Y1195218D01*
X1711219Y1195283D01*
G37*
G36*
G01X1711464Y1229810D02*
G03X1711014Y1230198I-400J-9D01*
G02X1710825Y1230186I-189J1490D01*
G02Y1233190I0J1502D01*
G02X1712327Y1231719I0J-1502D01*
G03X1712777Y1231331I400J9D01*
G02X1712966Y1231343I189J-1490D01*
G02Y1228339I0J-1502D01*
G02X1711464Y1229810I0J1502D01*
G37*
G36*
G01X1723896Y1158669D02*
G02X1723796Y1158666I-95J1499D01*
G02X1725298Y1160168I0J1502D01*
G02X1725184Y1159594I-1502J0D01*
G03X1725580Y1159043I370J-152D01*
G02X1725680Y1159046I95J-1499D01*
G02X1724178Y1157544I0J-1502D01*
G02X1724292Y1158118I1502J0D01*
G03X1723896Y1158669I-370J152D01*
G37*
G36*
G01X1720177Y1201265D02*
G02X1721662Y1202545I1485J-221D01*
G02Y1199541I0J-1502D01*
G02X1720749Y1199850I0J1503D01*
G03X1720110Y1199592I-243J-317D01*
G02X1718625Y1198312I-1485J221D01*
G02Y1201316I0J1502D01*
G02X1719538Y1201007I0J-1503D01*
G03X1720177Y1201265I243J317D01*
G37*
G36*
G01X1734541Y1214055D02*
X1734529Y1214107D01*
G02X1734487Y1214458I1460J353D01*
G02X1735989Y1212956I1502J0D01*
G02X1735638Y1212998I2J1502D01*
G01X1735586Y1213010D01*
X1735487Y1212982D01*
X1735171Y1212666D01*
X1735143Y1212567D01*
X1735155Y1212515D01*
G02X1735197Y1212164I-1460J-353D01*
G02X1733695Y1210662I-1502J0D01*
G02X1733551Y1210669I1J1502D01*
G01X1733506Y1210673D01*
X1733422Y1210643D01*
X1733140Y1210361D01*
X1733110Y1210278D01*
X1733114Y1210233D01*
G02X1733121Y1210089I-1495J-145D01*
G02X1731619Y1211591I-1502J0D01*
G02X1731763Y1211584I-1J-1502D01*
G01X1731808Y1211580D01*
X1731892Y1211610D01*
X1732174Y1211892D01*
X1732204Y1211975D01*
X1732200Y1212020D01*
G02X1732193Y1212164I1495J145D01*
G02X1733695Y1213666I1502J0D01*
G02X1734046Y1213624I-2J-1502D01*
G01X1734098Y1213612D01*
X1734197Y1213640D01*
X1734513Y1213956D01*
X1734541Y1214055D01*
G37*
G36*
G01X1730055Y1227959D02*
G02X1730031Y1228226I1478J267D01*
G02X1731533Y1226724I1502J0D01*
G02X1731265Y1226748I-1J1502D01*
G03X1730800Y1226283I-71J-394D01*
G02X1730824Y1226016I-1478J-267D01*
G02X1729322Y1227518I-1502J0D01*
G02X1729590Y1227494I1J-1502D01*
G03X1730055Y1227959I71J394D01*
G37*
G36*
G01X1769063Y921922D02*
X1765663D01*
G02Y925526I0J1802D01*
G01X1769063D01*
G02Y921922I0J-1802D01*
G37*
G36*
G01X1801150Y409056D02*
X1801444D01*
G03X1801591Y409121I-1J200D01*
G02X1803803I1106J-1017D01*
G03X1803950Y409056I148J135D01*
G01X1804244D01*
G03X1804391Y409121I-1J200D01*
G02X1805497Y409606I1106J-1019D01*
G02Y406602I0J-1502D01*
G02X1804391Y407087I0J1504D01*
G03X1804244Y407152I-148J-135D01*
G01X1803950D01*
G03X1803803Y407087I1J-200D01*
G02X1801591I-1106J1017D01*
G03X1801444Y407152I-148J-135D01*
G01X1801150D01*
G03X1801003Y407087I1J-200D01*
G02X1799897Y406602I-1106J1019D01*
G02Y409606I0J1502D01*
G02X1801003Y409121I0J-1504D01*
G03X1801150Y409056I148J135D01*
G37*
G36*
G01X1800867Y421327D02*
X1801161D01*
G03X1801308Y421392I-1J200D01*
G02X1803520I1106J-1017D01*
G03X1803667Y421327I148J135D01*
G01X1803961D01*
G03X1804108Y421392I-1J200D01*
G02X1805214Y421877I1106J-1019D01*
G02Y418873I0J-1502D01*
G02X1804108Y419358I0J1504D01*
G03X1803961Y419423I-148J-135D01*
G01X1803667D01*
G03X1803520Y419358I1J-200D01*
G02X1801308I-1106J1017D01*
G03X1801161Y419423I-148J-135D01*
G01X1800867D01*
G03X1800720Y419358I1J-200D01*
G02X1799614Y418873I-1106J1019D01*
G02Y421877I0J1502D01*
G02X1800720Y421392I0J-1504D01*
G03X1800867Y421327I148J135D01*
G37*
G36*
G01X1756089Y541450D02*
G02Y544454I0J1502D01*
G02X1757193Y543971I0J-1503D01*
G01X1757222Y543939D01*
X1757302Y543905D01*
X1757647Y543915D01*
G03X1757796Y543989I-6J200D01*
G02X1758957Y544538I1161J-953D01*
G02Y541534I0J-1502D01*
G02X1757853Y542017I0J1503D01*
G01X1757824Y542049D01*
X1757744Y542083D01*
X1757399Y542073D01*
G03X1757250Y541999I6J-200D01*
G02X1756089Y541450I-1161J953D01*
G37*
G36*
G01X1746557Y899314D02*
X1746243D01*
G03X1746085Y899237I0J-200D01*
G02X1744900Y898658I-1185J923D01*
G02Y901662I0J1502D01*
G02X1746085Y901083I0J-1502D01*
G03X1746243Y901006I158J123D01*
G01X1746557D01*
G03X1746715Y901083I0J200D01*
G02X1747900Y901662I1185J-923D01*
G02Y898658I0J-1502D01*
G02X1746715Y899237I0J1502D01*
G03X1746557Y899314I-158J-123D01*
G37*
G36*
G01X1772943Y929006D02*
Y929320D01*
G03X1772866Y929478I-200J0D01*
G02X1772287Y930663I923J1185D01*
G02X1775291I1502J0D01*
G02X1774712Y929478I-1502J0D01*
G03X1774635Y929320I123J-158D01*
G01Y929006D01*
G03X1774712Y928848I200J0D01*
G02X1775291Y927663I-923J-1185D01*
G02X1772287I-1502J0D01*
G02X1772866Y928848I1502J0D01*
G03X1772943Y929006I-123J158D01*
G37*
G36*
G01X1781411Y957047D02*
X1781705D01*
G03X1781852Y957112I-1J200D01*
G02X1784064I1106J-1017D01*
G03X1784211Y957047I148J135D01*
G01X1784505D01*
G03X1784652Y957112I-1J200D01*
G02X1785758Y957597I1106J-1019D01*
G02X1787260Y956095I0J-1502D01*
G02X1786775Y954989I-1504J0D01*
G03X1786710Y954842I135J-148D01*
G01Y954548D01*
G03X1786775Y954401I200J1D01*
G02X1787260Y953295I-1019J-1106D01*
G02X1785758Y951793I-1502J0D01*
G02X1784652Y952278I0J1504D01*
G03X1784505Y952343I-148J-135D01*
G01X1784211D01*
G03X1784064Y952278I1J-200D01*
G02X1781852I-1106J1017D01*
G03X1781705Y952343I-148J-135D01*
G01X1781411D01*
G03X1781264Y952278I1J-200D01*
G02X1780158Y951793I-1106J1019D01*
G02X1778656Y953295I0J1502D01*
G02X1779141Y954401I1504J0D01*
G03X1779206Y954548I-135J148D01*
G01Y954842D01*
G03X1779141Y954989I-200J-1D01*
G02X1778656Y956095I1019J1106D01*
G02X1780158Y957597I1502J0D01*
G02X1781264Y957112I0J-1504D01*
G03X1781411Y957047I148J135D01*
G37*
G36*
G01X1806711Y965113D02*
Y965407D01*
G03X1806646Y965554I-200J-1D01*
G02X1806161Y966660I1019J1106D01*
G02X1809165I1502J0D01*
G02X1808680Y965554I-1504J0D01*
G03X1808615Y965407I135J-148D01*
G01Y965113D01*
G03X1808680Y964966I200J1D01*
G02X1809165Y963860I-1019J-1106D01*
G02X1806161I-1502J0D01*
G02X1806646Y964966I1504J0D01*
G03X1806711Y965113I-135J148D01*
G37*
G36*
G01X1796963Y1075686D02*
X1796990Y1075660D01*
X1797061Y1075632D01*
X1797411D01*
X1797482Y1075660D01*
X1797509Y1075686D01*
G02X1798536Y1076092I1027J-1096D01*
G02X1800038Y1074590I0J-1502D01*
G02X1799668Y1073603I-1501J0D01*
G01Y1073602D01*
X1799667D01*
G03X1799619Y1073472I152J-130D01*
G01Y1073208D01*
G03X1799667Y1073078I200J0D01*
G01X1799668Y1073077D01*
G02X1800038Y1072090I-1131J-987D01*
G02X1798536Y1070588I-1502J0D01*
G02X1797509Y1070994I0J1502D01*
G01X1797482Y1071020D01*
X1797411Y1071048D01*
X1797061D01*
X1796990Y1071020D01*
X1796963Y1070994D01*
G02X1794909I-1027J1096D01*
G01X1794882Y1071020D01*
X1794811Y1071048D01*
X1794461D01*
X1794390Y1071020D01*
X1794363Y1070994D01*
G02X1792309I-1027J1096D01*
G01X1792282Y1071020D01*
X1792211Y1071048D01*
X1791861D01*
X1791790Y1071020D01*
X1791763Y1070994D01*
G02X1790736Y1070588I-1027J1096D01*
G02X1789234Y1072090I0J1502D01*
G02X1789604Y1073077I1501J0D01*
G01Y1073078D01*
X1789605D01*
G03X1789653Y1073208I-152J130D01*
G01Y1073472D01*
G03X1789605Y1073602I-200J0D01*
G01X1789604Y1073603D01*
G02X1789234Y1074590I1131J987D01*
G02X1790736Y1076092I1502J0D01*
G02X1791763Y1075686I0J-1502D01*
G01X1791790Y1075660D01*
X1791861Y1075632D01*
X1792211D01*
X1792282Y1075660D01*
X1792309Y1075686D01*
G02X1794363I1027J-1096D01*
G01X1794390Y1075660D01*
X1794461Y1075632D01*
X1794811D01*
X1794882Y1075660D01*
X1794909Y1075686D01*
G02X1796963I1027J-1096D01*
G37*
G36*
G01X1782225Y1075803D02*
X1782252Y1075777D01*
X1782323Y1075749D01*
X1782673D01*
X1782744Y1075777D01*
X1782771Y1075803D01*
G02X1783798Y1076209I1027J-1096D01*
G02X1785300Y1074707I0J-1502D01*
G02X1784930Y1073720I-1501J0D01*
G01Y1073719D01*
X1784929D01*
G03X1784881Y1073589I152J-130D01*
G01Y1073325D01*
G03X1784929Y1073195I200J0D01*
G01X1784930Y1073194D01*
G02X1785300Y1072207I-1131J-987D01*
G02X1783798Y1070705I-1502J0D01*
G02X1782771Y1071111I0J1502D01*
G01X1782744Y1071137D01*
X1782673Y1071165D01*
X1782323D01*
X1782252Y1071137D01*
X1782225Y1071111D01*
G02X1780171I-1027J1096D01*
G01X1780144Y1071137D01*
X1780073Y1071165D01*
X1779723D01*
X1779652Y1071137D01*
X1779625Y1071111D01*
G02X1777571I-1027J1096D01*
G01X1777544Y1071137D01*
X1777473Y1071165D01*
X1777123D01*
X1777052Y1071137D01*
X1777025Y1071111D01*
G02X1775998Y1070705I-1027J1096D01*
G02X1774496Y1072207I0J1502D01*
G02X1774866Y1073194I1501J0D01*
G01Y1073195D01*
X1774867D01*
G03X1774915Y1073325I-152J130D01*
G01Y1073589D01*
G03X1774867Y1073719I-200J0D01*
G01X1774866Y1073720D01*
G02X1774496Y1074707I1131J987D01*
G02X1775998Y1076209I1502J0D01*
G02X1777025Y1075803I0J-1502D01*
G01X1777052Y1075777D01*
X1777123Y1075749D01*
X1777473D01*
X1777544Y1075777D01*
X1777571Y1075803D01*
G02X1779625I1027J-1096D01*
G01X1779652Y1075777D01*
X1779723Y1075749D01*
X1780073D01*
X1780144Y1075777D01*
X1780171Y1075803D01*
G02X1782225I1027J-1096D01*
G37*
G36*
G01X1789070Y1085152D02*
G02X1792074I1502J0D01*
G02X1791706Y1084167I-1502J0D01*
G01X1791681Y1084139D01*
X1791656Y1084069D01*
X1791665Y1083723D01*
X1791694Y1083654D01*
X1791720Y1083628D01*
G02X1792141Y1082585I-1081J-1043D01*
G02X1789137I-1502J0D01*
G02X1789505Y1083570I1502J0D01*
G01X1789530Y1083598D01*
X1789555Y1083668D01*
X1789546Y1084014D01*
X1789517Y1084083D01*
X1789491Y1084109D01*
G02X1789070Y1085152I1081J1043D01*
G37*
G36*
G01X1781353Y1093447D02*
X1781380Y1093421D01*
X1781451Y1093393D01*
X1781801D01*
X1781872Y1093421D01*
X1781899Y1093447D01*
G02X1782926Y1093853I1027J-1096D01*
G02X1784428Y1092351I0J-1502D01*
G02X1784058Y1091364I-1501J0D01*
G01Y1091363D01*
X1784057D01*
G03X1784009Y1091233I152J-130D01*
G01Y1090969D01*
G03X1784057Y1090839I200J0D01*
G01X1784058Y1090838D01*
G02X1784428Y1089851I-1131J-987D01*
G02X1782926Y1088349I-1502J0D01*
G02X1781899Y1088755I0J1502D01*
G01X1781872Y1088781D01*
X1781801Y1088809D01*
X1781451D01*
X1781380Y1088781D01*
X1781353Y1088755D01*
G02X1779299I-1027J1096D01*
G01X1779272Y1088781D01*
X1779201Y1088809D01*
X1778851D01*
X1778780Y1088781D01*
X1778753Y1088755D01*
G02X1776699I-1027J1096D01*
G01X1776672Y1088781D01*
X1776601Y1088809D01*
X1776251D01*
X1776180Y1088781D01*
X1776153Y1088755D01*
G02X1775126Y1088349I-1027J1096D01*
G02X1773624Y1089851I0J1502D01*
G02X1773994Y1090838I1501J0D01*
G01Y1090839D01*
X1773995D01*
G03X1774043Y1090969I-152J130D01*
G01Y1091233D01*
G03X1773995Y1091363I-200J0D01*
G01X1773994Y1091364D01*
G02X1773624Y1092351I1131J987D01*
G02X1775126Y1093853I1502J0D01*
G02X1776153Y1093447I0J-1502D01*
G01X1776180Y1093421D01*
X1776251Y1093393D01*
X1776601D01*
X1776672Y1093421D01*
X1776699Y1093447D01*
G02X1778753I1027J-1096D01*
G01X1778780Y1093421D01*
X1778851Y1093393D01*
X1779201D01*
X1779272Y1093421D01*
X1779299Y1093447D01*
G02X1781353I1027J-1096D01*
G37*
G36*
G01X1815910Y1095488D02*
Y1095802D01*
G03X1815833Y1095960I-200J0D01*
G02X1815254Y1097145I923J1185D01*
G02X1818258I1502J0D01*
G02X1817679Y1095960I-1502J0D01*
G03X1817602Y1095802I123J-158D01*
G01Y1095488D01*
G03X1817679Y1095330I200J0D01*
G02X1818258Y1094145I-923J-1185D01*
G02X1815254I-1502J0D01*
G02X1815833Y1095330I1502J0D01*
G03X1815910Y1095488I-123J158D01*
G37*
G36*
G01X1781593Y1112134D02*
X1781620Y1112108D01*
X1781691Y1112080D01*
X1782041D01*
X1782112Y1112108D01*
X1782139Y1112134D01*
G02X1783166Y1112540I1027J-1096D01*
G02X1784668Y1111038I0J-1502D01*
G01Y1111037D01*
G02X1784290Y1110041I-1502J0D01*
G01X1784264Y1110012D01*
X1784238Y1109939D01*
X1784249Y1109626D01*
G03X1784310Y1109489I200J7D01*
G02X1784764Y1108413I-1048J-1076D01*
G02X1783262Y1106911I-1502J0D01*
G02X1782235Y1107317I0J1502D01*
G01X1782208Y1107343D01*
X1782137Y1107371D01*
X1781787D01*
X1781716Y1107343D01*
X1781689Y1107317D01*
G02X1779635I-1027J1096D01*
G01X1779608Y1107343D01*
X1779537Y1107371D01*
X1779187D01*
X1779116Y1107343D01*
X1779089Y1107317D01*
G02X1777035I-1027J1096D01*
G01X1777008Y1107343D01*
X1776937Y1107371D01*
X1776587D01*
X1776516Y1107343D01*
X1776489Y1107317D01*
G02X1775462Y1106911I-1027J1096D01*
G02X1773960Y1108413I0J1502D01*
G01Y1108414D01*
G02X1774338Y1109410I1502J0D01*
G01X1774364Y1109439D01*
X1774390Y1109512D01*
X1774379Y1109825D01*
G03X1774318Y1109962I-200J-7D01*
G02X1773864Y1111038I1048J1076D01*
G02X1775366Y1112540I1502J0D01*
G02X1776393Y1112134I0J-1502D01*
G01X1776420Y1112108D01*
X1776491Y1112080D01*
X1776841D01*
X1776912Y1112108D01*
X1776939Y1112134D01*
G02X1778993I1027J-1096D01*
G01X1779020Y1112108D01*
X1779091Y1112080D01*
X1779441D01*
X1779512Y1112108D01*
X1779539Y1112134D01*
G02X1781593I1027J-1096D01*
G37*
G36*
G01X1803506Y1116091D02*
G02X1804572Y1115647I0J-1502D01*
G03X1804714Y1115588I142J141D01*
G01X1804998D01*
G03X1805140Y1115647I0J200D01*
G02X1806206Y1116091I1066J-1058D01*
G02Y1113087I0J-1502D01*
G02X1805140Y1113531I0J1502D01*
G03X1804998Y1113590I-142J-141D01*
G01X1804714D01*
G03X1804572Y1113531I0J-200D01*
G02X1803506Y1113087I-1066J1058D01*
G02X1802479Y1113493I0J1502D01*
G01X1802452Y1113519D01*
X1802381Y1113547D01*
X1802031D01*
X1801960Y1113519D01*
X1801933Y1113493D01*
G02X1799879I-1027J1096D01*
G01X1799852Y1113519D01*
X1799781Y1113547D01*
X1799431D01*
X1799360Y1113519D01*
X1799333Y1113493D01*
G02X1798306Y1113087I-1027J1096D01*
G02Y1116091I0J1502D01*
G02X1799333Y1115685I0J-1502D01*
G01X1799360Y1115659D01*
X1799431Y1115631D01*
X1799781D01*
X1799852Y1115659D01*
X1799879Y1115685D01*
G02X1801933I1027J-1096D01*
G01X1801960Y1115659D01*
X1802031Y1115631D01*
X1802381D01*
X1802452Y1115659D01*
X1802479Y1115685D01*
G02X1803506Y1116091I1027J-1096D01*
G37*
G36*
G01X1790521Y1122624D02*
G02X1791587Y1122180I0J-1502D01*
G03X1791729Y1122121I142J141D01*
G01X1792013D01*
G03X1792155Y1122180I0J200D01*
G02X1793221Y1122624I1066J-1058D01*
G02Y1119620I0J-1502D01*
G02X1792155Y1120064I0J1502D01*
G03X1792013Y1120123I-142J-141D01*
G01X1791729D01*
G03X1791587Y1120064I0J-200D01*
G02X1790521Y1119620I-1066J1058D01*
G02X1789494Y1120026I0J1502D01*
G01X1789467Y1120052D01*
X1789396Y1120080D01*
X1789046D01*
X1788975Y1120052D01*
X1788948Y1120026D01*
G02X1786894I-1027J1096D01*
G01X1786867Y1120052D01*
X1786796Y1120080D01*
X1786446D01*
X1786375Y1120052D01*
X1786348Y1120026D01*
G02X1785321Y1119620I-1027J1096D01*
G02Y1122624I0J1502D01*
G02X1786348Y1122218I0J-1502D01*
G01X1786375Y1122192D01*
X1786446Y1122164D01*
X1786796D01*
X1786867Y1122192D01*
X1786894Y1122218D01*
G02X1788948I1027J-1096D01*
G01X1788975Y1122192D01*
X1789046Y1122164D01*
X1789396D01*
X1789467Y1122192D01*
X1789494Y1122218D01*
G02X1790521Y1122624I1027J-1096D01*
G37*
G36*
G01X1803902Y1125830D02*
G02X1804968Y1125386I0J-1502D01*
G03X1805110Y1125327I142J141D01*
G01X1805394D01*
G03X1805536Y1125386I0J200D01*
G02X1806602Y1125830I1066J-1058D01*
G02Y1122826I0J-1502D01*
G02X1805536Y1123270I0J1502D01*
G03X1805394Y1123329I-142J-141D01*
G01X1805110D01*
G03X1804968Y1123270I0J-200D01*
G02X1803902Y1122826I-1066J1058D01*
G02X1802875Y1123232I0J1502D01*
G01X1802848Y1123258D01*
X1802777Y1123286D01*
X1802427D01*
X1802356Y1123258D01*
X1802329Y1123232D01*
G02X1800275I-1027J1096D01*
G01X1800248Y1123258D01*
X1800177Y1123286D01*
X1799827D01*
X1799756Y1123258D01*
X1799729Y1123232D01*
G02X1798702Y1122826I-1027J1096D01*
G02Y1125830I0J1502D01*
G02X1799729Y1125424I0J-1502D01*
G01X1799756Y1125398D01*
X1799827Y1125370D01*
X1800177D01*
X1800248Y1125398D01*
X1800275Y1125424D01*
G02X1802329I1027J-1096D01*
G01X1802356Y1125398D01*
X1802427Y1125370D01*
X1802777D01*
X1802848Y1125398D01*
X1802875Y1125424D01*
G02X1803902Y1125830I1027J-1096D01*
G37*
G36*
G01X1790521Y1132324D02*
G02X1791587Y1131880I0J-1502D01*
G03X1791729Y1131821I142J141D01*
G01X1792013D01*
G03X1792155Y1131880I0J200D01*
G02X1793221Y1132324I1066J-1058D01*
G02Y1129320I0J-1502D01*
G02X1792155Y1129764I0J1502D01*
G03X1792013Y1129823I-142J-141D01*
G01X1791729D01*
G03X1791587Y1129764I0J-200D01*
G02X1790521Y1129320I-1066J1058D01*
G02X1789494Y1129726I0J1502D01*
G01X1789467Y1129752D01*
X1789396Y1129780D01*
X1789046D01*
X1788975Y1129752D01*
X1788948Y1129726D01*
G02X1786894I-1027J1096D01*
G01X1786867Y1129752D01*
X1786796Y1129780D01*
X1786446D01*
X1786375Y1129752D01*
X1786348Y1129726D01*
G02X1785321Y1129320I-1027J1096D01*
G02Y1132324I0J1502D01*
G02X1786348Y1131918I0J-1502D01*
G01X1786375Y1131892D01*
X1786446Y1131864D01*
X1786796D01*
X1786867Y1131892D01*
X1786894Y1131918D01*
G02X1788948I1027J-1096D01*
G01X1788975Y1131892D01*
X1789046Y1131864D01*
X1789396D01*
X1789467Y1131892D01*
X1789494Y1131918D01*
G02X1790521Y1132324I1027J-1096D01*
G37*
G36*
G01X1804532Y1131854D02*
G02Y1134858I0J1502D01*
G02X1805598Y1134414I0J-1502D01*
G03X1805740Y1134355I142J141D01*
G01X1806024D01*
G03X1806166Y1134414I0J200D01*
G02X1807232Y1134858I1066J-1058D01*
G02Y1131854I0J-1502D01*
G02X1806166Y1132298I0J1502D01*
G03X1806024Y1132357I-142J-141D01*
G01X1805740D01*
G03X1805598Y1132298I0J-200D01*
G02X1804532Y1131854I-1066J1058D01*
G37*
G36*
G01X1807035Y1135410D02*
G02Y1138414I0J1502D01*
G02X1808022Y1138044I0J-1501D01*
G01X1808023D01*
Y1138043D01*
G03X1808153Y1137995I130J152D01*
G01X1808417D01*
G03X1808547Y1138043I0J200D01*
G01X1808548Y1138044D01*
G02X1809535Y1138414I987J-1131D01*
G02Y1135410I0J-1502D01*
G02X1808548Y1135780I0J1501D01*
G01X1808547D01*
Y1135781D01*
G03X1808417Y1135829I-130J-152D01*
G01X1808153D01*
G03X1808023Y1135781I0J-200D01*
G01X1808022Y1135780D01*
G02X1807035Y1135410I-987J1131D01*
G37*
G36*
G01X1781874Y1138320D02*
G02Y1141324I0J1502D01*
G02X1782861Y1140954I0J-1501D01*
G01X1782862D01*
Y1140953D01*
G03X1782992Y1140905I130J152D01*
G01X1783256D01*
G03X1783386Y1140953I0J200D01*
G01X1783387Y1140954D01*
G02X1784374Y1141324I987J-1131D01*
G02Y1138320I0J-1502D01*
G02X1783387Y1138690I0J1501D01*
G01X1783386D01*
Y1138691D01*
G03X1783256Y1138739I-130J-152D01*
G01X1782992D01*
G03X1782862Y1138691I0J-200D01*
G01X1782861Y1138690D01*
G02X1781874Y1138320I-987J1131D01*
G37*
G36*
G01X1807035Y1143410D02*
G02Y1146414I0J1502D01*
G02X1808022Y1146044I0J-1501D01*
G01X1808023D01*
Y1146043D01*
G03X1808153Y1145995I130J152D01*
G01X1808417D01*
G03X1808547Y1146043I0J200D01*
G01X1808548Y1146044D01*
G02X1809535Y1146414I987J-1131D01*
G02Y1143410I0J-1502D01*
G02X1808548Y1143780I0J1501D01*
G01X1808547D01*
Y1143781D01*
G03X1808417Y1143829I-130J-152D01*
G01X1808153D01*
G03X1808023Y1143781I0J-200D01*
G01X1808022Y1143780D01*
G02X1807035Y1143410I-987J1131D01*
G37*
G36*
G01X1781802Y1146320D02*
G02Y1149324I0J1502D01*
G02X1782789Y1148954I0J-1501D01*
G01X1782790D01*
Y1148953D01*
G03X1782920Y1148905I130J152D01*
G01X1783184D01*
G03X1783314Y1148953I0J200D01*
G01X1783315Y1148954D01*
G02X1784302Y1149324I987J-1131D01*
G02Y1146320I0J-1502D01*
G02X1783315Y1146690I0J1501D01*
G01X1783314D01*
Y1146691D01*
G03X1783184Y1146739I-130J-152D01*
G01X1782920D01*
G03X1782790Y1146691I0J-200D01*
G01X1782789Y1146690D01*
G02X1781802Y1146320I-987J1131D01*
G37*
G36*
G01X1798332Y1264676D02*
X1798333Y1264675D01*
G03X1798463Y1264627I130J152D01*
G01X1798727D01*
G03X1798857Y1264675I0J200D01*
G01X1798858Y1264676D01*
G02X1799845Y1265046I987J-1131D01*
G02X1801347Y1263544I0J-1502D01*
G02X1800977Y1262557I-1501J0D01*
G01Y1262556D01*
X1800976D01*
G03X1800928Y1262426I152J-130D01*
G01Y1262162D01*
G03X1800976Y1262032I200J0D01*
G01X1800977Y1262031D01*
G02X1801347Y1261044I-1131J-987D01*
G02X1799845Y1259542I-1502J0D01*
G02X1798858Y1259912I0J1501D01*
G01X1798857D01*
Y1259913D01*
G03X1798727Y1259961I-130J-152D01*
G01X1798463D01*
G03X1798333Y1259913I0J-200D01*
G01X1798332Y1259912D01*
G02X1796358I-987J1131D01*
G01X1796357D01*
Y1259913D01*
G03X1796227Y1259961I-130J-152D01*
G01X1795963D01*
G03X1795833Y1259913I0J-200D01*
G01X1795832Y1259912D01*
G02X1794845Y1259542I-987J1131D01*
G02X1793343Y1261044I0J1502D01*
G02X1793713Y1262031I1501J0D01*
G01Y1262032D01*
X1793714D01*
G03X1793762Y1262162I-152J130D01*
G01Y1262426D01*
G03X1793714Y1262556I-200J0D01*
G01X1793713Y1262557D01*
G02X1793343Y1263544I1131J987D01*
G02X1794845Y1265046I1502J0D01*
G02X1795832Y1264676I0J-1501D01*
G01X1795833D01*
Y1264675D01*
G03X1795963Y1264627I130J152D01*
G01X1796227D01*
G03X1796357Y1264675I0J200D01*
G01X1796358Y1264676D01*
G02X1798332I987J-1131D01*
G37*
G36*
G01X1782563Y981162D02*
G02X1783787Y980530I0J-1501D01*
G03X1783950Y980446I163J116D01*
G01X1784276D01*
G03X1784439Y980530I0J200D01*
G02X1785663Y981162I1224J-869D01*
G02Y978158I0J-1502D01*
G02X1784439Y978790I0J1501D01*
G03X1784276Y978874I-163J-116D01*
G01X1783950D01*
G03X1783787Y978790I0J-200D01*
G02X1782563Y978158I-1224J869D01*
G02X1781300Y978848I0J1501D01*
G03X1781131Y978940I-168J-108D01*
G01X1780795D01*
G03X1780626Y978848I-1J-200D01*
G02X1779363Y978158I-1263J811D01*
G02Y981162I0J1502D01*
G02X1780626Y980472I0J-1501D01*
G03X1780795Y980380I168J108D01*
G01X1781131D01*
G03X1781300Y980472I1J200D01*
G02X1782563Y981162I1263J-811D01*
G37*
G36*
G01X1760531Y991010D02*
G02X1760201Y990973I-331J1465D01*
G02X1761703Y992475I0J1502D01*
G01Y992474D01*
G02X1761676Y992191I-1502J1D01*
G03X1762156Y991725I393J-76D01*
G02X1762486Y991762I331J-1465D01*
G02X1760984Y990260I0J-1502D01*
G01Y990261D01*
G02X1761011Y990544I1502J-1D01*
G03X1760531Y991010I-393J76D01*
G37*
G36*
G01X1770271Y1028845D02*
G02X1771773Y1030331I1502J-16D01*
G02Y1027327I0J-1502D01*
G02X1770962Y1027565I0J1501D01*
G03X1770346Y1027232I-216J-337D01*
G02X1768844Y1025746I-1502J16D01*
G02Y1028750I0J1502D01*
G02X1769655Y1028512I0J-1501D01*
G03X1770271Y1028845I216J337D01*
G37*
G36*
G01X1776607Y185330D02*
X1776742Y185710D01*
X1776732Y185800D01*
X1776708Y185839D01*
G02X1776483Y186629I1277J791D01*
G02X1779487I1502J0D01*
G02X1778484Y185212I-1502J0D01*
G01X1778440Y185197D01*
X1778377Y185133D01*
X1778242Y184753D01*
X1778252Y184663D01*
X1778276Y184624D01*
G02X1778501Y183834I-1277J-791D01*
G02X1775497I-1502J0D01*
G02X1776500Y185251I1502J0D01*
G01X1776544Y185266D01*
X1776607Y185330D01*
G37*
G54D37*
X876200Y86012D03*
Y94374D03*
X429919Y141247D03*
X445949D03*
X887005D03*
X903035D03*
X450436Y143518D03*
X907522D03*
X437386Y143740D03*
X894472D03*
X458181Y157370D03*
X915267D03*
X899573Y158195D03*
X891383Y243203D03*
X896034Y243307D03*
X910977D03*
Y248032D03*
X887148Y249670D03*
X895064Y250186D03*
X885884Y255118D03*
X897004Y257480D03*
X892484Y260860D03*
X910977Y262205D03*
X883118Y262687D03*
X895140Y265236D03*
X886496Y268968D03*
X943183Y281652D03*
X991246Y281716D03*
X886059Y284644D03*
X790280Y287421D03*
X359376Y290592D03*
X805952Y301675D03*
X930727Y302571D03*
X327032Y303962D03*
X784118D03*
X923732Y304585D03*
X718338Y305272D03*
X809490Y305368D03*
X817456D03*
X869924D03*
X885989D03*
X915653Y307438D03*
X257993Y307994D03*
X822477Y309368D03*
X863430D03*
X877977D03*
X885989D03*
X164496Y309405D03*
X1002580Y309619D03*
X592900Y309871D03*
X913057Y311046D03*
X170215Y311671D03*
X817456Y313368D03*
X869924D03*
X877977D03*
X885989D03*
X230842Y313888D03*
X987517Y314092D03*
X519638Y314346D03*
X286940Y315039D03*
X348806Y315427D03*
X741051Y316389D03*
X863430Y316970D03*
X809490Y317368D03*
X877977D03*
X885989D03*
X950953Y317947D03*
X1001105Y318006D03*
X993552Y318175D03*
X348351Y319372D03*
X817100Y319600D03*
X947733Y319680D03*
X1041783Y321114D03*
X809490Y321368D03*
X869924D03*
X877977D03*
X885953D03*
X351132Y322202D03*
X1003181Y323057D03*
X1195800Y324000D03*
X1190127Y324142D03*
X318508Y324322D03*
X863114Y324505D03*
X312263Y324518D03*
X769349D03*
X842240Y324854D03*
X441296Y325061D03*
X809490Y325368D03*
X877977D03*
X885953D03*
X801097Y325858D03*
X869924Y328722D03*
X301943Y328867D03*
X759029D03*
X1115000Y329000D03*
X877977Y329368D03*
X885953D03*
X863040Y330140D03*
X1215776Y331072D03*
X400993Y331589D03*
X977150Y331972D03*
X1187996Y331992D03*
X1003076Y332496D03*
X315944Y332584D03*
X772162D03*
X443424Y332988D03*
X800029Y333368D03*
X877977D03*
X885953D03*
X1042948Y333696D03*
X1115000Y334000D03*
X349120Y336100D03*
X234986Y336161D03*
X1137830Y336230D03*
X584679Y336285D03*
X1179761Y336380D03*
X578193Y336391D03*
X410086Y336795D03*
X800155Y337368D03*
X977150Y338972D03*
X1115000Y339000D03*
X682857Y339477D03*
X297719Y339559D03*
X754805D03*
X1211892D03*
X689486Y339583D03*
X1043106Y340230D03*
X983717Y341665D03*
X236264Y342494D03*
X861770Y343006D03*
X1061387Y343509D03*
X989630Y343862D03*
X443480Y344014D03*
X1009770Y344486D03*
X410688Y344736D03*
X874005Y344917D03*
X825971Y345101D03*
X829485D03*
X997020Y345354D03*
X983956Y346652D03*
X316067Y347937D03*
X772859D03*
X1229942D03*
X472810Y347995D03*
X321416Y348015D03*
X778502D03*
X1235589D03*
X531636Y349057D03*
X988631Y349496D03*
X291396Y350223D03*
X551536D03*
X797141Y350368D03*
X1031259Y350427D03*
X1020406Y350772D03*
X491843Y351089D03*
X526388Y351301D03*
X472608Y352495D03*
X400728Y353152D03*
X774419Y353470D03*
X1231506D03*
X371417Y353820D03*
X435886Y353867D03*
X759624Y353961D03*
X531612Y354272D03*
X365559Y354300D03*
X551536Y354723D03*
X440538Y355372D03*
X845435Y356172D03*
X856069Y356426D03*
X852569Y356712D03*
X411007Y356743D03*
X492817Y357111D03*
X416574Y357528D03*
X934464Y358618D03*
X426830Y359026D03*
X421413Y359053D03*
X233258Y359186D03*
X551536Y359223D03*
X1284419Y359377D03*
X126131Y359511D03*
X532659Y359557D03*
X467335Y359944D03*
X872158Y359962D03*
X472913Y360089D03*
X944238Y360828D03*
X848879Y360849D03*
X905000Y362158D03*
X496023Y362913D03*
X551536Y363723D03*
X533211Y364746D03*
X936175Y364823D03*
X491053Y365423D03*
X125753Y365856D03*
X980045Y366559D03*
X469530Y366754D03*
X906161Y367191D03*
X455885Y367702D03*
X420422Y367859D03*
X412318Y367903D03*
X551536Y368223D03*
X1060679Y368276D03*
X472913Y369089D03*
X481724D03*
X934047Y369160D03*
X528812Y369164D03*
X497048Y369450D03*
X986373Y370467D03*
X377237Y371060D03*
X381237Y371076D03*
X1267944Y371767D03*
X533115Y371856D03*
X450852Y372054D03*
X351136Y372334D03*
X929943Y372600D03*
X551536Y372723D03*
X913288Y372752D03*
X472913Y373589D03*
X481724D03*
X490885D03*
X854086Y374500D03*
X858586D03*
X863086D03*
X98255Y374510D03*
X573479Y374705D03*
X530144Y376062D03*
X687055Y376456D03*
X350486Y377173D03*
X358491D03*
X366526D03*
X370486D03*
X1264659D03*
X1280699D03*
X1284659D03*
X551536Y377223D03*
X1274436Y377350D03*
X495750Y377531D03*
X100120Y377898D03*
X299000Y377912D03*
X756086D03*
X766344D03*
X1213173D03*
X1223431D03*
X472913Y378089D03*
X481724D03*
X569938Y378317D03*
X384173Y379028D03*
X1298346D03*
X378875Y379088D03*
X1293048D03*
X373264Y379429D03*
X1287437D03*
X723404Y379657D03*
X506500Y379687D03*
X531953Y380749D03*
X731511Y381113D03*
X274425Y381500D03*
X1188598D03*
X551536Y381723D03*
X766344Y381912D03*
X1223431D03*
X100066Y381976D03*
X295699Y382047D03*
X752785D03*
X1209872D03*
X490885Y382570D03*
X472913Y382589D03*
X481724D03*
X860586Y383000D03*
X292520Y384410D03*
X749606D03*
X1206693D03*
X721900Y384500D03*
X553563Y384987D03*
X354486Y385123D03*
X366486D03*
X1268659D03*
X1280659D03*
X349311Y385644D03*
X1263484D03*
X531953Y385749D03*
X541706Y386223D03*
X299000Y386500D03*
X756086D03*
X1213173D03*
X495203Y386890D03*
X931072Y386992D03*
X472913Y387089D03*
X533189Y390723D03*
X551620D03*
X298000Y391496D03*
X723440D03*
X755086D03*
X1212173D03*
X347591Y391533D03*
X1261764D03*
X370160Y391569D03*
X1284333D03*
X472913Y391589D03*
X491289D03*
X877909Y391731D03*
X890553Y392038D03*
X542034Y392209D03*
X1191748Y392676D03*
X960376Y392807D03*
X734661Y393633D03*
X292358Y393858D03*
X749444D03*
X1206531D03*
X861235Y394000D03*
X470796Y394592D03*
X277575Y395084D03*
X228267Y396718D03*
X685353D03*
X1142440D03*
X531992Y397552D03*
X299088Y397912D03*
X756174D03*
X766344D03*
X1213261D03*
X1223431D03*
X868586Y398500D03*
X294000Y398583D03*
X723440D03*
X751086D03*
X1208173D03*
X347058Y399918D03*
X1261231D03*
X368587Y401066D03*
X1282760D03*
X968348Y402369D03*
X296000Y403500D03*
X753086D03*
X1210173D03*
X717420Y404334D03*
X789581Y405011D03*
X353894Y406060D03*
X1268067D03*
X869342Y407627D03*
X971721Y407762D03*
X846098Y408715D03*
X298000Y409000D03*
X755086D03*
X1212173D03*
X991392Y409230D03*
X793893Y409502D03*
X717105Y410964D03*
X849591Y411388D03*
X855017Y411969D03*
X350163Y412106D03*
X1264336D03*
X488438Y418417D03*
X256475Y422088D03*
X1171445D03*
X971826Y430187D03*
X432270Y431112D03*
X1346443D03*
X489485Y431417D03*
X481485Y431917D03*
X437835Y435101D03*
X1352008D03*
X278784Y435158D03*
X1192957D03*
X485485Y439903D03*
X489485D03*
X432440Y440101D03*
X1346613D03*
X278529Y440489D03*
X1192702D03*
X438098Y442114D03*
X1352271D03*
X520823Y442603D03*
X274949Y442606D03*
X732035D03*
X1189122D03*
X720996Y442856D03*
X1178083D03*
X48643Y442919D03*
X512943Y443071D03*
X278827Y444841D03*
X1193000D03*
X65737Y445603D03*
X979910D03*
X254678Y445873D03*
X711764D03*
X1168851D03*
X57857Y446071D03*
X972030D03*
X722097Y446595D03*
X1179184D03*
X274866Y446606D03*
X731952D03*
X1188739D03*
X438078Y447121D03*
X1352251D03*
X927596Y447453D03*
X810406Y448214D03*
X503682Y448419D03*
X280220Y448493D03*
X414910Y448931D03*
X1329083D03*
X735599Y449961D03*
X1192686D03*
X824650Y450034D03*
X794173Y450510D03*
X262526Y451108D03*
X719612D03*
X1176699D03*
X48596Y451419D03*
X933161Y451442D03*
X438086Y452601D03*
X1352259D03*
X432075Y452718D03*
X1346248D03*
X421267Y452799D03*
X1335440D03*
X426647Y452987D03*
X1340820D03*
X810453Y453330D03*
X265011Y453881D03*
X722097D03*
X1179184D03*
X353320Y454214D03*
X1267493D03*
X345050Y454334D03*
X1259223D03*
X824650Y455034D03*
X367564Y456034D03*
X1281737D03*
X1168398Y456309D03*
X710643Y456335D03*
X250336Y456386D03*
X927766Y456442D03*
X261965Y458455D03*
X719051D03*
X933424D03*
X1176138D03*
X282230Y458572D03*
X739316D03*
X1196403D03*
X415433Y459170D03*
X1329606D03*
X353367Y459330D03*
X1267540D03*
X518240Y459371D03*
X367564Y461034D03*
X1281737D03*
X504729Y461419D03*
X425673Y461607D03*
X429673D03*
X433673D03*
X1339846D03*
X522756Y461818D03*
X496729Y461919D03*
X63154Y462371D03*
X977327D03*
X933404Y463462D03*
X275873Y463479D03*
X732959D03*
X1190046D03*
X459757Y463520D03*
X49643Y464419D03*
X67670Y464818D03*
X981843D03*
X41643Y464919D03*
X910236Y465272D03*
X1134629Y465551D03*
X220349Y465622D03*
X385293Y466409D03*
X1299466D03*
X276344Y467367D03*
X733430D03*
X405301Y467560D03*
X1319474D03*
X459414Y468689D03*
X933412Y468942D03*
X927401Y469059D03*
X916593Y469140D03*
X921973Y469328D03*
X500729Y469905D03*
X504729D03*
X517310Y470045D03*
X393662Y470382D03*
X1307835D03*
X496729Y470419D03*
X424876Y471334D03*
X1339049D03*
X397315Y471560D03*
X1311488D03*
X385634Y472020D03*
X1299807D03*
X45643Y472905D03*
X49643D03*
X959816D03*
X963816D03*
X62224Y473045D03*
X976397D03*
X41643Y473419D03*
X393646Y474382D03*
X1307819D03*
X418801Y474513D03*
X1332974D03*
X910759Y475511D03*
X397315Y475560D03*
X405801D03*
X1311488D03*
X1319974D03*
X385694Y477318D03*
X1299867D03*
X920999Y477948D03*
X924999D03*
X928999D03*
X869454Y479303D03*
X40009Y481467D03*
X497095D03*
X954182D03*
X44563Y482165D03*
X501649D03*
X958736D03*
X861468Y483303D03*
X882954Y486256D03*
X891454Y486303D03*
X861468Y487303D03*
X869954D03*
X373971Y489036D03*
X1288144D03*
X35650Y491982D03*
X492736D03*
X949823D03*
X501224Y492050D03*
X43948Y492108D03*
X958124Y492354D03*
X858169Y495032D03*
X502493Y495917D03*
X35650Y495982D03*
X492736D03*
X949823D03*
X45256Y495993D03*
X959600Y496486D03*
X43804Y500202D03*
X500890D03*
X957977D03*
X724362Y504731D03*
X1126622Y506256D03*
X833269Y506683D03*
X464199Y510184D03*
X468558Y516609D03*
X376881Y518564D03*
X25819Y527726D03*
X482905D03*
X939992D03*
X833953Y530621D03*
X885931Y534093D03*
X892931D03*
X30177Y534211D03*
X944351D03*
X482836Y534249D03*
X34732Y534909D03*
X491818D03*
X948905D03*
X834282Y536085D03*
X882195Y539204D03*
X318660Y539315D03*
X775746D03*
X1232833D03*
X34359Y541135D03*
X491445D03*
X948532D03*
X885556Y543664D03*
X917811Y544325D03*
X25819Y544726D03*
X482905D03*
X939992D03*
X781429Y545017D03*
X874649Y545296D03*
X185328Y545528D03*
X642414D03*
X1099501D03*
X468850Y545586D03*
X34425Y546553D03*
X491511D03*
X948598D03*
X711463Y546712D03*
X25819Y548726D03*
X482905D03*
X939992D03*
X866938Y549771D03*
X327456Y550065D03*
X1241629D03*
X913728Y550495D03*
X204674Y551683D03*
X661760D03*
X1118847D03*
X34448Y552726D03*
X491534D03*
X948621D03*
X320785Y553287D03*
X777708D03*
X886549Y553963D03*
X867093Y554703D03*
X878382Y554942D03*
X1326993Y556788D03*
X914296Y558143D03*
X1319000Y558500D03*
X681126Y558800D03*
X1138213D03*
X899407Y560019D03*
X908846Y560124D03*
X923642Y561578D03*
X1319000Y562500D03*
X1327000D03*
X1338000D03*
X681190Y562800D03*
X1138277D03*
X1346738Y564492D03*
X887417Y566713D03*
X680586Y568000D03*
X1137673D03*
X1339289Y568461D03*
X923453Y569578D03*
X931627D03*
X876949Y571419D03*
X931627Y573578D03*
X1319000Y574500D03*
X867093Y574703D03*
X1346533Y576780D03*
X881131Y577349D03*
X931627Y577578D03*
X194063Y577716D03*
X651149D03*
X1108236D03*
X78733Y578405D03*
X535819D03*
X992906D03*
X1319000Y578500D03*
X875290Y578703D03*
X84159Y578986D03*
X541245D03*
X998332D03*
X1342053Y579339D03*
X923599Y581578D03*
X931627D03*
X1346533Y581898D03*
X64408Y582747D03*
X521494D03*
X978581D03*
X1340522Y586133D03*
X1319000Y586500D03*
X867093Y586828D03*
X881476Y588202D03*
X1343000Y590458D03*
X63859Y590801D03*
X520945D03*
X978032D03*
X222289Y590895D03*
X221693Y594982D03*
X665586Y595500D03*
X1122673D03*
X72515Y596089D03*
X529601D03*
X986688D03*
X83684Y596729D03*
X540770D03*
X997857D03*
X77734Y596782D03*
X534820D03*
X991907D03*
X913998Y597103D03*
X63684Y597130D03*
X520770D03*
X977857D03*
X67684Y597232D03*
X524770D03*
X981857D03*
X910789Y598726D03*
X898207Y599891D03*
X891673Y600049D03*
X247536Y602689D03*
X208000Y604567D03*
X665086D03*
X1122173D03*
X876351Y605023D03*
X59684Y605443D03*
X63684D03*
X79684D03*
X516770D03*
X520770D03*
X536770D03*
X993857D03*
X67684Y605637D03*
X524770D03*
X203500Y606929D03*
X660586D03*
X1117673D03*
X876351Y608523D03*
X925949Y608863D03*
X895933Y609696D03*
X1123331Y610072D03*
X191125Y610400D03*
X648211D03*
X1105298D03*
X40362Y610548D03*
X497448D03*
X30123Y611071D03*
X487209D03*
X944296D03*
X925949Y612363D03*
X203741Y612592D03*
X660827D03*
X1117914D03*
X666180Y616317D03*
X1123267D03*
X36494Y616905D03*
X493580D03*
X950667D03*
X891933Y618143D03*
X247278Y618288D03*
X704364D03*
X1161451D03*
X203460Y618400D03*
X660546D03*
X1117633D03*
X27686Y621311D03*
X484772D03*
X941859D03*
X36306Y622285D03*
X493392D03*
X950479D03*
X321119Y622912D03*
X778205D03*
X66530Y625013D03*
X523616D03*
X980703D03*
X27686Y625311D03*
X484772D03*
X941859D03*
X423963Y625778D03*
X778860Y626912D03*
X36575Y627713D03*
X493661D03*
X950748D03*
X58181Y627908D03*
X515267D03*
X972354D03*
X49192Y628078D03*
X506278D03*
X963365D03*
X443144Y628667D03*
X27686Y629311D03*
X484772D03*
X941859D03*
X447921Y630789D03*
X453552Y631779D03*
X879135Y632552D03*
X54192Y633473D03*
X511278D03*
X968365D03*
X42172Y633716D03*
X499258D03*
X956345D03*
X36692Y633724D03*
X493778D03*
X950865D03*
X47179Y633736D03*
X504265D03*
X961352D03*
X922626Y633772D03*
X252688Y636364D03*
X447279Y637031D03*
X456469Y638302D03*
X441162Y638313D03*
X64692Y642184D03*
X521778D03*
X978865D03*
X240194Y643113D03*
X446987Y643360D03*
X481165Y646036D03*
X665643Y646055D03*
X658233Y646449D03*
X1115320D03*
X861663Y646653D03*
X855300Y646819D03*
X658064Y650119D03*
X1115151D03*
X711328Y653821D03*
X481742Y657477D03*
X853982Y657506D03*
X848444Y657756D03*
X494465Y657772D03*
X84845Y659857D03*
X73914Y660107D03*
X483059Y662649D03*
X842640Y662814D03*
X518812Y662874D03*
X657967Y662981D03*
X1115054D03*
X95539Y664443D03*
X496070Y665976D03*
X662092Y666275D03*
X839636Y666533D03*
X521868Y666577D03*
X929690Y666593D03*
X954526Y666671D03*
X920090Y666714D03*
X872862Y666859D03*
X878881Y667156D03*
X488765Y667224D03*
X79043Y667391D03*
X650958Y668153D03*
X1108045D03*
X82648Y670679D03*
X522200Y677613D03*
X909265Y677795D03*
X1170465Y677836D03*
X859441Y678015D03*
X1001676D03*
X504966Y678098D03*
X245000Y678462D03*
X702086D03*
X1159173D03*
X248690Y678519D03*
X705776D03*
X1162863D03*
X82562Y680037D03*
X928704Y680261D03*
X935281Y680945D03*
X510425Y683246D03*
X78735Y683426D03*
X912462Y683770D03*
X84314Y686107D03*
X521540Y686319D03*
X928353Y686342D03*
X912462Y687770D03*
X864029Y688970D03*
X884911Y690279D03*
X876286Y690970D03*
X248090Y691114D03*
X659209Y691851D03*
X855646Y692710D03*
X722473Y693718D03*
X849680Y694789D03*
X876286Y694970D03*
X1169256Y694983D03*
X244267Y696911D03*
X703680Y697094D03*
X254634Y698241D03*
X543101Y698772D03*
X876286Y698970D03*
X947556Y699550D03*
X713200Y699676D03*
X838152Y700215D03*
X868919Y700894D03*
X858186Y701170D03*
X703600Y702212D03*
X906886Y702285D03*
X536087Y702364D03*
X716623Y702463D03*
X823890Y703415D03*
X829784Y705489D03*
X723656Y705858D03*
X715802Y706446D03*
X956023Y706907D03*
X965774D03*
X858002Y707244D03*
X710196Y707562D03*
X661018Y707592D03*
X1118105D03*
X500714Y708755D03*
X908699Y709387D03*
X836078Y709619D03*
X111993Y710102D03*
X823670Y710542D03*
X867455Y710611D03*
X720985Y711658D03*
X1163774Y713347D03*
X835987Y713745D03*
X913247Y714204D03*
X921061Y715386D03*
X886836Y715970D03*
X829784Y716589D03*
X845784D03*
X986600Y717641D03*
X1166115Y718469D03*
X933974Y719371D03*
X540379Y719785D03*
X502832Y720491D03*
X889525Y722060D03*
X857986Y722670D03*
X926961Y723797D03*
X818307Y724144D03*
X957763Y725336D03*
X936026Y727450D03*
X723177Y728219D03*
X424993Y728291D03*
X883686Y729778D03*
X970839Y729923D03*
X951151Y730111D03*
X978352Y730766D03*
X380963Y731000D03*
X1033200Y731700D03*
X725667Y732161D03*
X575979Y732517D03*
X1129471Y732571D03*
X391470Y732865D03*
X955950Y734178D03*
X959950D03*
X963950D03*
X854484Y738633D03*
X830484Y738750D03*
X846484D03*
X836713Y738751D03*
X721163Y738981D03*
X563200Y739600D03*
X819788Y739634D03*
X381875Y740341D03*
X406200Y741300D03*
X957579Y744168D03*
X859199Y744517D03*
X557847Y744599D03*
X981876Y745179D03*
X987461Y745796D03*
X372400Y746300D03*
X838484Y746701D03*
X854484D03*
X1148962Y747253D03*
X973450Y747280D03*
X573778Y747437D03*
X874142Y748914D03*
X881157Y749148D03*
X372300Y750000D03*
X567428Y750145D03*
X557751Y750851D03*
X570038Y752339D03*
X873728Y752692D03*
X509096Y753072D03*
X524598Y753387D03*
X879875Y753612D03*
X119099Y755052D03*
X702691Y756971D03*
X870017Y757313D03*
X564362Y757979D03*
X849500Y758500D03*
X120250Y758841D03*
X691991Y759581D03*
X429253Y759847D03*
X883413Y759855D03*
X869325Y761259D03*
X520549Y761982D03*
X702691Y762971D03*
X953837Y763025D03*
X571493Y763090D03*
X849500Y763500D03*
X965983Y763567D03*
X988371Y764143D03*
X1152485Y764552D03*
X692356Y764614D03*
X1173034Y765060D03*
X983786Y765647D03*
X1147468Y766093D03*
X883126Y766124D03*
X842661Y769521D03*
X577638Y769772D03*
X956017Y770300D03*
X1174595Y771744D03*
X846000Y772079D03*
X537578Y772428D03*
X513551Y773203D03*
X520833Y773389D03*
X692221Y773449D03*
X365850Y773950D03*
X859000Y774000D03*
X987990Y774005D03*
X578204Y775137D03*
X702677Y775159D03*
X966127Y776382D03*
X849500Y776500D03*
X1038678Y776750D03*
X984357Y777555D03*
X990699Y778630D03*
X692155Y778974D03*
X567126Y779066D03*
X950699Y779711D03*
X870000Y780000D03*
X702677Y780659D03*
X957500Y780800D03*
X849500Y781500D03*
X1043016Y782161D03*
X560263Y782207D03*
X539449Y782389D03*
X717434Y782500D03*
X373703Y782555D03*
X380331Y782627D03*
X513278Y783286D03*
X504508Y783817D03*
X571984Y784507D03*
X892040Y784511D03*
X407000Y784700D03*
X955076Y784861D03*
X587183Y785008D03*
X432303Y785067D03*
X710275Y786131D03*
X946970Y786366D03*
X421200Y786400D03*
X380607Y786932D03*
X987394Y787490D03*
X582100Y787600D03*
X889763Y788159D03*
X955225Y788984D03*
X397900Y789000D03*
X504641Y789139D03*
X942676Y789286D03*
X950475Y789361D03*
X976186Y789819D03*
X853282Y789887D03*
X1154652Y791056D03*
X371436Y791188D03*
X1164925Y791607D03*
X1169697Y791935D03*
X1046068Y792742D03*
X586060Y793145D03*
X506166Y793224D03*
X550420Y793743D03*
X556326D03*
X544515Y793875D03*
X540578Y793889D03*
X849500Y794500D03*
X859000Y796000D03*
X949609Y796051D03*
X1046930Y796557D03*
X118467Y796785D03*
X113505Y796856D03*
X109591Y796905D03*
X430600Y797400D03*
X434100D03*
X876402Y797415D03*
X489406Y797558D03*
X588345Y798030D03*
X933201Y798297D03*
X469300Y799500D03*
X849500D03*
X891916Y799605D03*
X859000Y800000D03*
X895829Y800660D03*
X874925Y800746D03*
X902641Y800748D03*
X887916Y800815D03*
X927916Y800909D03*
X1042414Y801443D03*
X1164732Y802269D03*
X1173122Y802759D03*
X1154985Y802897D03*
X1145910Y803642D03*
X383391Y804000D03*
X813000Y805000D03*
X532304Y806649D03*
X561001Y806889D03*
X459245Y807152D03*
X544741Y809649D03*
X581001Y810973D03*
X518565Y811973D03*
X256303Y812254D03*
X1039251Y812340D03*
X531313Y812850D03*
X1153485Y813142D03*
X690449Y814406D03*
X362042Y814772D03*
X507095Y814784D03*
X365691Y815127D03*
X237591Y815266D03*
X371507Y815303D03*
X733000Y816000D03*
X544878Y816309D03*
X562400Y818900D03*
X813009Y819734D03*
X582737Y819831D03*
X556741Y820149D03*
X274096Y820725D03*
X473654Y821234D03*
X712901Y821600D03*
X86289Y822088D03*
X489572Y822805D03*
X1051550Y823146D03*
X544741Y823149D03*
X581158Y823473D03*
X522481Y824661D03*
X531313Y826630D03*
X56049Y827218D03*
X68649D03*
X72149Y827318D03*
X479448Y828594D03*
X577501Y829069D03*
X588001Y829624D03*
X556326Y829989D03*
X494677Y830468D03*
X1043425Y830800D03*
X274697Y830951D03*
X1053392Y832788D03*
X1048314Y833102D03*
X532316Y833649D03*
X514682Y834590D03*
X495073Y835586D03*
X358207Y836462D03*
X1037527Y836486D03*
X252100Y836800D03*
X238400Y836900D03*
X1053913Y837718D03*
X1050358Y837793D03*
X472399Y839566D03*
X560813Y840574D03*
X1046045Y841217D03*
X74700Y842890D03*
X53549Y843118D03*
X546241Y843149D03*
X1161535Y844167D03*
X1185516Y844248D03*
X495470Y844271D03*
X524741Y845149D03*
X530741D03*
X572476Y845535D03*
X511741Y846649D03*
X463404Y846870D03*
X479700Y847600D03*
X69049Y847718D03*
X275123Y847874D03*
X86367Y848086D03*
X1153229Y848581D03*
X1190968Y848703D03*
X495700Y849389D03*
X534632Y849830D03*
X1031813Y850273D03*
X548665Y850399D03*
X65549Y850718D03*
X1163579Y850774D03*
X1184340Y851072D03*
X557836Y851669D03*
X269700Y853100D03*
X732713Y853890D03*
X1053909Y855472D03*
X1049087Y856033D03*
X1183012Y856553D03*
X1190213Y856816D03*
X136862Y857244D03*
X133424Y857303D03*
X129666Y857514D03*
X490706Y859339D03*
X68598Y859415D03*
X383462Y860535D03*
X477574Y860815D03*
X1044390Y861210D03*
X465492Y861970D03*
X503383Y863025D03*
X275400Y864400D03*
X404468Y864407D03*
X386589Y864408D03*
X396306Y864409D03*
X498507Y865392D03*
X103770Y868206D03*
X1187431Y868340D03*
X1180239Y868430D03*
X1159887Y869106D03*
X561134Y869291D03*
X63969Y869475D03*
X406770Y869767D03*
X382675Y870151D03*
X460498Y870334D03*
X397431Y870654D03*
X90000Y871389D03*
X1045300Y872352D03*
X508248Y873319D03*
X68778Y873821D03*
X525718D03*
X63930Y874694D03*
X520870D03*
X1038363Y875288D03*
X392584Y875845D03*
X592272Y877262D03*
X84367Y878286D03*
X401108Y878487D03*
X76528Y878533D03*
X1054900Y879321D03*
X405466Y881299D03*
X509791Y881932D03*
X1185058Y883475D03*
X471726Y883705D03*
X859614Y883800D03*
X425062Y883981D03*
X110887Y884000D03*
X567827D03*
X1037709Y886209D03*
X837290Y887490D03*
X1058155Y887635D03*
X859614Y887846D03*
X122887Y888000D03*
X579827D03*
X83079Y888515D03*
X74028Y889065D03*
X932300Y890200D03*
X102320Y891043D03*
X559260D03*
X1050295Y891100D03*
X942194Y891216D03*
X835346Y891346D03*
X123387Y892000D03*
X580327D03*
X826070Y893014D03*
X564165Y894411D03*
X1181654Y894671D03*
X836066Y894955D03*
X929181Y895029D03*
X842827Y895443D03*
X592110Y895611D03*
X817152Y896380D03*
X848792Y896472D03*
X559214Y897425D03*
X76203Y897910D03*
X533143D03*
X80339Y897943D03*
X72035Y898346D03*
X824804Y898395D03*
X275400Y899400D03*
X103692Y900295D03*
X941592Y900908D03*
X64632Y901500D03*
X521572D03*
X1038010Y902565D03*
X583065Y903294D03*
X966813Y904556D03*
X719661Y904900D03*
X52077Y905295D03*
X91387D03*
X509017D03*
X548327D03*
X818031Y907747D03*
X586136Y908935D03*
X982783Y909995D03*
X973988Y910038D03*
X68100Y910122D03*
X59962Y910251D03*
X516902D03*
X1012842Y910685D03*
X71528Y913190D03*
X531076D03*
X601084Y913544D03*
X525159Y913818D03*
X604715Y914640D03*
X817884Y915425D03*
X48429Y916430D03*
X825336Y916774D03*
X1018419Y917575D03*
X1022346Y917669D03*
X1029570Y917718D03*
X849600Y918028D03*
X47264Y919649D03*
X989311Y920364D03*
X1187151Y921000D03*
X471110Y921577D03*
X834751Y922368D03*
X1004953Y923995D03*
X1008935Y924007D03*
X849205Y924129D03*
X368067Y925136D03*
X841329Y926602D03*
X722789Y927095D03*
X474540Y927341D03*
X471068Y930235D03*
X391614Y930676D03*
X823552Y930700D03*
X816519Y931147D03*
X368626Y931346D03*
X1060698Y931619D03*
X720271Y931730D03*
X858601Y934505D03*
X366761Y934550D03*
X853030Y934690D03*
X372858Y935136D03*
X1191151Y936296D03*
X278739Y936439D03*
X1092769Y936975D03*
X471876Y937236D03*
X368964Y937738D03*
X1014719Y938322D03*
X1027319D03*
X1030819Y938422D03*
X491616Y938771D03*
X829617Y939583D03*
X824414Y939655D03*
X1193219Y940703D03*
X494315Y941212D03*
X573103Y941307D03*
X585703D03*
X589203Y941407D03*
X732306Y942682D03*
X370214Y943812D03*
X80593Y946082D03*
X363893Y946863D03*
X370214Y947812D03*
X384856Y947987D03*
X728846Y948331D03*
X392910Y948536D03*
X842856Y949146D03*
X78167Y949261D03*
X824168Y949538D03*
X379928Y949774D03*
X733798Y950186D03*
X851925Y951350D03*
X527879Y952189D03*
X521353Y952266D03*
X76332Y953421D03*
X370101Y953699D03*
X281980Y953926D03*
X1033370Y953994D03*
X1012219Y954222D03*
X1004994Y955372D03*
X591754Y956979D03*
X570603Y957207D03*
X562328Y957307D03*
X503144Y957934D03*
X1027719Y958822D03*
X865830Y961600D03*
X530473Y961728D03*
X586103Y961807D03*
X378875Y961862D03*
X397252Y962861D03*
X370214Y963812D03*
X832423Y964669D03*
X836423D03*
X825670Y964671D03*
X573895Y965319D03*
X602484Y965764D03*
X597556Y965829D03*
X608965Y966414D03*
X1191219Y967757D03*
X378928Y967812D03*
X396671Y968287D03*
X983227Y968565D03*
X393998Y971780D03*
X370214Y971812D03*
X451460Y974695D03*
X458120Y974701D03*
X489163Y977163D03*
X835431Y977775D03*
X828964Y977780D03*
X874066Y977928D03*
X865973Y978187D03*
X506702Y978947D03*
X1069607Y980131D03*
X1066009Y980330D03*
X1006222Y980337D03*
X1014009Y980356D03*
X1018009D03*
X560923Y980443D03*
X1021924Y980456D03*
X556923Y980523D03*
X742407Y988452D03*
X1065823Y988773D03*
X100200Y988800D03*
X95836Y988813D03*
X103836D03*
X107836D03*
X111836D03*
X115836D03*
X119836D03*
X123836D03*
X127836D03*
X131836D03*
X135836D03*
X139836D03*
X143836D03*
X147836D03*
X151836D03*
X159836D03*
X552923D03*
X556923D03*
X560923D03*
X564923D03*
X568923D03*
X572923D03*
X576923D03*
X580923D03*
X584923D03*
X588923D03*
X592923D03*
X596923D03*
X600923D03*
X604923D03*
X608923D03*
X616923D03*
X1014009D03*
X1018009D03*
X1022009D03*
X1026009D03*
X1030009D03*
X1034009D03*
X1038009D03*
X1042009D03*
X1046009D03*
X1050009D03*
X1054009D03*
X1058009D03*
X1062009D03*
X1070009D03*
X1074009D03*
X1009564Y988874D03*
X878976Y994020D03*
X612923Y997860D03*
X542793Y998507D03*
X743062Y1004460D03*
X544719Y1007522D03*
X618878Y1011914D03*
X599113Y1012354D03*
X545094Y1013678D03*
X571857Y1016827D03*
X577704D03*
X548852Y1018307D03*
X545566Y1023731D03*
X551673Y1023900D03*
X567484Y1024003D03*
X599113Y1024954D03*
X571857Y1029427D03*
X577704D03*
X587880Y1034834D03*
X607993Y1036920D03*
X606434Y1041904D03*
X617894Y1043955D03*
X617634Y1049283D03*
X610780Y1051037D03*
X603682Y1053457D03*
X612955Y1062941D03*
X587467Y1105091D03*
Y1117691D03*
Y1130291D03*
Y1142891D03*
Y1155491D03*
Y1168091D03*
X60269Y1198820D03*
X63094Y1207604D03*
X55596Y1210466D03*
X55188Y1205179D03*
X51023Y1201416D03*
X48842Y1211109D03*
X53479Y1216256D03*
X31631Y1198651D03*
X71910Y1625009D03*
X60554Y1615152D03*
X69816Y1592527D03*
X74909Y1593009D03*
X82291Y1633801D03*
X78291D03*
Y1625743D03*
X70291Y1633801D03*
X83689Y1624736D03*
X234976Y1481676D03*
X233313Y1476699D03*
X233180Y1486442D03*
X233166Y1491454D03*
X118533Y1207737D03*
X112048Y1214372D03*
X107803Y1218169D03*
X126433Y1230407D03*
X129250Y1227650D03*
X135448Y1234921D03*
Y1229402D03*
X23603Y1449735D03*
X54843Y1501625D03*
X48089Y1501387D03*
X26231Y1554167D03*
X22381Y1554152D03*
X39095Y1501361D03*
X60303Y1534436D03*
X6951Y1538547D03*
X47621Y1343672D03*
X60277Y1528395D03*
X60227Y1514751D03*
X18879Y1534334D03*
X55862Y1541791D03*
X10367Y1553080D03*
X65478Y1541980D03*
X19735Y1530499D03*
X19745Y1508846D03*
X12599Y1438143D03*
X58443Y1272257D03*
X47074Y1555923D03*
X64747Y1555890D03*
X40951Y1555932D03*
X93496Y1547768D03*
X60747Y1555890D03*
X73381Y94017D03*
X69381D03*
X73110Y101701D03*
X77804Y95879D03*
X27340Y230556D03*
X36185Y230117D03*
X31595Y227824D03*
X36201Y238714D03*
X27966Y238689D03*
X23844Y239299D03*
X21449Y253198D03*
X26325Y262078D03*
X25549Y256394D03*
X21386Y273198D03*
X29116Y281129D03*
X37117Y279991D03*
X25549Y276394D03*
X51550Y90615D03*
X45988Y102323D03*
X37988Y137756D03*
X37284Y285272D03*
X64829Y92874D03*
X55921Y95236D03*
X8335Y280663D03*
X14807Y282181D03*
X15586Y269108D03*
X15499Y288542D03*
X24316Y67527D03*
Y63527D03*
X32350Y63562D03*
Y67562D03*
X35442Y97667D03*
X22439Y106495D03*
Y102495D03*
X23184Y144728D03*
X20709Y175777D03*
X26565Y177448D03*
X32507Y180517D03*
X34520Y213539D03*
X14751Y62381D03*
X7271Y70981D03*
X11011Y79720D03*
X12786Y87903D03*
X18000Y90000D03*
X9364Y107501D03*
X16728Y107910D03*
X14996Y133034D03*
X11442Y132719D03*
X19855Y133000D03*
X19184Y144728D03*
X15184D03*
X19855Y141362D03*
X11999Y141415D03*
X15948Y141267D03*
X12247Y166341D03*
X17313Y166937D03*
X21909Y153263D03*
X22335Y166721D03*
X12709Y175777D03*
X16709Y175943D03*
X19638Y226320D03*
X22599Y228646D03*
X18564Y238589D03*
X9745Y245784D03*
X18206Y244571D03*
X15586Y249108D03*
X13715Y259381D03*
X8970Y254871D03*
X18206Y264571D03*
X19075Y278429D03*
X7036Y268371D03*
X105971Y1025745D03*
X164028Y1041468D03*
X153693Y1051037D03*
X160547Y1049283D03*
X160807Y1043955D03*
X159228Y1065613D03*
X155513Y1065148D03*
X142026Y1012354D03*
X145516Y1024954D03*
Y1012354D03*
X142026Y1024954D03*
X144640Y1039439D03*
X150952Y1040115D03*
X148534Y1046476D03*
X146595Y1053457D03*
X130434Y1144964D03*
X130380Y1155491D03*
X124079Y1009354D03*
X120579D03*
Y1021954D03*
X124079D03*
X120617Y1029427D03*
Y1016827D03*
X133870Y1105091D03*
X133579Y1097469D03*
X130380Y1105091D03*
X133870Y1117691D03*
X130380D03*
X133870Y1130291D03*
X130380D03*
X133870Y1142891D03*
Y1155491D03*
X103124Y1147364D03*
X108971D03*
X111275Y1008262D03*
X114770Y1009354D03*
X111275Y1011762D03*
X114770Y1016827D03*
X110409Y1024094D03*
X114770Y1029427D03*
X108933Y1102091D03*
X112433D03*
X103124D03*
X112433Y1114691D03*
X103124D03*
X108933D03*
X103124Y1122164D03*
X108971D03*
X103124Y1109564D03*
X108971D03*
X108933Y1127291D03*
X112433D03*
X103124D03*
X112433Y1139891D03*
X103124Y1134764D03*
X108971D03*
X103124Y1152491D03*
X108933D03*
X112433D03*
X94586Y1023900D03*
X91765Y1018307D03*
X88007Y1013678D03*
X97609Y1018469D03*
X100594Y1035088D03*
X97247Y1030568D03*
X90450Y1033542D03*
X87632Y1007522D03*
X84679Y1018368D03*
X70059Y1071656D03*
Y1075656D03*
X70302Y1067656D03*
X70059Y1079656D03*
X53197Y1017759D03*
Y1014205D03*
X55699Y1072761D03*
X61588Y1074481D03*
X55049Y1082343D03*
X55004Y1086937D03*
X62109Y1079656D03*
Y1091656D03*
X57218Y1123867D03*
X48704Y1017982D03*
X47314Y1072228D03*
X50366Y1086981D03*
Y1082388D03*
X38200Y1089721D03*
X44365Y1086404D03*
X41172Y1079064D03*
X46166Y1093757D03*
X48585Y1123867D03*
X38216Y1093757D03*
X38823Y1009273D03*
X44999Y1009510D03*
X50541Y1009589D03*
X42470Y1006738D03*
X48683Y1006510D03*
X38197Y1017759D03*
X44197D03*
X41197Y1014205D03*
X47197D03*
X20216Y1009748D03*
X14357Y1009906D03*
X17033Y1006819D03*
X20197Y1017759D03*
Y1014205D03*
X14197Y1017759D03*
Y1014205D03*
X26155Y1009985D03*
X32093Y1009748D03*
X24456Y1006401D03*
X30479Y1006509D03*
X36529Y1006321D03*
X35197Y1014205D03*
X26197Y1017759D03*
X32197D03*
X29197Y1014205D03*
X102761Y1096233D03*
X69263Y1053152D03*
X69373Y1063389D03*
X77734Y1095676D03*
X95711Y143518D03*
X103456Y157370D03*
X98826Y172665D03*
X98763Y178560D03*
X92898Y192490D03*
X98173Y190185D03*
X75194Y141247D03*
X82661Y143740D03*
X80502Y177616D03*
X81083Y172190D03*
X81572Y184619D03*
X76766Y256535D03*
X75438Y265701D03*
X57987Y258880D03*
X48476Y180812D03*
X103841Y228631D03*
X103213Y219379D03*
X98966Y207037D03*
X99032Y212455D03*
X85541Y266114D03*
X103184Y1177691D03*
X103124Y1165091D03*
X138547Y230117D03*
X130328Y238689D03*
X129702Y230556D03*
X124961Y228646D03*
X122000Y226320D03*
X206398Y55513D03*
X205976Y85731D03*
X201669Y103621D03*
X188820Y80140D03*
Y84140D03*
X191568Y72615D03*
X183752Y94017D03*
X186026Y97475D03*
X183022Y103783D03*
X179743Y94017D03*
X175743D03*
X171743D03*
X175472Y101701D03*
X167191Y92874D03*
X158283Y95236D03*
X120926Y238589D03*
X137804Y97667D03*
X148600Y90650D03*
X148350Y95236D03*
Y102323D03*
X140350Y137756D03*
X136882Y213539D03*
X117886Y124663D03*
X112864Y124879D03*
X119230Y138838D03*
X133200Y95111D03*
X124606Y102495D03*
X122867Y125107D03*
X131481Y143762D03*
X129134Y150847D03*
X119582Y102249D03*
X111582D03*
X115582D03*
X118307Y110784D03*
X117607Y133298D03*
X183934Y184619D03*
X182864Y177616D03*
X183445Y172190D03*
X179128Y256535D03*
X177800Y265701D03*
X160349Y258880D03*
X127911Y256394D03*
X123811Y253198D03*
X117948Y249108D03*
X109329Y252371D03*
X133870Y1168091D03*
X134457Y1180654D03*
X205818Y157370D03*
X201125Y178560D03*
X201188Y172665D03*
X195260Y192490D03*
X200535Y190185D03*
X197380Y112083D03*
X193586Y141247D03*
X198073Y143518D03*
X177556Y141247D03*
X185023Y143740D03*
X206203Y228631D03*
X205575Y219379D03*
X201394Y212455D03*
X201328Y207037D03*
X187903Y266114D03*
X433063Y1221428D03*
X429063D03*
X433063Y1225428D03*
Y1229428D03*
Y1233428D03*
Y1237428D03*
X429063Y1225428D03*
Y1229428D03*
Y1233428D03*
Y1237428D03*
X433063Y1241428D03*
Y1245428D03*
X429063Y1241428D03*
Y1245428D03*
X425063Y1221428D03*
X421063D03*
X417063D03*
X413063D03*
X425063Y1225428D03*
Y1229428D03*
Y1233428D03*
Y1237428D03*
X421063Y1225428D03*
Y1229428D03*
Y1233428D03*
Y1237428D03*
X417063Y1225428D03*
Y1229428D03*
Y1233428D03*
Y1237428D03*
X413063Y1225428D03*
Y1229428D03*
Y1233428D03*
Y1237428D03*
X425063Y1241428D03*
Y1245428D03*
X421063Y1241428D03*
Y1245428D03*
X417063Y1241428D03*
Y1245428D03*
X413063Y1241428D03*
Y1245428D03*
X409063Y1221428D03*
X405063D03*
X401063D03*
X397063D03*
X409063Y1225428D03*
Y1229428D03*
Y1233428D03*
Y1237428D03*
X405063Y1225428D03*
Y1229428D03*
Y1233428D03*
Y1237428D03*
X401063Y1225428D03*
Y1229428D03*
Y1233428D03*
Y1237428D03*
X397063Y1225428D03*
Y1229428D03*
Y1233428D03*
X409063Y1241428D03*
Y1245428D03*
X405063Y1241428D03*
Y1245428D03*
X401063Y1241428D03*
X404324Y1271889D03*
Y1275889D03*
X366133Y1162817D03*
Y1170767D03*
X368661Y1182649D03*
X366429Y1185238D03*
X366222Y1180235D03*
X368917Y1195419D03*
X362402Y1201039D03*
X366402Y1200969D03*
X369839Y1218940D03*
X366521Y1208993D03*
X360877Y1157404D03*
X357947Y1159455D03*
X352931Y1167768D03*
X357950D03*
X357057Y1179542D03*
X361792Y1187310D03*
X348432Y1187215D03*
X348125Y1180175D03*
X358368Y1201043D03*
X354398D03*
X350402D03*
X346387Y1199256D03*
X349276Y1217228D03*
X351940Y1219895D03*
X355215Y1223170D03*
X340500Y1147500D03*
X342009Y1176100D03*
X335190Y1173065D03*
X349700Y1148000D03*
X454120Y1269498D03*
X341266Y1171956D03*
X215226Y124879D03*
X213944Y102249D03*
X214389Y94374D03*
Y86012D03*
X223288Y238589D03*
X231496Y150847D03*
X221592Y138838D03*
X220248Y124663D03*
X225229Y125107D03*
X219969Y133298D03*
X220669Y110784D03*
X226968Y102495D03*
X217944Y102249D03*
X221944D03*
X239244Y213539D03*
X233843Y143762D03*
X242712Y137756D03*
X235562Y95111D03*
X240166Y97667D03*
X269553Y92874D03*
X277834Y101701D03*
X278105Y94017D03*
X274105D03*
X250712Y102323D03*
Y95236D03*
X260645D03*
X250962Y90650D03*
X285384Y103783D03*
X288388Y97475D03*
X286114Y94017D03*
X282105D03*
X293930Y72615D03*
X291182Y80140D03*
Y84140D03*
X304031Y103621D03*
X308338Y85731D03*
X308760Y55513D03*
X240925Y238714D03*
X232690Y238689D03*
X232064Y230556D03*
X240909Y230117D03*
X227323Y228646D03*
X224362Y226320D03*
X285226Y177616D03*
X286296Y184619D03*
X281490Y256535D03*
X285807Y172190D03*
X280162Y265701D03*
X262711Y258880D03*
X226173Y253198D03*
X233417D03*
X220310Y249108D03*
X211691Y252371D03*
X295948Y141247D03*
X299742Y112083D03*
X300435Y143518D03*
X308180Y157370D03*
X303550Y172665D03*
X303487Y178560D03*
X287385Y143740D03*
X279918Y141247D03*
X308565Y228631D03*
X303756Y212455D03*
X303690Y207037D03*
X307937Y219379D03*
X290265Y266114D03*
X325650Y238589D03*
X323954Y138838D03*
X322331Y133298D03*
X317588Y124879D03*
X322610Y124663D03*
X327591Y125107D03*
X323031Y110784D03*
X316306Y102249D03*
X320306D03*
X316751Y94374D03*
X324306Y102249D03*
X316751Y86012D03*
X341606Y213539D03*
X333858Y150847D03*
X336205Y143762D03*
X345074Y137756D03*
X329330Y102495D03*
X337924Y95111D03*
X342528Y97667D03*
X353074Y102323D03*
Y95236D03*
X353324Y90650D03*
X363007Y95236D03*
X371915Y92874D03*
X376467Y94017D03*
X387746Y103783D03*
X390750Y97475D03*
X380196Y101701D03*
X380467Y94017D03*
X388476D03*
X384467D03*
X393544Y80140D03*
Y84140D03*
Y76140D03*
X388612Y31168D03*
X406393Y103621D03*
X404686Y45448D03*
X400714D03*
X343287Y238714D03*
X335052Y238689D03*
X334426Y230556D03*
X343271Y230117D03*
X329685Y228646D03*
X326724Y226320D03*
X388658Y184619D03*
X383852Y256535D03*
X382524Y265701D03*
X387588Y177616D03*
X388169Y172190D03*
X365073Y258880D03*
X332635Y256394D03*
X322672Y249108D03*
X328535Y253198D03*
X314053Y252371D03*
X405912Y172665D03*
X405849Y178560D03*
X399984Y192490D03*
X405259Y190185D03*
X395942Y192300D03*
X402104Y112083D03*
X475588Y1043055D03*
X471755Y1038665D03*
X495236Y1129094D03*
X528500Y1106365D03*
X525525Y1110092D03*
X528274Y1160834D03*
X514566Y1000766D03*
X514690Y996766D03*
Y1004766D03*
X514566Y1016266D03*
X514649Y1020266D03*
X514843Y1030766D03*
X519500Y1028377D03*
X498585Y1016266D03*
X506566Y1012266D03*
X496372Y1106298D03*
X493397Y1110092D03*
X502562Y1158200D03*
X493091Y989550D03*
X498435Y1008766D03*
X506566Y996766D03*
Y1008766D03*
X498524Y997590D03*
X487091Y989550D03*
X480711Y999941D03*
X477857Y1004375D03*
X462687Y1160834D03*
X468850D03*
X475018Y992568D03*
X467345Y996480D03*
X459360Y1004680D03*
X464385Y1038534D03*
X477765Y1093432D03*
X462913Y1106365D03*
X459938Y1110092D03*
X459360Y1012325D03*
X443591Y1019766D03*
X451140Y1021793D03*
X447091Y1019766D03*
X450875Y1028416D03*
X443091Y1034266D03*
X452091Y1039880D03*
X443091Y1026266D03*
X429677Y1106955D03*
X427810Y1110092D03*
X437132Y1158266D03*
X409231Y1118801D03*
X403263Y1160834D03*
X378790Y1001083D03*
X380280Y1006071D03*
X383710Y1007283D03*
X382465Y1012430D03*
X464795Y1000647D03*
X488041Y1020440D03*
X522544Y992854D03*
X432838Y1128821D03*
X429348Y1129092D03*
X498727Y1128759D03*
X459290Y1297035D03*
X463290D03*
X451304Y1297045D03*
X444288Y1314391D03*
X434424Y1286274D03*
X430527Y1289198D03*
X440906D03*
X439434Y1322369D03*
X429530Y1325051D03*
X419619Y1539978D03*
X421454Y1544625D03*
X422539Y1534361D03*
X426701Y1541947D03*
X418151Y1552470D03*
X417461Y1569584D03*
X419545Y1317722D03*
X413127Y1318011D03*
X413526Y1288938D03*
X419977Y1288843D03*
X413640Y1292856D03*
X404500Y1452500D03*
X408964Y1531149D03*
X399373Y1555855D03*
X405496Y1561024D03*
X400396D03*
X410596D03*
X401461Y1569560D03*
X397461D03*
X407767Y1292198D03*
X403678Y1295426D03*
X398584Y1313443D03*
X409220Y1315516D03*
X404583Y1316131D03*
X408787Y1321795D03*
X382017Y1559700D03*
X395296Y1561024D03*
X391740Y1550729D03*
Y1555829D03*
Y1545629D03*
Y1540529D03*
X386415Y1321645D03*
X391691Y1326715D03*
X401011Y1307258D03*
X417305Y1359169D03*
X418430Y1394237D03*
X420636Y1383912D03*
X410172Y1402446D03*
X420925Y1390330D03*
X398340Y1399779D03*
X425283Y1364023D03*
X399959Y1352153D03*
X410299Y219379D03*
X406118Y212455D03*
X406052Y207037D03*
X392627Y266114D03*
X473955Y138838D03*
X472611Y124663D03*
X467589Y124879D03*
X477592Y125107D03*
X472332Y133298D03*
X473032Y110784D03*
X466307Y102249D03*
X470307D03*
X474307D03*
X475651Y238589D03*
X491607Y213539D03*
X483859Y150847D03*
X486206Y143762D03*
X479331Y102495D03*
X487925Y95111D03*
X492529Y97667D03*
X521916Y92874D03*
X513008Y95236D03*
X495075Y137756D03*
X503075Y102323D03*
Y95236D03*
X503325Y90650D03*
X530468Y94017D03*
X538477D03*
X534468D03*
X537747Y103783D03*
X540751Y97475D03*
X530197Y101701D03*
X526468Y94017D03*
X556394Y103621D03*
X546293Y72615D03*
X543545Y80140D03*
Y84140D03*
X560701Y85731D03*
X561123Y55513D03*
X493288Y238714D03*
X485053Y238689D03*
X484427Y230556D03*
X493272Y230117D03*
X479686Y228646D03*
X476725Y226320D03*
X538170Y172190D03*
X537589Y177616D03*
X538659Y184619D03*
X533853Y256535D03*
X532525Y265701D03*
X515074Y258880D03*
X478536Y253198D03*
X482636Y256394D03*
X472673Y249108D03*
X464054Y252371D03*
X548311Y141247D03*
X560543Y157370D03*
X552105Y112083D03*
X552798Y143518D03*
X555850Y178560D03*
X555913Y172665D03*
X555260Y190185D03*
X549985Y192490D03*
X532281Y141247D03*
X539748Y143740D03*
X560928Y228631D03*
X560300Y219379D03*
X556119Y212455D03*
X556053Y207037D03*
X542628Y266114D03*
X569951Y124879D03*
X574973Y124663D03*
X568669Y102249D03*
X572669D03*
X569114Y94374D03*
Y86012D03*
X578013Y238589D03*
X586221Y150847D03*
X576317Y138838D03*
X588568Y143762D03*
X579954Y125107D03*
X574694Y133298D03*
X575394Y110784D03*
X581693Y102495D03*
X576669Y102249D03*
X593969Y213539D03*
X597437Y137756D03*
X590287Y95111D03*
X605687Y90650D03*
X594891Y97667D03*
X605437Y102323D03*
Y95236D03*
X615370D03*
X624278Y92874D03*
X632559Y101701D03*
X632830Y94017D03*
X628830D03*
X636830D03*
X640109Y103783D03*
X643113Y97475D03*
X640839Y94017D03*
X645907Y80140D03*
Y84140D03*
X648655Y72615D03*
X658756Y103621D03*
X663063Y85731D03*
X595650Y238714D03*
X587415Y238689D03*
X586789Y230556D03*
X595634Y230117D03*
X582048Y228646D03*
X579087Y226320D03*
X640532Y172190D03*
X641021Y184619D03*
X636215Y256535D03*
X634887Y265701D03*
X639951Y177616D03*
X617436Y258880D03*
X580898Y253198D03*
X584998Y256394D03*
X575035Y249108D03*
X566416Y252371D03*
X569520Y1114691D03*
X566020D03*
X569520Y1139891D03*
X566020D03*
Y1127291D03*
X569520D03*
X566020Y1152491D03*
X569520D03*
X566020Y1165091D03*
X569520D03*
X566020Y1177691D03*
X569520D03*
X650673Y141247D03*
X654467Y112083D03*
X662905Y157370D03*
X658275Y172665D03*
X658212Y178560D03*
X657622Y190185D03*
X655160Y143518D03*
X642110Y143740D03*
X652347Y192490D03*
X634643Y141247D03*
X806148Y1383715D03*
Y1375208D03*
X816648Y1380758D03*
X810148Y1374884D03*
X810204Y1401661D03*
X804654Y1404769D03*
X823220Y1170767D03*
X818879Y1187310D03*
X823309Y1180235D03*
X823516Y1185238D03*
X819489Y1201039D03*
X823489Y1200969D03*
X823608Y1208993D03*
X809632Y1142666D03*
X817964Y1157404D03*
X811507Y1157544D03*
X810018Y1167768D03*
X815037D03*
X814160Y1178240D03*
X814170Y1185205D03*
X805212Y1180175D03*
X805519Y1187215D03*
X815455Y1201043D03*
X811485D03*
X812302Y1223170D03*
X797160Y1146609D03*
X799020Y1175975D03*
X794533Y1195766D03*
X793548Y1397690D03*
X798542Y1188345D03*
X891107Y1314305D03*
X1007850Y1368835D03*
X931159Y1379427D03*
Y1383227D03*
X931137Y1375878D03*
X931199Y1371951D03*
X931159Y1387027D03*
Y1390827D03*
Y1394627D03*
X778685Y1416198D03*
X783694Y1410977D03*
X939559Y1402227D03*
X980166Y1373622D03*
X998600Y1369200D03*
X988784Y1361974D03*
X1019391Y1377061D03*
X985448Y1398271D03*
X998600Y1373400D03*
X948235Y1406262D03*
X944235D03*
X939559Y1398427D03*
X927193Y1361547D03*
X952561Y1383465D03*
X980203Y1377559D03*
X980139Y1381496D03*
Y1393308D03*
X980047Y1397245D03*
X920255Y1383264D03*
X952716Y1387402D03*
X952395Y1395276D03*
X952514Y1391339D03*
X904177Y1359955D03*
X999283Y1377400D03*
X997401Y1381200D03*
X920360Y1387039D03*
X804458Y1193112D03*
X793842Y1143384D03*
X798353Y1172011D03*
X780162Y1412848D03*
X663290Y228631D03*
X658481Y212455D03*
X658415Y207037D03*
X662662Y219379D03*
X644990Y266114D03*
X672313Y124879D03*
X671476Y86012D03*
X680375Y238589D03*
X678679Y138838D03*
X677335Y124663D03*
X682316Y125107D03*
X677056Y133298D03*
X677756Y110784D03*
X684055Y102495D03*
X671476Y94374D03*
X679031Y102249D03*
X692649Y95111D03*
X697253Y97667D03*
X696331Y213539D03*
X688583Y150847D03*
X690930Y143762D03*
X699799Y137756D03*
X707799Y102323D03*
Y95236D03*
X717732D03*
X708049Y90650D03*
X726640Y92874D03*
X734921Y101701D03*
X731192Y94017D03*
X735192D03*
X742471Y103783D03*
X745475Y97475D03*
X739192Y94017D03*
X743201D03*
X751017Y72615D03*
X748269Y80140D03*
Y84140D03*
X761118Y103621D03*
X765425Y85731D03*
X765847Y55513D03*
X698012Y238714D03*
X689777Y238689D03*
X689151Y230556D03*
X697996Y230117D03*
X684410Y228646D03*
X681449Y226320D03*
X742894Y172190D03*
X742313Y177616D03*
X743383Y184619D03*
X738577Y256535D03*
X719798Y258880D03*
X737249Y265701D03*
X690504Y253198D03*
X677397Y249108D03*
X683260Y253198D03*
X668778Y252371D03*
X753035Y141247D03*
X756829Y112083D03*
X757522Y143518D03*
X765267Y157370D03*
X760637Y172665D03*
X760574Y178560D03*
X754709Y192490D03*
X759984Y190185D03*
X753182Y198671D03*
X750667Y192300D03*
X737005Y141247D03*
X744472Y143740D03*
X740640Y1586885D03*
X791610Y1593708D03*
X751140Y1581335D03*
X735878Y1617010D03*
X760398Y1440276D03*
X755035Y1443524D03*
X789647Y1427518D03*
X793459Y1429165D03*
X781110Y1595254D03*
X787447Y1593586D03*
X784046Y1600438D03*
X781545Y1602835D03*
X738775Y1597866D03*
X749786Y1590517D03*
X737892Y1602340D03*
X749704Y1608631D03*
X736067Y1611892D03*
X768361Y1610083D03*
X767310Y1599164D03*
X774658Y1601012D03*
X777033Y1595215D03*
X777059Y1608982D03*
X732825Y1604100D03*
X732268Y1618260D03*
X786787Y1433800D03*
X845306Y1438269D03*
X800607Y1440760D03*
X798601Y1431673D03*
X793744Y1437159D03*
X777749Y1431432D03*
Y1435432D03*
X742655Y1445733D03*
X781124Y1583553D03*
X740530Y1524113D03*
X749439Y1458777D03*
X799314Y1475693D03*
X777260Y1446237D03*
X778428Y1455156D03*
X768812Y1453306D03*
X790361Y1447895D03*
X793288Y1450918D03*
X759802Y1590864D03*
X763542Y1590186D03*
X760843Y212455D03*
X760777Y207037D03*
X765024Y219379D03*
X763653Y224536D03*
X747352Y266114D03*
X781041Y138838D03*
X784678Y125107D03*
X773838Y94374D03*
Y86012D03*
X786417Y102495D03*
X799615Y97667D03*
X782737Y238589D03*
X798693Y213539D03*
X790945Y150847D03*
X793292Y143762D03*
X802161Y137756D03*
X810161Y102323D03*
Y95236D03*
X810411Y90650D03*
X820094Y95236D03*
X829002Y92874D03*
X844833Y103783D03*
X847837Y97475D03*
X837283Y101701D03*
X833554Y94017D03*
X845563D03*
X837554D03*
X841554D03*
X850631Y80140D03*
Y84140D03*
X863480Y103621D03*
X853379Y72615D03*
X867787Y85731D03*
X868209Y55513D03*
X779418Y133298D03*
X774675Y124879D03*
X779697Y124663D03*
X780118Y110784D03*
X773393Y102249D03*
X777393D03*
X781393D03*
X795011Y95111D03*
X800374Y238714D03*
X792139Y238689D03*
X791513Y230556D03*
X800358Y230117D03*
X786772Y228646D03*
X783811Y226320D03*
X840939Y256535D03*
X839611Y265701D03*
X844675Y177616D03*
X845256Y172190D03*
X845745Y184619D03*
X822160Y258880D03*
X785622Y253198D03*
X789722Y256394D03*
X779759Y249108D03*
X771140Y252371D03*
X859191Y112083D03*
X862999Y172665D03*
X862936Y178560D03*
X857071Y192490D03*
X862346Y190185D03*
X853029Y192300D03*
X985921Y805135D03*
X987501Y812573D03*
X987903Y818645D03*
X982300Y821200D03*
X988820Y858903D03*
X964070Y807686D03*
Y813006D03*
X978214Y821224D03*
X964036Y818961D03*
X969309Y839334D03*
X970040Y842903D03*
X967842Y864801D03*
X975925Y854783D03*
X967510Y868971D03*
X978880Y869552D03*
X947735Y824921D03*
X954700Y837700D03*
X948935Y835800D03*
X955712Y833988D03*
X954700Y842700D03*
X947735Y854935D03*
X953091Y857440D03*
X960100Y846665D03*
X950291Y870240D03*
Y866240D03*
X940100Y830700D03*
X931916Y817015D03*
X946700Y849200D03*
X877818Y824214D03*
X872700Y816615D03*
X848224Y823502D03*
X851161Y855205D03*
X837396Y871459D03*
X840234Y875459D03*
X841500Y812161D03*
X836894Y824401D03*
X835215Y847719D03*
X829791Y839020D03*
X837434Y851459D03*
X846336Y855459D03*
X818500Y810135D03*
Y814000D03*
X826925Y823000D03*
X822608Y848526D03*
X829757Y842672D03*
X831654Y864494D03*
X823540Y857956D03*
X822916Y852576D03*
X819134Y863607D03*
X827992Y874107D03*
X833194Y873561D03*
X820432Y800529D03*
X820500Y792000D03*
X826925Y787000D03*
X824342Y792315D03*
X859000Y814000D03*
X824500Y774000D03*
Y800500D03*
X826925Y769000D03*
Y805000D03*
X824500Y782500D03*
X850496Y831469D03*
X851782Y823720D03*
X937200Y841000D03*
X961175Y838525D03*
X957900Y856300D03*
X938729Y874396D03*
X955343Y866850D03*
X990457Y852043D03*
X843574Y859423D03*
X859165Y848728D03*
X839530Y859408D03*
X979203Y829159D03*
X987702D03*
X987703Y837159D03*
X890326Y828548D03*
X895050D03*
X867386Y219379D03*
X863205Y212455D03*
X863139Y207037D03*
X866015Y224536D03*
X849714Y266114D03*
X930754Y1310564D03*
X902353Y1104333D03*
X898278Y1136426D03*
X903959Y1207823D03*
X906784Y1216607D03*
X913784Y1221057D03*
X909077Y1232724D03*
X887862Y1088067D03*
X894004Y1081231D03*
X892856Y1102760D03*
X894713Y1210419D03*
X898878Y1214182D03*
X899286Y1219469D03*
X892532Y1220112D03*
X897169Y1225259D03*
X875321Y1207654D03*
X906309Y1226647D03*
X910633Y1222799D03*
X891367Y941126D03*
X965671Y982191D03*
X947029Y915242D03*
X950567Y927654D03*
X962329Y936229D03*
X957235Y936398D03*
X951863Y936168D03*
X949671Y977921D03*
X957671D03*
Y991564D03*
X953671Y982191D03*
X940628Y915242D03*
X944628Y928101D03*
X932628D03*
X936628D03*
X940497D03*
X946363Y951179D03*
X940716Y951733D03*
X936371Y951484D03*
X935255Y962725D03*
X933810Y972433D03*
X945671Y982191D03*
X920628Y928101D03*
X928628D03*
X916628D03*
X924628D03*
X928227Y951125D03*
X923289Y965780D03*
X918648Y964717D03*
X924956Y994321D03*
X916932Y994405D03*
X909166Y994188D03*
X912690Y994350D03*
X900628Y915242D03*
X912628Y928101D03*
X900983Y940895D03*
X906909Y951494D03*
X892628Y915242D03*
X896553Y918042D03*
X884628D03*
X882763Y933472D03*
X876628Y918042D03*
X969806Y993033D03*
X959545Y918306D03*
X1018209Y55513D03*
X1017787Y85731D03*
X1003379Y72615D03*
X995563Y94017D03*
X997837Y97475D03*
X1013480Y103621D03*
X1000631Y84140D03*
Y80140D03*
X983554Y94017D03*
X987554D03*
X991554D03*
X987283Y101701D03*
X994833Y103783D03*
X952161Y137756D03*
X949359Y198710D03*
X949443Y208206D03*
X950177Y215730D03*
X951040Y223885D03*
X948741Y229468D03*
X979002Y92874D03*
X970094Y95236D03*
X934678Y125107D03*
X943292Y143762D03*
X940945Y150847D03*
X934477Y211491D03*
X946234Y213390D03*
X942179Y215727D03*
X937438Y213817D03*
X938125Y230891D03*
X942805Y223860D03*
X944248Y239844D03*
X949615Y97667D03*
X960411Y90650D03*
X960161Y95236D03*
Y102323D03*
X945011Y95111D03*
X936417Y102495D03*
X931393Y102249D03*
X923393D03*
X927393D03*
X930118Y110784D03*
X929418Y133298D03*
X924675Y124879D03*
X929697Y124663D03*
X931041Y138838D03*
X995745Y184619D03*
X994675Y177616D03*
X990939Y256535D03*
X989611Y265701D03*
X995256Y172190D03*
X951278Y250583D03*
X972160Y258880D03*
X940158Y245707D03*
X936962Y249807D03*
X1048043Y1105091D03*
Y1117691D03*
Y1130291D03*
Y1155491D03*
Y1142891D03*
X1038252Y1009354D03*
X1034752D03*
X1028943D03*
X1034790Y1016827D03*
X1028943D03*
X1034752Y1021954D03*
X1038252D03*
X1034790Y1029427D03*
X1028943D03*
X1044553Y1105091D03*
Y1117691D03*
Y1130291D03*
Y1142891D03*
Y1155491D03*
X1026606Y1152491D03*
X1017297Y1147364D03*
X1023144D03*
X1025448Y1008262D03*
X1011782Y1016591D03*
X1024570Y1024003D03*
X1025448Y1011762D03*
X1014767Y1035088D03*
X1022594Y1035114D03*
X1017297Y1102091D03*
X1026606Y1102591D03*
X1023106Y1102091D03*
X1017297Y1114691D03*
X1023106D03*
X1026606D03*
X1017297Y1122164D03*
X1023144D03*
Y1109564D03*
X1017297D03*
X1023106Y1127291D03*
X1026606D03*
X1017297Y1139891D03*
X1023106D03*
X1026606D03*
X1017297Y1127291D03*
Y1134764D03*
X1023144D03*
X1017297Y1152491D03*
X1023106D03*
X1001805Y1007522D03*
X1002652Y1023731D03*
X1005938Y1018307D03*
X1002180Y1013678D03*
X1008759Y1023900D03*
X999700Y1018400D03*
X988240Y1023968D03*
X1056199Y1012354D03*
Y1024954D03*
X1059689Y1012354D03*
Y1024954D03*
X1057212Y1040356D03*
X1065079Y1036920D03*
X1066933Y1040567D03*
X1067866Y1051037D03*
X1071348Y1050503D03*
X1079178Y1037884D03*
X1079910Y1045264D03*
X1076868Y1047293D03*
X1076577Y1041332D03*
X989513Y1097683D03*
X986645Y1108465D03*
X1044553Y1168091D03*
Y1180691D03*
X1029797Y1220921D03*
X1017297Y1172564D03*
X1023162Y1174445D03*
X1023139Y1184856D03*
X1017297Y1185164D03*
X979001Y1288925D03*
X984817Y1303297D03*
X967936Y1207823D03*
X970761Y1216607D03*
X978169Y1221268D03*
X974985Y1290950D03*
X958690Y1210419D03*
X963263Y1219469D03*
X962855Y1214182D03*
X956509Y1220112D03*
X961146Y1225259D03*
X962255Y1136426D03*
X939298Y1207654D03*
X1049770Y1229402D03*
X1040606Y1230407D03*
X1049720Y1234921D03*
X1043588Y1227300D03*
X1046075Y1350650D03*
X1421964Y1502813D03*
X1420877Y1494706D03*
X1446135Y1530876D03*
X1407255Y1571732D03*
X1423930Y1520364D03*
X1429587Y1527450D03*
X1432913Y1568679D03*
X1443103Y1527201D03*
X1407747Y1549054D03*
X1433405Y1546001D03*
X1441145Y1540415D03*
X1440153Y1563093D03*
X1430374Y1492474D03*
X1408044Y1559306D03*
X990501Y1320756D03*
X1253904Y1519645D03*
X1443769Y1562173D03*
X1049204Y1337377D03*
X1101474Y1637820D03*
X1097474Y1637753D03*
X1105474Y1629450D03*
X1096941Y1627905D03*
X1090093Y1628297D03*
X1085474Y1629028D03*
X1101946Y1614709D03*
X1098904Y1602138D03*
X1088021Y1606949D03*
X1082176Y1600598D03*
X1102904Y1566668D03*
X1090876Y1554183D03*
X1100876D03*
X1099371Y1561153D03*
X1091569Y1561300D03*
X1086904Y1599004D03*
X1107620Y1603602D03*
X1017629Y157370D03*
X1009191Y112083D03*
X1005397Y141247D03*
X1009884Y143518D03*
X1012936Y178560D03*
X1012999Y172665D03*
X1003029Y192300D03*
X1012346Y190185D03*
X1007071Y192490D03*
X989367Y141247D03*
X996834Y143740D03*
X1014587Y802788D03*
X1016320Y828481D03*
X1017800Y867065D03*
X1013151Y756726D03*
X1008342Y761735D03*
X1002751Y757169D03*
X1002834Y777394D03*
X1007027Y792973D03*
X1006053Y787745D03*
X998376Y810970D03*
X1001187Y850084D03*
X1004713Y871389D03*
X1004577Y853679D03*
X1015804Y760454D03*
X1013319Y785929D03*
X1019375Y783056D03*
X1014064Y793660D03*
X1018044Y793592D03*
X992441Y870398D03*
X988231Y878203D03*
X988054Y888283D03*
X982787Y899757D03*
X978201Y897500D03*
X1013486Y750773D03*
X1012703Y837659D03*
X1013918Y851306D03*
X1018071Y798490D03*
X1017955Y812097D03*
X1017664Y779101D03*
X1018015Y751565D03*
X1006054Y810969D03*
X1010699Y803454D03*
X999990Y774671D03*
Y764566D03*
X1007990Y765899D03*
X1012695Y776728D03*
X1018014Y228631D03*
X1017386Y219379D03*
X1013139Y207037D03*
X1013205Y212455D03*
X999714Y266114D03*
X1022604Y290262D03*
X1041496Y300276D03*
X1092354Y290755D03*
X1100354D03*
X1096354D03*
X1198716D03*
X1202716D03*
X1194716D03*
X1301078D03*
X1297078D03*
X1305078D03*
X1259991Y340691D03*
X1257000Y333500D03*
X1283494Y339495D03*
X1294425Y321425D03*
X1289345Y330655D03*
X1294080Y349820D03*
X1299959Y356954D03*
Y351454D03*
X1313103Y339606D03*
X1308012Y348109D03*
X1303158Y371043D03*
X1320903Y370995D03*
X1027037Y124879D03*
X1025755Y102249D03*
X1026200Y94374D03*
Y86012D03*
X1035099Y238589D03*
X1043307Y150847D03*
X1033403Y138838D03*
X1045654Y143762D03*
X1032059Y124663D03*
X1037040Y125107D03*
X1031780Y133298D03*
X1032480Y110784D03*
X1038779Y102495D03*
X1029755Y102249D03*
X1033755D03*
X1051055Y213539D03*
X1054523Y137756D03*
X1047373Y95111D03*
X1051977Y97667D03*
X1062523Y102323D03*
Y95236D03*
X1072456D03*
X1062773Y90650D03*
X1081364Y92874D03*
X1089645Y101701D03*
X1085916Y94017D03*
X1089916D03*
X1097195Y103783D03*
X1100199Y97475D03*
X1093916Y94017D03*
X1097925D03*
X1105741Y72615D03*
X1102993Y80140D03*
Y84140D03*
X1115842Y103621D03*
X1120149Y85731D03*
X1052736Y238714D03*
X1044501Y238689D03*
X1043875Y230556D03*
X1052720Y230117D03*
X1039134Y228646D03*
X1036173Y226320D03*
X1093301Y256535D03*
X1097618Y172190D03*
X1097037Y177616D03*
X1098107Y184619D03*
X1091973Y265701D03*
X1074522Y258880D03*
X1032121Y249108D03*
X1037984Y253198D03*
X1042084Y256394D03*
X1023502Y252371D03*
X1111553Y112083D03*
X1112246Y143518D03*
X1119991Y157370D03*
X1115298Y178560D03*
X1115361Y172665D03*
X1114708Y190185D03*
X1107759Y141247D03*
X1099196Y143740D03*
X1109903Y171523D03*
X1109433Y192490D03*
X1091729Y141247D03*
X1120376Y228631D03*
X1115501Y207037D03*
X1115567Y212455D03*
X1119748Y219379D03*
X1102076Y266114D03*
X1135765Y138838D03*
X1134421Y124663D03*
X1129399Y124879D03*
X1139402Y125107D03*
X1134142Y133298D03*
X1128117Y102249D03*
X1132117D03*
X1134842Y110784D03*
X1141141Y102495D03*
X1128562Y94374D03*
X1136117Y102249D03*
X1128562Y86012D03*
X1149735Y95111D03*
X1154339Y97667D03*
X1137461Y238589D03*
X1164885Y102323D03*
Y95236D03*
X1170447Y90615D03*
X1153417Y213539D03*
X1145669Y150847D03*
X1148016Y143762D03*
X1156885Y137756D03*
X1174818Y95236D03*
X1183726Y92874D03*
X1188278Y94017D03*
X1192007Y101701D03*
X1192278Y94017D03*
X1200287D03*
X1196278D03*
X1205355Y80140D03*
Y84140D03*
X1199557Y103783D03*
X1202561Y97475D03*
X1218204Y103621D03*
X1222511Y85731D03*
X1208103Y72615D03*
X1222933Y55513D03*
X1155098Y238714D03*
X1146863Y238689D03*
X1146237Y230556D03*
X1155082Y230117D03*
X1141496Y228646D03*
X1138535Y226320D03*
X1199980Y172190D03*
X1199399Y177616D03*
X1200469Y184619D03*
X1194335Y265701D03*
X1195663Y256535D03*
X1177035Y257919D03*
X1147590Y253198D03*
X1134483Y249108D03*
X1140346Y253198D03*
X1125864Y252371D03*
X1217070Y190185D03*
X1207753Y192300D03*
X1211795Y192490D03*
X1210268Y198671D03*
X1213915Y112083D03*
X1210121Y141247D03*
X1214608Y143518D03*
X1222353Y157370D03*
X1212265Y171523D03*
X1217723Y172665D03*
X1217660Y178560D03*
X1194091Y141247D03*
X1201558Y143740D03*
X1436736Y1222194D03*
Y1226194D03*
X1432736Y1222194D03*
X1428736D03*
X1424736D03*
X1420736D03*
X1432736Y1226194D03*
Y1230194D03*
Y1234194D03*
X1428736Y1226194D03*
Y1230194D03*
Y1234194D03*
Y1238194D03*
X1424736Y1226194D03*
Y1230194D03*
Y1234194D03*
Y1238194D03*
X1420736Y1226194D03*
Y1230194D03*
Y1234194D03*
Y1238194D03*
X1428736Y1242194D03*
Y1246194D03*
X1424736Y1242194D03*
Y1246194D03*
X1420736Y1242194D03*
Y1246194D03*
X1416736Y1222194D03*
X1412736D03*
X1408736D03*
X1416736Y1226194D03*
Y1230194D03*
Y1234194D03*
Y1238194D03*
X1412736Y1226194D03*
Y1230194D03*
Y1234194D03*
Y1238194D03*
X1408736Y1226194D03*
Y1230194D03*
Y1234194D03*
Y1238194D03*
Y1246194D03*
Y1242194D03*
X1416736D03*
Y1246194D03*
X1412736Y1242194D03*
Y1246194D03*
X1385052Y1303139D03*
X1389052D03*
X1347237Y1237428D03*
Y1233428D03*
Y1229428D03*
X1343237D03*
Y1233428D03*
Y1237428D03*
X1339237D03*
Y1233428D03*
Y1229428D03*
Y1225428D03*
X1347237Y1245428D03*
Y1241428D03*
X1343237D03*
Y1245428D03*
X1339237D03*
Y1241428D03*
X1335237D03*
X1323237Y1245428D03*
Y1241428D03*
X1327237Y1237428D03*
Y1233428D03*
Y1229428D03*
Y1225428D03*
X1331237Y1237428D03*
Y1233428D03*
Y1229428D03*
Y1225428D03*
X1335237Y1237428D03*
Y1233428D03*
Y1229428D03*
Y1225428D03*
X1323237Y1237428D03*
Y1233428D03*
Y1229428D03*
Y1225428D03*
X1327237Y1245428D03*
Y1241428D03*
X1331237Y1245428D03*
Y1241428D03*
X1335237Y1245428D03*
X1311237Y1233428D03*
Y1229428D03*
Y1225428D03*
X1315237Y1237428D03*
Y1233428D03*
Y1229428D03*
Y1225428D03*
X1319237Y1237428D03*
Y1233428D03*
Y1229428D03*
Y1225428D03*
X1315237Y1241428D03*
X1319237D03*
X1318287Y1295381D03*
X1271921Y1134729D03*
X1275794D03*
X1275050Y1157404D03*
X1280306Y1170767D03*
X1275965Y1187232D03*
X1280602Y1185238D03*
X1280395Y1180235D03*
X1272541Y1201043D03*
X1276575Y1201039D03*
X1280575Y1200969D03*
X1280694Y1208993D03*
X1267921Y1134729D03*
X1266718Y1142666D03*
X1268593Y1157544D03*
X1267104Y1167768D03*
X1272123D03*
X1271246Y1178240D03*
X1271256Y1185205D03*
X1262605Y1187215D03*
X1262298Y1180175D03*
X1268571Y1201043D03*
X1263449Y1217228D03*
X1266113Y1219895D03*
X1269388Y1223170D03*
X1256218Y1175987D03*
X1255628Y1188345D03*
X1303900Y1288000D03*
X1260800Y1191096D03*
X1255439Y1172008D03*
X1222738Y228631D03*
X1217863Y207037D03*
X1217929Y212455D03*
X1222110Y219379D03*
X1204438Y266114D03*
X1230924Y94374D03*
X1238479Y102249D03*
X1230924Y86012D03*
X1252097Y95111D03*
X1256701Y97667D03*
X1238127Y138838D03*
X1231761Y124879D03*
X1236783Y124663D03*
X1236504Y133298D03*
X1237204Y110784D03*
X1234479Y102249D03*
X1230479D03*
X1267247Y102323D03*
Y95236D03*
X1267497Y90650D03*
X1239823Y238589D03*
X1248031Y150847D03*
X1250378Y143762D03*
X1241764Y125107D03*
X1243503Y102495D03*
X1277180Y95236D03*
X1286088Y92874D03*
X1255779Y213539D03*
X1259247Y137756D03*
X1301919Y103783D03*
X1294640Y94017D03*
X1304923Y97475D03*
X1294369Y101701D03*
X1290640Y94017D03*
X1298640D03*
X1302649D03*
X1302785Y31168D03*
X1320566Y103621D03*
X1307717Y80140D03*
Y76140D03*
Y84140D03*
X1318859Y45448D03*
X1314887D03*
X1324120Y22742D03*
X1257460Y238714D03*
X1249225Y238689D03*
X1248599Y230556D03*
X1257444Y230117D03*
X1243858Y228646D03*
X1240897Y226320D03*
X1301761Y177616D03*
X1302342Y172190D03*
X1302831Y184619D03*
X1298025Y256535D03*
X1296697Y265701D03*
X1279246Y258880D03*
X1242708Y253198D03*
X1246808Y256394D03*
X1236845Y249108D03*
X1228226Y252371D03*
X1320085Y172665D03*
X1320022Y178560D03*
X1319432Y190185D03*
X1314157Y192490D03*
X1310115Y192300D03*
X1316277Y112083D03*
X1314627Y171523D03*
X1305740Y877534D03*
X1309753Y877589D03*
X1293500Y875800D03*
Y871800D03*
Y879800D03*
Y883800D03*
X1293272Y887800D03*
X1296866Y894993D03*
X1285302Y877283D03*
Y885783D03*
X1343725Y1128738D03*
X1402215Y1020440D03*
X1435669Y1005366D03*
X1440869Y1010256D03*
X1442674Y1106365D03*
X1439699Y1110092D03*
X1442448Y1160834D03*
X1420740Y996766D03*
Y1008766D03*
Y1012266D03*
X1416736Y1158200D03*
X1410546Y1106298D03*
X1407571Y1110092D03*
X1394885Y999941D03*
X1392031Y1004375D03*
X1389762Y1043055D03*
X1392086Y1092743D03*
X1389192Y992568D03*
X1385929Y1038665D03*
X1377087Y1106365D03*
X1374112Y1110092D03*
X1376861Y1160834D03*
X1383024D03*
X1381519Y996280D03*
X1373534Y1012325D03*
Y1004680D03*
X1378938Y1000586D03*
X1378559Y1038534D03*
X1357765Y1019766D03*
X1361265D03*
X1365049Y1028416D03*
X1365314Y1021793D03*
X1357265Y1026266D03*
Y1034266D03*
X1366265Y1039880D03*
X1351149Y1158200D03*
X1344241Y1106298D03*
X1341984Y1110092D03*
X1333974Y1033483D03*
X1317437Y1160834D03*
X1416618Y992307D03*
X1412759Y1016266D03*
X1412609Y1008766D03*
X1412698Y997590D03*
X1383162Y991829D03*
X1407265Y989465D03*
X1413177Y1128894D03*
X1347300Y1128332D03*
X1409425Y1129238D03*
X1402064Y965913D03*
X1413322Y958908D03*
X1413575Y915186D03*
X1404760D03*
X1396869Y958707D03*
X1394891Y914783D03*
X1373948Y940103D03*
X1369948Y943603D03*
X1361948D03*
X1358500Y930500D03*
X1354500D03*
X1362500D03*
X1357948Y938842D03*
X1365948Y939475D03*
X1353948Y943603D03*
X1362500Y925500D03*
X1358500D03*
X1354500D03*
X1341820Y947407D03*
X1345948Y943603D03*
X1346500Y930500D03*
X1342500D03*
X1350500D03*
X1338500D03*
X1342500Y925500D03*
X1350500D03*
X1346500D03*
X1332500Y961500D03*
X1326500Y943500D03*
X1336000D03*
X1323000Y934075D03*
X1329199Y933825D03*
X1333132Y933781D03*
X1333000Y937925D03*
X1315441Y960000D03*
X1313152Y936605D03*
X1312575Y943974D03*
X1300500Y960000D03*
X1297558Y970216D03*
X1378500Y930500D03*
X1374500D03*
X1370500D03*
X1366500D03*
X1382775Y930281D03*
X1382500Y925500D03*
X1378500D03*
X1370500D03*
X1366500D03*
X1349848Y936755D03*
X1325100Y228631D03*
X1324472Y219379D03*
X1320225Y207037D03*
X1320291Y212455D03*
X1306800Y266114D03*
X1651443Y981515D03*
X1547644Y903060D03*
X1548080Y910757D03*
X1525022Y909558D03*
X1515179Y921094D03*
X1521085D03*
X1521500Y947500D03*
X1522209Y937846D03*
X1527267Y932647D03*
X1521085Y957340D03*
X1529128Y952978D03*
X1504208Y909740D03*
X1505337Y921240D03*
X1509274Y921226D03*
X1501812Y938397D03*
X1509500Y944138D03*
Y937000D03*
Y950500D03*
X1512161Y957541D03*
X1504495Y796844D03*
X1510527Y833500D03*
X1500638Y873839D03*
X1502158Y899479D03*
X1496806Y817000D03*
X1496845Y809000D03*
X1487050Y809413D03*
X1496621Y829000D03*
X1495240Y825000D03*
X1491425Y842425D03*
X1698716Y550065D03*
X1689920Y539315D03*
X1692379Y622912D03*
X1693000Y626912D03*
X1618538Y618288D03*
X1627224Y643252D03*
X1619950Y678519D03*
X1616260Y678462D03*
X1595300Y558800D03*
X1595364Y562800D03*
X1594760Y568000D03*
X1577862Y554121D03*
X1565323Y577716D03*
X1579260Y604567D03*
X1574760Y606929D03*
X1579760Y595500D03*
X1580354Y616317D03*
X1580418Y610072D03*
X1575001Y612592D03*
X1574720Y618400D03*
X1571888Y649380D03*
X1574880Y645891D03*
X1572141Y662981D03*
X1568872Y686971D03*
X1575192Y707592D03*
X1556588Y545528D03*
X1562385Y610400D03*
X1564670Y650122D03*
X1565132Y668153D03*
X1495500Y750500D03*
X1496629Y765000D03*
X1496763Y777000D03*
X1493301Y776911D03*
X1496814Y773000D03*
X1472000Y727500D03*
X1476716Y748398D03*
X1479665Y754555D03*
X1474713Y685247D03*
X1455419Y578986D03*
X1454944Y596729D03*
X1450944Y605443D03*
X1461474Y655807D03*
X1455761Y683448D03*
X1468372Y673812D03*
X1460111Y683536D03*
X1451428Y673252D03*
X1455291Y759656D03*
X1455159Y763714D03*
X1438944Y605637D03*
X1448994Y596782D03*
X1443775Y596089D03*
X1438944Y597232D03*
X1434944Y605443D03*
X1437790Y625013D03*
X1435952Y642184D03*
X1446323Y673183D03*
X1437738Y686992D03*
X1437533Y699280D03*
Y704398D03*
X1438930Y716363D03*
X1446860Y730735D03*
X1446538Y719548D03*
X1437738Y730992D03*
X1446717Y735536D03*
X1437533Y748398D03*
X1449993Y578405D03*
X1435668Y582747D03*
X1435119Y590801D03*
X1434944Y597130D03*
X1430944Y605443D03*
X1425452Y633473D03*
X1430175Y627852D03*
X1420452Y628078D03*
X1433529Y660564D03*
X1433464Y692658D03*
X1433053Y701839D03*
X1434000Y712958D03*
X1431522Y708633D03*
X1430289Y734961D03*
X1429000Y729000D03*
X1434000Y751958D03*
X1415623Y492268D03*
X1406910Y491982D03*
X1416413Y495649D03*
X1406910Y495982D03*
X1415064Y500202D03*
X1405619Y541135D03*
X1405992Y534909D03*
X1401438Y534211D03*
X1405708Y552726D03*
X1405685Y546553D03*
X1407754Y616905D03*
X1407566Y622285D03*
X1411622Y610548D03*
X1401383Y611071D03*
X1407835Y627713D03*
X1413432Y633716D03*
X1407952Y633724D03*
X1418439Y633736D03*
X1405229Y652028D03*
X1405000Y660000D03*
X1404500Y675000D03*
X1410000Y681000D03*
Y685000D03*
Y697000D03*
Y701000D03*
X1405000Y703000D03*
Y707000D03*
X1410000Y713000D03*
Y709000D03*
Y717000D03*
Y725000D03*
Y729000D03*
X1404500Y722000D03*
X1404249Y735858D03*
X1410000Y741000D03*
X1398946Y621311D03*
Y625311D03*
Y629311D03*
X1397000Y652000D03*
Y656000D03*
Y660000D03*
X1397079Y527726D03*
X1395605Y556217D03*
X1397079Y544726D03*
Y548726D03*
X1390741Y565000D03*
Y569000D03*
Y561000D03*
X1391087Y581317D03*
X1496756Y785000D03*
X1499633Y787794D03*
X1497000Y781000D03*
X1431000Y591000D03*
X1761360Y281982D03*
X1755419Y281716D03*
X1700223Y292141D03*
X1703609Y287320D03*
X1653057Y281716D03*
X1658998Y281982D03*
X1596691Y287397D03*
X1574775Y333549D03*
X1563877Y329863D03*
Y343363D03*
Y334363D03*
X1578587Y341787D03*
X1578420Y338309D03*
X1563877Y352363D03*
Y325363D03*
Y316363D03*
X1556636Y281982D03*
X1550695Y281716D03*
X1550931Y305158D03*
X1554403Y316363D03*
X1553534Y327337D03*
X1553910Y331798D03*
X1553597Y336601D03*
X1553862Y344867D03*
X1545583Y316363D03*
X1539140Y320863D03*
X1545636Y325363D03*
X1542797Y329863D03*
X1545846Y334363D03*
X1544951Y343363D03*
X1538133Y354553D03*
X1551175Y347283D03*
X1545434Y352363D03*
X1503884Y295549D03*
X1501684Y336561D03*
X1516838Y347422D03*
X1515909Y354601D03*
X1497446Y295877D03*
X1486360Y322700D03*
X1500659Y330024D03*
X1495605Y322700D03*
X1486360Y345200D03*
X1500386Y344642D03*
X1486913Y340327D03*
X1487152Y331272D03*
X1495689Y332534D03*
X1495521Y340700D03*
X1486360Y349700D03*
X1495521Y349681D03*
X1495925Y358700D03*
X1499839Y354001D03*
X1486890Y368576D03*
X1494286Y372699D03*
X1477549Y327200D03*
Y322700D03*
Y345200D03*
Y340700D03*
Y331700D03*
Y358700D03*
Y349700D03*
Y354200D03*
X1468309Y408861D03*
X1475236Y412482D03*
X1466231Y423671D03*
X1469538Y416795D03*
X1466653Y428582D03*
X1454274Y281982D03*
X1459060Y320861D03*
Y325361D03*
Y329861D03*
Y338861D03*
Y343361D03*
Y334361D03*
Y347861D03*
Y352361D03*
X1458214Y406231D03*
X1464536Y433114D03*
X1448822Y345324D03*
X1448500Y340575D03*
X1439712Y336673D03*
X1449060Y356861D03*
X1441180Y354909D03*
X1434697Y347125D03*
X1439719Y350387D03*
X1434608Y362584D03*
X1438768Y371655D03*
X1442633Y371502D03*
X1440523Y382747D03*
X1435424Y430361D03*
X1436930Y461818D03*
X1448333Y281716D03*
X1448948Y326448D03*
X1449060Y320861D03*
X1438829Y329861D03*
X1437064Y320861D03*
X1440420Y346833D03*
X1434166Y325361D03*
X1434164Y339232D03*
X1434038Y334114D03*
X1435818Y352361D03*
X1417903Y439919D03*
X1434997Y442603D03*
X1427117Y443071D03*
X1432414Y459371D03*
X1418903Y469905D03*
X1431484Y470045D03*
X1391623Y409900D03*
X1403085Y460565D03*
X1402921Y322403D03*
X1404690Y362209D03*
X1416912Y386903D03*
X1408854Y381207D03*
X1416470Y381397D03*
X1414369Y398056D03*
X1408254Y398041D03*
X1407844Y411033D03*
X1415610Y417644D03*
X1415674Y421278D03*
X1417856Y448419D03*
X1414903Y469905D03*
X1410903Y461919D03*
X1418903Y461419D03*
X1395726Y320529D03*
X1395568Y325529D03*
X1395726Y330529D03*
X1395736Y335529D03*
X1395726Y340529D03*
Y345529D03*
Y360529D03*
Y350529D03*
Y355529D03*
X1391896Y365529D03*
X1399884Y367165D03*
X1387847Y366710D03*
X1384265Y320871D03*
Y325371D03*
X1383551Y337808D03*
X1384265Y329871D03*
X1383634Y342766D03*
X1384265Y334371D03*
X1375073Y356871D03*
X1336646Y22627D03*
X1336551Y26534D03*
X1344092Y141247D03*
X1351559Y143740D03*
X1348419Y265222D03*
X1360122Y141247D03*
X1364609Y143518D03*
X1336623Y30483D03*
X1544736Y305156D03*
X1487318Y318200D03*
X1411269Y481467D03*
X1415823Y482165D03*
X1410903Y470419D03*
X1480702Y368516D03*
X1611327Y735973D03*
X1501500Y321000D03*
X1486860Y327200D03*
X1501000Y317500D03*
X1615913Y692245D03*
X1578000Y678776D03*
X1624000Y760900D03*
X1611873Y795127D03*
X1609500Y776100D03*
X1630327Y774627D03*
X1620100Y738300D03*
X1628027Y801427D03*
X1606709Y819165D03*
X1611027Y722427D03*
X1629927Y787327D03*
X1611627Y780327D03*
X1612573Y761427D03*
X1635283Y728117D03*
X1613117Y828117D03*
X1620500Y723200D03*
X1616683Y744517D03*
X1628200Y711417D03*
X1620600Y705900D03*
X1612800D03*
X1473489Y861354D03*
X1628343Y747288D03*
X1606190Y803774D03*
X1500353Y859855D03*
X1471006Y744818D03*
X1470801Y739280D03*
X1504938Y859711D03*
X1644325Y942120D03*
X1552000Y969850D03*
X1647402Y881460D03*
X1518517Y878898D03*
X1635176Y886761D03*
X1648387Y945554D03*
X1528500Y947612D03*
X1551163Y952888D03*
X1516500Y947500D03*
X1644552Y871353D03*
X1647470Y952125D03*
X1647763Y919268D03*
X1635000Y919263D03*
X1644718Y909263D03*
X1518452Y873780D03*
X1548504Y915689D03*
X1512712Y867418D03*
X1548629Y927836D03*
X1548616Y931602D03*
X1388480Y102249D03*
X1381762Y124879D03*
X1386784Y124663D03*
X1387205Y110784D03*
X1384480Y102249D03*
X1380480D03*
X1389824Y238589D03*
X1398032Y150847D03*
X1388128Y138838D03*
X1400379Y143762D03*
X1391765Y125107D03*
X1386505Y133298D03*
X1393504Y102495D03*
X1405780Y213539D03*
X1409248Y137756D03*
X1417248Y102323D03*
X1402098Y95111D03*
X1417248Y95236D03*
X1417498Y90650D03*
X1406702Y97667D03*
X1436089Y92874D03*
X1444370Y101701D03*
X1440641Y94017D03*
X1427181Y95236D03*
X1448641Y94017D03*
X1444641D03*
X1451920Y103783D03*
X1454924Y97475D03*
X1452650Y94017D03*
X1460466Y72615D03*
X1457718Y80140D03*
Y84140D03*
X1470567Y103621D03*
X1475431Y94351D03*
X1474874Y85731D03*
X1475296Y55513D03*
X1407461Y238714D03*
X1399226Y238689D03*
X1398600Y230556D03*
X1407445Y230117D03*
X1393859Y228646D03*
X1390898Y226320D03*
X1452343Y172190D03*
X1452832Y184619D03*
X1451762Y177616D03*
X1448026Y256535D03*
X1446698Y265701D03*
X1429247Y258880D03*
X1392709Y253198D03*
X1396809Y256394D03*
X1386846Y249108D03*
X1378227Y252371D03*
X1474716Y157370D03*
X1470023Y178560D03*
X1470086Y172665D03*
X1469433Y190185D03*
X1466278Y112083D03*
X1462484Y141247D03*
X1466971Y143518D03*
X1453921Y143740D03*
X1464628Y171523D03*
X1464158Y192490D03*
X1446454Y141247D03*
X1435000Y765500D03*
X1427000Y766500D03*
Y770500D03*
X1435000D03*
X1446000D03*
X1427000Y774500D03*
Y781834D03*
Y790500D03*
Y794500D03*
X1443000D03*
Y798500D03*
X1427000Y802500D03*
X1435000D03*
Y809500D03*
X1427000Y810500D03*
Y814500D03*
X1435000D03*
X1427000Y818500D03*
X1435000D03*
Y825500D03*
X1427000Y826500D03*
Y830500D03*
X1434975D03*
X1427000Y834500D03*
X1435000D03*
X1427000Y838500D03*
X1443000D03*
X1427000Y842500D03*
X1443000D03*
X1427000Y846500D03*
X1435000D03*
X1435212Y854042D03*
X1448726Y864400D03*
X1438188Y867633D03*
X1435082Y869475D03*
X1461113Y871389D03*
X1488138Y872839D03*
X1435043Y874694D03*
X1488138Y878339D03*
X1437703Y880067D03*
X1482195Y885807D03*
X1460472Y885985D03*
X1452641Y888033D03*
X1457218Y888764D03*
X1445367Y891888D03*
X1441223Y891957D03*
X1449072Y892581D03*
X1473387Y897425D03*
X1435288Y897500D03*
X1451286Y898549D03*
X1439103Y898564D03*
X1447261Y898571D03*
X1443231Y899006D03*
X1459420Y899226D03*
X1462500Y905295D03*
X1429059Y908579D03*
X1487075Y920925D03*
X1487240Y924453D03*
X1446022Y927000D03*
X1484824Y927324D03*
X1451005Y931848D03*
X1435516Y936000D03*
X1461888Y936055D03*
X1444453Y938806D03*
X1483324Y939324D03*
X1474349Y949394D03*
X1448137Y949440D03*
X1462819Y949996D03*
X1487240Y952012D03*
X1480414Y952214D03*
X1439031Y957683D03*
X1458202Y960288D03*
X1497075Y961000D03*
X1482591Y961909D03*
X1460655Y964253D03*
X1501400Y966000D03*
X1482237Y966028D03*
X1457937Y966712D03*
X1514000Y968739D03*
X1479196Y970000D03*
X1489500Y972500D03*
X1495500D03*
X1510740Y973740D03*
X1485226Y973886D03*
X1468500Y974181D03*
X1492560Y974654D03*
X1480414Y975064D03*
X1498973Y975443D03*
X1457352Y976277D03*
X1519863Y977637D03*
X1466076Y979746D03*
X1530594Y979952D03*
X1523966Y980281D03*
X1433996Y981437D03*
X1467096Y988813D03*
X1471296D03*
X1475096D03*
X1479096D03*
X1483096D03*
X1487096D03*
X1491096D03*
X1495096D03*
X1499096D03*
X1503096D03*
X1507096D03*
X1511096D03*
X1515096D03*
X1519096D03*
X1523096D03*
X1531096D03*
X1459519Y989432D03*
X1475101Y228631D03*
X1470292Y212455D03*
X1470226Y207037D03*
X1474473Y219379D03*
X1456801Y266114D03*
X1487266Y1002046D03*
X1468869Y1018469D03*
X1471096Y997860D03*
X1479096D03*
X1487096D03*
X1495096D03*
X1483096D03*
X1491096D03*
X1499096D03*
X1511096D03*
X1503096D03*
X1507096D03*
X1531961Y1050849D03*
X1531993Y1056453D03*
X1527096Y997860D03*
X1523096D03*
X1519096D03*
X1531096D03*
X1515096D03*
X1531546Y1062769D03*
X1531947Y1046212D03*
X1532067Y1041832D03*
X1483287Y86012D03*
X1490490Y138838D03*
X1489146Y124663D03*
X1494127Y125107D03*
X1488867Y133298D03*
X1489567Y110784D03*
X1495866Y102495D03*
X1482842Y102249D03*
X1486842D03*
X1483287Y94374D03*
X1490842Y102249D03*
X1484124Y124879D03*
X1504460Y95111D03*
X1509064Y97667D03*
X1492186Y238589D03*
X1508142Y213539D03*
X1500394Y150847D03*
X1502741Y143762D03*
X1511610Y137756D03*
X1519610Y102323D03*
Y95236D03*
X1529543D03*
X1519860Y90650D03*
X1538451Y92874D03*
X1546732Y101701D03*
X1543003Y94017D03*
X1547003D03*
X1554282Y103783D03*
X1557286Y97475D03*
X1551003Y94017D03*
X1555012D03*
X1562828Y72615D03*
X1560080Y80140D03*
Y84140D03*
X1572929Y103621D03*
X1577793Y94351D03*
X1577236Y85731D03*
X1509823Y238714D03*
X1501588Y238689D03*
X1500962Y230556D03*
X1509807Y230117D03*
X1496221Y228646D03*
X1493260Y226320D03*
X1554705Y172190D03*
X1554124Y177616D03*
X1555194Y184619D03*
X1550388Y256535D03*
X1531609Y258880D03*
X1549060Y265701D03*
X1489208Y249108D03*
X1495071Y253198D03*
X1499171Y256394D03*
X1480589Y252371D03*
X1480193Y1177691D03*
X1474384D03*
X1483693D03*
X1482535Y1024254D03*
Y1011762D03*
X1513286Y1024954D03*
X1516776D03*
X1495339Y1021954D03*
X1491839D03*
X1486030D03*
X1513286Y1012354D03*
X1516776D03*
X1483693Y1114691D03*
X1480193D03*
X1474384D03*
X1483693Y1127291D03*
X1480193D03*
X1474384D03*
X1483693Y1139891D03*
X1480193D03*
X1474384D03*
X1483693Y1152491D03*
X1480193D03*
X1474384D03*
X1483693Y1165091D03*
X1480193D03*
X1474384D03*
X1501640Y1105091D03*
X1505130D03*
X1483693Y1102091D03*
X1480193D03*
X1474384D03*
X1521939Y1040818D03*
X1522099Y1035521D03*
X1517855Y1053457D03*
X1503572Y1034538D03*
X1568640Y112083D03*
X1569333Y143518D03*
X1577078Y157370D03*
X1566990Y171523D03*
X1572385Y178560D03*
X1572448Y172665D03*
X1571795Y190185D03*
X1566520Y192490D03*
X1548816Y141247D03*
X1564846D03*
X1556283Y143740D03*
X1762041Y1631511D03*
X1768422Y1632245D03*
X1773820Y1631238D03*
X1765040Y1599511D03*
X1759947Y1599029D03*
X1750685Y1621654D03*
X1766313Y1580198D03*
X1761072Y1590719D03*
X1758390Y1577905D03*
X1778104Y1470289D03*
X1803885Y1435046D03*
X1778227Y1438099D03*
X1812202Y1432624D03*
X1806428Y1444543D03*
X1809342Y1476733D03*
X1786091Y1443715D03*
X1772188Y1428369D03*
X1787745Y1437765D03*
X1783178Y1437550D03*
X1795374Y1444543D03*
X1577463Y228631D03*
X1572654Y212455D03*
X1572588Y207037D03*
X1576835Y219379D03*
X1559163Y266114D03*
X1585649Y94374D03*
X1593204Y102249D03*
X1585649Y86012D03*
X1594548Y238589D03*
X1592852Y138838D03*
X1596489Y125107D03*
X1591229Y133298D03*
X1591508Y124663D03*
X1586486Y124879D03*
X1591929Y110784D03*
X1589204Y102249D03*
X1585204D03*
X1610504Y213539D03*
X1602756Y150847D03*
X1605103Y143762D03*
X1598228Y102495D03*
X1606822Y95111D03*
X1611426Y97667D03*
X1613972Y137756D03*
X1621972Y102323D03*
Y95236D03*
X1622222Y90650D03*
X1631905Y95236D03*
X1640813Y92874D03*
X1656644Y103783D03*
X1659648Y97475D03*
X1649094Y101701D03*
X1645365Y94017D03*
X1653365D03*
X1657374D03*
X1649365D03*
X1675291Y103621D03*
X1679598Y85731D03*
X1665190Y72615D03*
X1662442Y80140D03*
Y84140D03*
X1680155Y94351D03*
X1680020Y55513D03*
X1612185Y238714D03*
X1603950Y238689D03*
X1603324Y230556D03*
X1612169Y230117D03*
X1598583Y228646D03*
X1595622Y226320D03*
X1656486Y177616D03*
X1657067Y172190D03*
X1657556Y184619D03*
X1652750Y256535D03*
X1651422Y265701D03*
X1633971Y258880D03*
X1597433Y253198D03*
X1604677D03*
X1591570Y249108D03*
X1582951Y252371D03*
X1695142Y303839D03*
X1686339Y314890D03*
X1658200Y315039D03*
X1681273Y316731D03*
X1691117Y321649D03*
X1674226Y324139D03*
X1677810Y324466D03*
X1683523Y324518D03*
X1686408Y332584D03*
X1640030Y335550D03*
X1635987Y335616D03*
X1687164Y336324D03*
X1668979Y339559D03*
X1678072Y342319D03*
X1712226Y344028D03*
X1687424Y347937D03*
X1692676Y348015D03*
X1594466Y350984D03*
X1598223Y351003D03*
X1626147Y351033D03*
X1602138Y351047D03*
X1654771Y352088D03*
X1670323Y353534D03*
X1673723Y353881D03*
X1691182Y357016D03*
X1744524Y370010D03*
X1765497Y370899D03*
X1723964Y370935D03*
X1756497Y370976D03*
X1748497Y371060D03*
X1760497Y371070D03*
X1752497Y371076D03*
X1640197Y374690D03*
X1721746Y377173D03*
X1725746D03*
X1729751D03*
X1741746D03*
X1670260Y377912D03*
X1755433Y379028D03*
X1750135Y379088D03*
X1744524Y379429D03*
X1645685Y381500D03*
X1655335D03*
X1666959Y382047D03*
X1744180Y383966D03*
X1663780Y384410D03*
X1725746Y385123D03*
X1737746D03*
X1747561Y385161D03*
X1720571Y385644D03*
X1680518Y385912D03*
X1670260Y386500D03*
X1715228Y387966D03*
X1680518Y389912D03*
X1669260Y391496D03*
X1718851Y391533D03*
X1741420Y391569D03*
X1728433Y392183D03*
X1733027Y392228D03*
X1599527Y392718D03*
X1663618Y393858D03*
X1680518Y393924D03*
X1748252Y395248D03*
X1728478Y396866D03*
X1733071D03*
X1670348Y397912D03*
X1665260Y398583D03*
X1766204Y398949D03*
X1718318Y399918D03*
X1599527Y400718D03*
X1739847Y401066D03*
X1680518Y401924D03*
X1763704Y401949D03*
X1636271Y403307D03*
X1663760D03*
X1667260Y403500D03*
X1599527Y404718D03*
X1680518Y405924D03*
X1725154Y406060D03*
X1599527Y408718D03*
X1669260Y409000D03*
X1739847Y409016D03*
X1735811Y409032D03*
X1680518Y409924D03*
X1636271Y410394D03*
X1663760D03*
X1721423Y412106D03*
X1599527Y412718D03*
X1677933Y418838D03*
X1628636Y422088D03*
X1626260Y427017D03*
X1625952Y431029D03*
X1650044Y435158D03*
X1649789Y440489D03*
X1635170Y442856D03*
X1650087Y444841D03*
X1673717Y445787D03*
X1669767Y445908D03*
X1635185Y446595D03*
X1718710Y447486D03*
X1786170Y448931D03*
X1625938Y449873D03*
X1649773Y449961D03*
X1632439Y452265D03*
X1724580Y454214D03*
X1747359Y454309D03*
X1716310Y454334D03*
X1786713Y455039D03*
X1621596Y456386D03*
X1747359Y458309D03*
X1716310Y458334D03*
X1637665Y458406D03*
X1633225Y458455D03*
X1786693Y459170D03*
X1724627Y459330D03*
X1738824Y461034D03*
X1747359Y462309D03*
X1655776Y465492D03*
X1756553Y466409D03*
X1765097D03*
X1768586Y467560D03*
X1776561D03*
X1756894Y472020D03*
X1737703Y472189D03*
X1663576Y472579D03*
X1764906Y474382D03*
X1783014Y474513D03*
X1645607Y475262D03*
X1777061Y475560D03*
X1756954Y477318D03*
X1765006Y478382D03*
X1768575Y479560D03*
X1655776Y479665D03*
X1663576D03*
X1764912Y482382D03*
X1645607Y482666D03*
X1655776Y486752D03*
X1663576D03*
X1765083Y487382D03*
X1679440Y157370D03*
X1671002Y112083D03*
X1667208Y141247D03*
X1671695Y143518D03*
X1669352Y171523D03*
X1674810Y172665D03*
X1674747Y178560D03*
X1674157Y190185D03*
X1668882Y192490D03*
X1667318Y198828D03*
X1664840Y192300D03*
X1658645Y143740D03*
X1651178Y141247D03*
X1679825Y228631D03*
X1679197Y219379D03*
X1674950Y207037D03*
X1675016Y212455D03*
X1661525Y266114D03*
X1709941Y228747D03*
X1782382Y55513D03*
X1781832Y60513D03*
X1781960Y85731D03*
X1782517Y94351D03*
X1777653Y103621D03*
X1759006Y103783D03*
X1764804Y84140D03*
Y80140D03*
X1767552Y72615D03*
X1759736Y94017D03*
X1762010Y97475D03*
X1755727Y94017D03*
X1751456Y101701D03*
X1747727Y94017D03*
X1751727D03*
X1743175Y92874D03*
X1734267Y95236D03*
X1697984Y226320D03*
X1705686Y230556D03*
X1700945Y228646D03*
X1696910Y238589D03*
X1706312Y238689D03*
X1713788Y97667D03*
X1724584Y90650D03*
X1724334Y95236D03*
Y102323D03*
X1716334Y137756D03*
X1712866Y213539D03*
X1714531Y230117D03*
X1714547Y238714D03*
X1709184Y95111D03*
X1700590Y102495D03*
X1698851Y125107D03*
X1707465Y143762D03*
X1705118Y150847D03*
X1688011Y86012D03*
Y94374D03*
X1695566Y102249D03*
X1687566D03*
X1691566D03*
X1694291Y110784D03*
X1693591Y133298D03*
X1693870Y124663D03*
X1688848Y124879D03*
X1695214Y138838D03*
X1759918Y184619D03*
X1755112Y256535D03*
X1753784Y265701D03*
X1758848Y177616D03*
X1759429Y172190D03*
X1736333Y258880D03*
X1699795Y253198D03*
X1703895Y256394D03*
X1693932Y249108D03*
X1685313Y252371D03*
X1739917Y1146937D03*
X1732137Y1157404D03*
X1729207Y1159455D03*
X1737393Y1162817D03*
Y1170767D03*
X1729210Y1167768D03*
X1728333Y1178240D03*
X1733052Y1187310D03*
X1737689Y1185238D03*
X1737482Y1180235D03*
X1733660Y1193019D03*
X1729660D03*
X1737660D03*
X1733662Y1201039D03*
X1729628Y1201043D03*
X1737662Y1200969D03*
X1740785Y1219254D03*
X1737781Y1208993D03*
X1726475Y1223170D03*
X1723805Y1142666D03*
X1724191Y1167768D03*
X1713239Y1176038D03*
X1728343Y1185205D03*
X1719692Y1187215D03*
X1719385Y1180175D03*
X1725660Y1193019D03*
X1721660D03*
X1725658Y1201043D03*
X1720536Y1217228D03*
X1723200Y1219895D03*
X1711333Y1146609D03*
X1720960Y1148000D03*
X1708889Y1189221D03*
X1712715Y1188500D03*
X1712526Y1171950D03*
X1807844Y1027248D03*
Y1023694D03*
X1816756Y1089145D03*
X1816235Y1083970D03*
X1810346Y1082250D03*
X1824706Y1093150D03*
X1816756Y1101145D03*
X1810310Y1104819D03*
X1812130Y1205349D03*
X1814741Y1217093D03*
X1811482Y1226423D03*
X1824949Y1077145D03*
X1824706Y1085145D03*
Y1100185D03*
Y1106145D03*
X1834665Y1213239D03*
X1792844Y1027248D03*
X1798844D03*
X1795844Y1023694D03*
X1801844D03*
X1793470Y1018762D03*
X1799646Y1018999D03*
X1805188Y1019078D03*
X1803351Y1027471D03*
X1811468Y1021084D03*
X1759569Y1021944D03*
X1801961Y1081717D03*
X1795819Y1088553D03*
X1800813Y1103246D03*
X1806835Y1214668D03*
X1800489Y1220598D03*
X1807243Y1219955D03*
X1802670Y1210905D03*
X1805126Y1225745D03*
X1779404Y826570D03*
X1791041Y818795D03*
X1789844Y1023694D03*
X1774844Y1027248D03*
X1780844D03*
X1786844D03*
X1783844Y1023694D03*
X1774844D03*
X1774863Y1019237D03*
X1780802Y1019474D03*
X1786740Y1019237D03*
X1810349Y1031264D03*
X1779033Y1023432D03*
X1783278Y1208140D03*
X1774476Y995049D03*
X1773810Y990821D03*
X1758881Y995633D03*
X1768844Y1023694D03*
X1769004Y1019395D03*
X1812538Y1026859D03*
X1751854Y991297D03*
X1749314Y987904D03*
X1745824Y987058D03*
X1748677Y993986D03*
X1753860Y997271D03*
X1750879Y541940D03*
X1791088Y77296D03*
X1804758Y294429D03*
X1805196Y300952D03*
X1809095Y435101D03*
X1803700Y440101D03*
X1803530Y431112D03*
X1809358Y442114D03*
X1803335Y452718D03*
X1809346Y452601D03*
X1797907Y452987D03*
X1809338Y447121D03*
X1804933Y461607D03*
X1796933D03*
X1800933D03*
X1790664Y71908D03*
X1790712Y81713D03*
X1830915Y1109146D03*
X1828272Y1095968D03*
X1802363Y989660D03*
X1805463Y969260D03*
X1801963Y969160D03*
X1789363D03*
X1786863Y985060D03*
X1779143Y995203D03*
X1802000Y892447D03*
X1780016Y874400D03*
X1746884Y884649D03*
X1746600Y935100D03*
X1750915Y902055D03*
X1749267Y918413D03*
X1789537Y930498D03*
X1746897Y879199D03*
X1741800Y917900D03*
X1793474Y930374D03*
X1775904Y924546D03*
X1751200Y931100D03*
X1778047Y916120D03*
X1797365Y930761D03*
X1819900Y906900D03*
X1808014Y984832D03*
X1777172Y172665D03*
X1777109Y178560D03*
X1773364Y112083D03*
X1771714Y171523D03*
X1771244Y192490D03*
X1776519Y190185D03*
X1767202Y192300D03*
X1782187Y228631D03*
X1763887Y266114D03*
X1781559Y219379D03*
X1777312Y207037D03*
X1777378Y212455D03*
G54D59*
X133957Y227824D03*
X236319D03*
X338681D03*
X410927Y228631D03*
X488682Y227824D03*
X591044D03*
X693406D03*
X771383Y1616917D03*
X778045Y1622545D03*
X782289Y1620109D03*
X773822Y1627418D03*
X778358D03*
X762671Y1619367D03*
X752150Y1627871D03*
X741705Y1622015D03*
X748924Y1617709D03*
X747590Y1627871D03*
X783620Y1460108D03*
X790296Y1463459D03*
X787038Y1460533D03*
X793723Y1468071D03*
X766433Y1583713D03*
X795768Y227824D03*
X1048130D03*
X1150492D03*
X1252854D03*
X1416802Y936845D03*
X1417284Y911009D03*
X1402855Y227824D03*
X1505217D03*
X1607579D03*
X1822594Y1211054D03*
Y1215324D03*
G54D52*
X607776Y1073326D03*
X615256D03*
X622736D03*
X615256Y1077066D03*
X622736D03*
X611516Y1080807D03*
X618996D03*
X626476D03*
X611516Y1084547D03*
X618996D03*
X626476D03*
X600295Y1088287D03*
X604035D03*
X607776Y1092027D03*
X615256D03*
X622736D03*
X632086Y1093897D03*
X639567D03*
X647047D03*
X654527D03*
X662008D03*
X669488D03*
X676968D03*
X607776Y1095767D03*
X615256D03*
X622736D03*
X632086Y1097637D03*
X639567D03*
X647047D03*
X654527D03*
X662008D03*
X669488D03*
X676968D03*
X684449D03*
X600295Y1099507D03*
X604035D03*
X611516D03*
X618996D03*
X611516Y1103247D03*
X618996D03*
X626476D03*
X600295Y1106988D03*
X604035D03*
X600295Y1114468D03*
X186220Y1217322D03*
Y1224803D03*
Y1228543D03*
X178740D03*
X171259Y1224803D03*
X182480Y1236023D03*
Y1232283D03*
X174999D03*
X171259Y1228543D03*
X178740Y1224803D03*
X174999Y1236023D03*
X182480Y1108858D03*
X281594Y1136909D03*
X285334D03*
Y1118208D03*
X281594D03*
X285334Y1114468D03*
X281594D03*
X274114Y1118208D03*
Y1121948D03*
X270373Y1118208D03*
X266633Y1121948D03*
X270373D03*
X277854Y1118208D03*
Y1121948D03*
X270373Y1114468D03*
X274114D03*
X277854D03*
Y1129429D03*
X274114Y1125688D03*
X270373Y1136909D03*
X266633Y1133169D03*
X270373D03*
Y1125688D03*
Y1129429D03*
X266633Y1125688D03*
X277854Y1136909D03*
Y1133169D03*
Y1125688D03*
X266633Y1129429D03*
X274114D03*
Y1136909D03*
X255413Y1121948D03*
X251673D03*
X247933D03*
X262893D03*
X259153D03*
X262893Y1118208D03*
X259153Y1114468D03*
X262893D03*
X255413Y1118208D03*
Y1114468D03*
X247933D03*
X259153Y1118208D03*
X247933D03*
X251673D03*
X247933Y1133169D03*
X251673D03*
X255413D03*
X247933Y1125688D03*
X251673D03*
X255413D03*
X259153Y1133169D03*
X262893D03*
X259153Y1125688D03*
X262893D03*
X247933Y1129429D03*
X259153D03*
X262893D03*
X255413D03*
X251673D03*
X236712Y1121948D03*
X240452D03*
X244192D03*
X240452Y1114468D03*
X244192D03*
X236712Y1118208D03*
X244192D03*
X236712Y1114468D03*
X240452Y1118208D03*
X236712Y1133464D03*
X240452Y1133169D03*
X236712Y1125688D03*
X240452D03*
X244192Y1133169D03*
Y1125688D03*
Y1129429D03*
X240452D03*
X236712D03*
X218011Y1114468D03*
X225492Y1133169D03*
Y1125688D03*
X218011D03*
X221751D03*
Y1133169D03*
X218011D03*
X229330Y1132677D03*
X229232Y1125688D03*
Y1129429D03*
X218011D03*
X221751D03*
X225492D03*
X223622Y1090157D03*
X219881Y1086417D03*
Y1082677D03*
Y1090157D03*
X223622Y1078936D03*
Y1093897D03*
X219881D03*
Y1097637D03*
X223621Y1101376D03*
Y1105117D03*
X219881Y1101377D03*
Y1105117D03*
X223622Y1097637D03*
X225492Y1118208D03*
Y1121948D03*
X218011Y1118208D03*
X221751D03*
X218011Y1121948D03*
X221751D03*
X229232D03*
Y1118208D03*
Y1114468D03*
X225492D03*
X221752D03*
X219880Y1071455D03*
X223622Y1075196D03*
X199311Y1129429D03*
X206791D03*
X204921Y1097637D03*
X216141Y1101376D03*
X208661D03*
X212401Y1097637D03*
X204921Y1101377D03*
X208661Y1097637D03*
X201181D03*
X204921Y1105117D03*
X212401Y1101377D03*
Y1105117D03*
X216141Y1097637D03*
X208661Y1105117D03*
X216141D03*
X201181Y1101376D03*
Y1105117D03*
X199311Y1118208D03*
Y1121948D03*
X206791Y1118208D03*
X203051D03*
Y1121948D03*
X206791D03*
X210531Y1118208D03*
X214271Y1114468D03*
X210531Y1121948D03*
X214271Y1118208D03*
Y1121948D03*
X203051Y1114468D03*
X199311D03*
X206791D03*
X210531D03*
X199311Y1125688D03*
X203051D03*
X206791D03*
Y1133169D03*
X203051D03*
X199311D03*
X210531D03*
X214271Y1125688D03*
X210531D03*
X214271Y1133169D03*
Y1129429D03*
X210531D03*
X203051D03*
X201181Y1075196D03*
X208661D03*
X216141D03*
X204920Y1071455D03*
X212400D03*
X208661Y1078936D03*
X204921Y1090157D03*
X201181Y1093897D03*
X208661D03*
X216141Y1090157D03*
X212401Y1086417D03*
Y1082677D03*
X216141Y1078936D03*
X212401Y1090157D03*
X216141Y1093897D03*
X208661Y1090157D03*
X201181D03*
X204921Y1086417D03*
Y1082677D03*
X201181Y1078936D03*
X212401Y1093897D03*
X204921D03*
X195570Y1121948D03*
X188090Y1114468D03*
X191830D03*
X195570D03*
X191830Y1125688D03*
X188090D03*
X184350D03*
X188090Y1129429D03*
X184350D03*
X188090Y1133169D03*
X184350D03*
X188090Y1136909D03*
Y1140649D03*
X184350D03*
X195570Y1133169D03*
Y1129429D03*
Y1125688D03*
Y1136909D03*
X191830D03*
X184350D03*
X191830Y1129429D03*
Y1133169D03*
X188090Y1144389D03*
Y1151870D03*
X184350Y1144389D03*
X188090Y1155610D03*
X184350Y1151870D03*
X188090Y1148129D03*
X197440Y1093897D03*
X193700Y1090157D03*
X189960Y1086417D03*
Y1082677D03*
X193700Y1078936D03*
X186220D03*
X189960Y1090157D03*
X186220D03*
X193700Y1093897D03*
X197440Y1086417D03*
Y1082677D03*
Y1090157D03*
X189960Y1093897D03*
X193700Y1105117D03*
X189960Y1097637D03*
X186220Y1105117D03*
X197440Y1097637D03*
X189960Y1101377D03*
X186220Y1097637D03*
X189960Y1105117D03*
X186220Y1093897D03*
X193700Y1097637D03*
X197440Y1101377D03*
Y1105117D03*
X193700Y1101376D03*
X186220D03*
X191830Y1118208D03*
X188090D03*
X184350D03*
X191830Y1121948D03*
X188090D03*
X184350D03*
X195570Y1118208D03*
X197439Y1071455D03*
X189959D03*
X186220Y1075196D03*
X193700D03*
X180610Y1136909D03*
Y1148129D03*
X173129Y1144389D03*
X169389D03*
X173129Y1148129D03*
Y1155610D03*
Y1151870D03*
X180610Y1155610D03*
Y1151870D03*
Y1144389D03*
X176870Y1151870D03*
Y1148129D03*
Y1144389D03*
X169389Y1151870D03*
Y1148129D03*
X174999Y1093897D03*
X182480D03*
X178740Y1090157D03*
Y1078936D03*
X174999Y1086417D03*
Y1082677D03*
Y1090157D03*
X178740Y1093897D03*
X171259Y1090157D03*
X182480Y1086417D03*
Y1082677D03*
Y1090157D03*
X169389Y1084547D03*
X178740Y1097637D03*
X174999Y1101377D03*
X169389Y1106988D03*
X171259Y1093897D03*
Y1097637D03*
X174999Y1105117D03*
X182480Y1101377D03*
Y1105117D03*
X178740Y1108858D03*
X182480Y1097637D03*
X174999D03*
X178740Y1101376D03*
Y1105117D03*
X169389Y1103247D03*
Y1121948D03*
X176870Y1118208D03*
Y1121948D03*
X169389Y1110728D03*
X180610Y1118208D03*
Y1121948D03*
X173129Y1133169D03*
X169389D03*
X176870Y1140649D03*
Y1125688D03*
Y1129429D03*
Y1133169D03*
Y1136909D03*
X173129Y1140649D03*
X169389D03*
X173129Y1129428D03*
X169389D03*
X180610Y1140649D03*
Y1125688D03*
Y1129429D03*
Y1133169D03*
X174998Y1071455D03*
X182479D03*
X178740Y1075196D03*
X171259D03*
X150689Y1151870D03*
X158169Y1155610D03*
X154429D03*
X150689D03*
X165649Y1148129D03*
Y1144389D03*
Y1155610D03*
X154429Y1092027D03*
X161909Y1077066D03*
X165649Y1080807D03*
Y1088287D03*
X161909D03*
Y1092027D03*
X165649D03*
X158169D03*
X150689D03*
X165649Y1077066D03*
X161909Y1084547D03*
X158169Y1077066D03*
X154429Y1084547D03*
X161909Y1080807D03*
X154429D03*
X158169Y1099507D03*
X150689D03*
X158169Y1103247D03*
X150689D03*
X158169Y1106988D03*
X161909Y1095767D03*
X165649Y1099507D03*
Y1103247D03*
Y1106988D03*
X161909D03*
X154429D03*
X150689D03*
X154429Y1095767D03*
X165649D03*
X161909Y1103247D03*
X158169Y1095767D03*
X154429Y1103247D03*
X150689Y1095767D03*
X161909Y1099507D03*
X154429D03*
X158169Y1110728D03*
Y1114468D03*
X154429D03*
X150689D03*
X158169Y1118208D03*
Y1121948D03*
X154429D03*
X150689D03*
X165649Y1114468D03*
X161909D03*
Y1118208D03*
Y1121948D03*
X165649Y1110728D03*
X161909D03*
X154429D03*
Y1118208D03*
X150689Y1110728D03*
Y1118208D03*
X158169Y1133169D03*
X161909Y1140649D03*
X158169Y1125688D03*
Y1129429D03*
X154429D03*
X150689D03*
Y1136909D03*
X154429Y1140649D03*
X150689D03*
X165649D03*
X161909Y1125688D03*
X165649Y1129429D03*
X161909D03*
X165649Y1136909D03*
X158169Y1140649D03*
X154429Y1125688D03*
X150689D03*
X161909Y1144389D03*
Y1148129D03*
Y1151870D03*
Y1155610D03*
X150689Y1144389D03*
X158169Y1151869D03*
X154429D03*
X150689Y1148129D03*
X154429Y1073326D03*
X161909D03*
X165649D03*
X158169D03*
X150689D03*
X150688Y1077066D03*
X154429D03*
X158169Y1080807D03*
X150689D03*
X158169Y1084547D03*
X150689D03*
X158169Y1088287D03*
X154429D03*
X150689D03*
X143208Y1095767D03*
X146948D03*
Y1103247D03*
Y1099507D03*
X143208D03*
X146948Y1106988D03*
X143208D03*
Y1110728D03*
Y1118208D03*
X146948Y1110728D03*
Y1118208D03*
Y1114468D03*
Y1121948D03*
X143208Y1114468D03*
Y1121948D03*
X146948Y1133169D03*
Y1140649D03*
X139468Y1136909D03*
X143208Y1125688D03*
Y1133169D03*
Y1140649D03*
X146948Y1125688D03*
Y1129429D03*
X143208D03*
Y1144389D03*
Y1151870D03*
X146948Y1144389D03*
Y1151870D03*
Y1148129D03*
X143208D03*
Y1084547D03*
Y1092027D03*
X146948Y1077066D03*
Y1080806D03*
Y1084547D03*
Y1092027D03*
Y1088287D03*
X143208D03*
Y1103247D03*
X165649Y1084547D03*
X197440Y1108858D03*
X204921D03*
X201181D03*
X186220D03*
X189960D03*
X193700D03*
X223622D03*
X219881D03*
X208661D03*
X165649Y1170570D03*
X150688D03*
X154429D03*
X180610D03*
X173129D03*
X176870D03*
X188090Y1178051D03*
X191830Y1174310D03*
Y1178051D03*
X188090Y1174310D03*
Y1170570D03*
X191830D03*
X184350D03*
X180610Y1181791D03*
X173129Y1178051D03*
Y1181791D03*
X180610Y1178051D03*
X176870D03*
Y1181791D03*
X165649Y1178050D03*
X150688Y1178051D03*
X204921Y1221062D03*
X208661D03*
X219881D03*
X320866D03*
X313385Y1209842D03*
X320866Y1213582D03*
X324606Y1221062D03*
X313385Y1217322D03*
X320866Y1236023D03*
Y1224803D03*
Y1232283D03*
X313385D03*
X317125Y1228543D03*
Y1224803D03*
X313385Y1236023D03*
X324606Y1232283D03*
Y1236023D03*
Y1224803D03*
X317125Y1236023D03*
X313385Y1224803D03*
X324606Y1228543D03*
X317125Y1232283D03*
X313385Y1228543D03*
X320866D03*
X328347Y1239762D03*
Y1247243D03*
X320866Y1250984D03*
Y1243503D03*
X313385Y1250984D03*
X317125Y1247243D03*
Y1243503D03*
X324606D03*
Y1250984D03*
Y1239763D03*
X313385Y1247243D03*
X320866D03*
X317125Y1250984D03*
X320866Y1239763D03*
X313385Y1243503D03*
X324606Y1247243D03*
X317125Y1258465D03*
X313385Y1254724D03*
X317125D03*
X322736Y1155610D03*
X318996D03*
X315255Y1151869D03*
X318996D03*
Y1148129D03*
X326476D03*
Y1155610D03*
X322736Y1151870D03*
X315255Y1148129D03*
X326476Y1151870D03*
X315255Y1155610D03*
X322736Y1170570D03*
Y1166830D03*
X315255Y1159350D03*
X318996D03*
X315255Y1166830D03*
X318996Y1170570D03*
Y1166830D03*
X326476D03*
Y1170570D03*
X322736Y1159350D03*
X326476D03*
X315255Y1170570D03*
Y1181791D03*
Y1189271D03*
X318996D03*
Y1185531D03*
Y1181791D03*
Y1178051D03*
X315255Y1174310D03*
X318996D03*
X326476Y1178051D03*
Y1185531D03*
X322736Y1178051D03*
Y1185531D03*
Y1174310D03*
Y1181791D03*
Y1189271D03*
X326476Y1174310D03*
X315255Y1178051D03*
X326476Y1181791D03*
X315255Y1185531D03*
X326476Y1189271D03*
X328347Y1198621D03*
Y1206102D03*
X322736Y1193011D03*
X320866Y1202362D03*
X318996Y1193011D03*
X317125Y1206102D03*
X313385D03*
X317125Y1198621D03*
X326416Y1193011D03*
X324606Y1202362D03*
X320866Y1198621D03*
X313385Y1202362D03*
X324606Y1198621D03*
X317125Y1202362D03*
X320866Y1206102D03*
X324606D03*
X315255Y1193011D03*
X328347Y1221062D03*
Y1213582D03*
X320866Y1217322D03*
Y1209842D03*
X313385Y1221062D03*
X317125D03*
X313385Y1213582D03*
X317125D03*
X324606Y1209842D03*
Y1217322D03*
X317125D03*
Y1209842D03*
X324606Y1213582D03*
X322736Y1148129D03*
X305905Y1224803D03*
X302165Y1236023D03*
X309645Y1247243D03*
Y1243503D03*
X317125Y1239763D03*
X294685Y1247243D03*
X298425Y1250984D03*
X302165Y1247243D03*
X294685Y1243503D03*
X302165D03*
X305905Y1239763D03*
X302165D03*
X313385D03*
X305905Y1250984D03*
X294685D03*
X298425Y1247243D03*
X309645Y1250984D03*
X298425Y1243503D03*
X305905D03*
Y1247243D03*
X302165Y1250984D03*
X309645Y1258465D03*
X294685D03*
X302165D03*
X298425Y1254724D03*
X305905D03*
X294685D03*
X309645D03*
X302165D03*
X311515Y1193011D03*
X305905Y1206102D03*
X302165Y1213582D03*
X294685Y1209842D03*
X298425D03*
X302165Y1206102D03*
X298425Y1221062D03*
X302165D03*
X298425Y1217322D03*
X309645D03*
Y1209842D03*
X305905Y1213582D03*
X309645D03*
Y1206102D03*
Y1221062D03*
X298425Y1213582D03*
X305905Y1209842D03*
Y1217322D03*
X302165Y1209842D03*
X298425Y1206102D03*
X302165Y1217322D03*
X298425Y1236023D03*
Y1232283D03*
X294685Y1228543D03*
X302165D03*
X294685Y1224803D03*
Y1221062D03*
X302165Y1224803D03*
X305905Y1221062D03*
X298425Y1239763D03*
X305905Y1232283D03*
X309645Y1228543D03*
Y1224803D03*
X305905Y1236023D03*
X309645Y1239763D03*
X302165Y1232283D03*
X309645D03*
X294685Y1236023D03*
X298425Y1224803D03*
X294685Y1232283D03*
X298425Y1228543D03*
X309645Y1236023D03*
X305905Y1228543D03*
X296555Y1151869D03*
X304035Y1155610D03*
Y1148129D03*
X300295Y1155610D03*
Y1151869D03*
Y1148129D03*
X307775D03*
X311515Y1151869D03*
X307775Y1155610D03*
X304035Y1151869D03*
X307775D03*
X296555Y1155610D03*
X311515Y1148129D03*
Y1155610D03*
X307775Y1159350D03*
X296555D03*
X300295D03*
X296555Y1166830D03*
X304035Y1170570D03*
X300295D03*
Y1166830D03*
X311515D03*
X307775Y1170570D03*
X311515Y1159350D03*
X304035Y1166830D03*
Y1159350D03*
X307775Y1166830D03*
X296555Y1170570D03*
X311515D03*
X300295Y1181791D03*
Y1178051D03*
Y1174310D03*
X296555D03*
X304035Y1185531D03*
Y1178051D03*
X311515Y1174310D03*
X307775Y1178051D03*
X311515Y1181791D03*
X307775Y1185531D03*
X311515Y1189271D03*
X304035Y1174310D03*
Y1181791D03*
Y1189271D03*
X307775Y1174310D03*
Y1181791D03*
Y1189271D03*
X311515Y1178051D03*
Y1185531D03*
X294685Y1194881D03*
Y1202362D03*
X304035Y1193011D03*
X302165Y1198621D03*
X298425Y1202362D03*
Y1194881D03*
X307775Y1193011D03*
X305905Y1198621D03*
X309645Y1202362D03*
X298425Y1198621D03*
X305905Y1202362D03*
X302165D03*
X279724Y1239763D03*
X287204Y1247243D03*
Y1243503D03*
X279724Y1247243D03*
X287204Y1239763D03*
X294685D03*
X290944Y1250984D03*
Y1247243D03*
Y1243503D03*
X287204Y1258465D03*
X290944Y1254724D03*
X294685Y1217322D03*
Y1213582D03*
Y1206102D03*
X281594Y1211712D03*
X285334Y1207972D03*
Y1215452D03*
Y1211712D03*
X281594Y1215452D03*
X279724Y1224803D03*
X283464Y1239763D03*
X290944Y1232283D03*
Y1236023D03*
Y1239763D03*
X283464Y1232283D03*
X287204Y1228543D03*
X283464Y1236023D03*
X287204Y1224803D03*
X290944D03*
Y1228543D03*
X281594Y1148129D03*
Y1155610D03*
Y1151869D03*
X285334D03*
X289074D03*
Y1155610D03*
X292814Y1151869D03*
X285334Y1155610D03*
Y1148129D03*
X289074D03*
X292815D03*
Y1155610D03*
X281594Y1159350D03*
X289074Y1166830D03*
Y1170570D03*
Y1159350D03*
X281594Y1170570D03*
Y1166830D03*
X292814Y1159350D03*
Y1166830D03*
X285334Y1170570D03*
Y1166830D03*
Y1159350D03*
X292815Y1170570D03*
X292814Y1181791D03*
X285334Y1185531D03*
X289074Y1174310D03*
Y1178051D03*
Y1185531D03*
X281594Y1189271D03*
Y1185531D03*
X285334Y1181791D03*
X281594Y1178051D03*
Y1174310D03*
X292814D03*
X285334D03*
Y1189271D03*
X281594Y1181791D03*
X285334Y1178051D03*
X289074Y1181791D03*
X281594Y1196751D03*
Y1204232D03*
Y1193011D03*
X285334D03*
X294685Y1198621D03*
X285334Y1196751D03*
Y1200491D03*
Y1204232D03*
X281594Y1200491D03*
X272244Y1224803D03*
X268503Y1236023D03*
Y1232283D03*
X272244Y1228543D03*
X264763Y1224803D03*
X268503Y1239763D03*
X275984D03*
X272244Y1243503D03*
Y1247243D03*
X264763Y1239763D03*
X272244D03*
X279724Y1243503D03*
X266633Y1181791D03*
X270373Y1189271D03*
X277854Y1178051D03*
Y1189271D03*
Y1185531D03*
X270373Y1174310D03*
X266633D03*
X277854D03*
X270373Y1181791D03*
X274114Y1189271D03*
Y1185531D03*
Y1178051D03*
Y1204232D03*
Y1196751D03*
X270393Y1196732D03*
X270373Y1204232D03*
X266633D03*
X270373Y1200491D03*
X266633Y1196751D03*
X270373Y1193011D03*
X277854D03*
X266633D03*
Y1200491D03*
X274114D03*
Y1193011D03*
X277854Y1200491D03*
Y1196751D03*
Y1204232D03*
X274114Y1207972D03*
X270373Y1211712D03*
X266633Y1207972D03*
Y1211712D03*
X264763Y1221062D03*
X270373Y1207972D03*
X277854Y1211712D03*
X274114Y1215452D03*
X277854D03*
X266633D03*
X274114Y1211712D03*
X277854Y1207972D03*
X275984Y1232283D03*
Y1236023D03*
X274114Y1155610D03*
Y1151869D03*
Y1148129D03*
X266633D03*
X270373D03*
Y1151869D03*
X277854Y1148129D03*
Y1151870D03*
X270373Y1155610D03*
X266633D03*
X277854D03*
X274114Y1166830D03*
Y1159350D03*
Y1170570D03*
X277854Y1159350D03*
Y1166830D03*
Y1170570D03*
Y1181791D03*
X274114D03*
Y1174310D03*
X266633Y1189271D03*
X270373Y1178051D03*
Y1185531D03*
X249803Y1228543D03*
X257283D03*
X249803Y1224803D03*
X246062Y1232283D03*
Y1236023D03*
X253543D03*
X264763Y1228543D03*
X257283Y1224803D03*
X261023Y1236023D03*
X253543Y1232283D03*
X261023D03*
X262893Y1166830D03*
X251673Y1170570D03*
X255413Y1166830D03*
X247933D03*
X251673Y1159350D03*
X259153D03*
Y1170570D03*
X251673Y1166830D03*
X255413Y1170570D03*
X247933D03*
X255413Y1159350D03*
X247933D03*
X259153Y1166830D03*
X247933Y1181791D03*
X251673D03*
X255413D03*
X247933Y1189271D03*
X251673D03*
X255413D03*
X262893D03*
Y1174310D03*
X259153Y1181791D03*
X262893D03*
X259153Y1189271D03*
X255413Y1174310D03*
X247933D03*
X251673D03*
X259153D03*
X247933Y1204232D03*
X255413D03*
X251673D03*
X247933Y1196751D03*
X251673D03*
X255413D03*
X259153Y1204232D03*
X262893D03*
X259153Y1196751D03*
X262893D03*
X251673Y1193011D03*
X255413D03*
X247933D03*
X262893D03*
X259153D03*
Y1200491D03*
X262893D03*
X251673D03*
X247933D03*
X255413D03*
X247933Y1207972D03*
X251673D03*
X255413Y1211712D03*
Y1207972D03*
X249803Y1221062D03*
X246062D03*
X253543D03*
X262893Y1207972D03*
X259153D03*
X262893Y1211712D03*
X259153D03*
X261023Y1221062D03*
X257283D03*
X255413Y1215452D03*
X262893D03*
X247932Y1215451D03*
X259153Y1215452D03*
X251673D03*
X247932Y1211711D03*
X251673D03*
X259153Y1148129D03*
X262893D03*
Y1155610D03*
X247933Y1148129D03*
X251673D03*
X255413D03*
X247933Y1155610D03*
X255413D03*
X251673D03*
X259153D03*
X236712Y1200491D03*
X244192D03*
X240452Y1207972D03*
Y1211712D03*
X242322Y1221062D03*
X244192Y1211712D03*
Y1207972D03*
X236712D03*
Y1211712D03*
X238582Y1232283D03*
X234842Y1228543D03*
Y1224803D03*
X238582Y1236023D03*
X242322Y1228543D03*
Y1224803D03*
X236712Y1148129D03*
X240452D03*
X244192D03*
X240452Y1155610D03*
X236712D03*
X244192D03*
X240452Y1166830D03*
X236712Y1159350D03*
X244192Y1170570D03*
Y1159350D03*
X240452Y1170570D03*
Y1159350D03*
X244192Y1166830D03*
X240452Y1181791D03*
Y1189271D03*
X244192Y1181791D03*
Y1189271D03*
X240452Y1174310D03*
X244192D03*
X240452Y1204232D03*
X236712D03*
X240452Y1196751D03*
X244192Y1204232D03*
Y1196751D03*
X240452Y1193011D03*
X244192D03*
X240452Y1200491D03*
X227362Y1228543D03*
Y1224803D03*
X219881Y1228543D03*
Y1224803D03*
X231102Y1232283D03*
Y1236023D03*
X223622Y1224803D03*
Y1228543D03*
X225492Y1148129D03*
X221751D03*
X218011D03*
X229232D03*
X221751Y1155610D03*
X229232D03*
X218011D03*
X225492D03*
Y1170570D03*
Y1159350D03*
X218011Y1170570D03*
Y1159350D03*
X221751Y1170570D03*
Y1159350D03*
X229232D03*
X225492Y1181791D03*
Y1189271D03*
X221751Y1181791D03*
X218011D03*
X221751Y1189271D03*
X218011D03*
X221751Y1174310D03*
X225492D03*
X218011D03*
Y1204232D03*
X229232Y1196751D03*
Y1204232D03*
X225492Y1196751D03*
Y1204232D03*
X221751D03*
Y1196751D03*
X218011D03*
Y1193011D03*
X221751D03*
X225492D03*
X218011Y1200491D03*
X221751D03*
X225492D03*
X229232D03*
X225492Y1207972D03*
X218011Y1211712D03*
X221751Y1207972D03*
X218011D03*
X229232D03*
Y1211712D03*
Y1215452D03*
X225492Y1211712D03*
X221752D03*
X214271Y1215452D03*
X201181Y1224803D03*
X208661Y1228543D03*
X212401D03*
Y1224803D03*
X204921Y1228543D03*
Y1224803D03*
X216141D03*
X208661D03*
X201181Y1228543D03*
X216141D03*
X203051Y1148129D03*
X199311D03*
X206791D03*
X214271D03*
X210531D03*
X199311Y1155610D03*
X206791D03*
X214271D03*
X210531D03*
X203051D03*
Y1159350D03*
Y1170570D03*
X210531Y1159350D03*
Y1170570D03*
X214271D03*
Y1159350D03*
X206791Y1170570D03*
X199311D03*
X206791Y1159350D03*
X199311D03*
X206791Y1181791D03*
X203051D03*
X199311D03*
X206791Y1189271D03*
X203051D03*
X199311D03*
X214271Y1181791D03*
X210531D03*
X214271Y1189271D03*
X210531D03*
X199311Y1174310D03*
X206791D03*
X214271D03*
X203051D03*
X210531D03*
X206791Y1196751D03*
X203051D03*
X199311D03*
Y1204232D03*
X203051D03*
X206791D03*
X214271Y1196751D03*
X210531D03*
Y1204232D03*
X214271D03*
Y1193011D03*
X210531D03*
X199311D03*
X203051D03*
X206791D03*
X214271Y1200491D03*
X210531D03*
X199311D03*
X206791D03*
X203051D03*
X206791Y1207972D03*
X203051D03*
X210531D03*
X214271D03*
Y1211712D03*
X197440Y1224803D03*
Y1228543D03*
X195570Y1151869D03*
Y1148129D03*
Y1155610D03*
Y1159350D03*
Y1189271D03*
Y1185531D03*
Y1200491D03*
Y1196751D03*
Y1193011D03*
Y1204232D03*
X212401Y1221062D03*
X281594Y1207972D03*
X270374Y1215452D03*
X272244Y1221062D03*
X197440D03*
X279724Y1228543D03*
X320866Y1254724D03*
X328347Y1228543D03*
X238582Y1221062D03*
X234842D03*
X201181D03*
X223622D03*
X290944Y1217322D03*
Y1213582D03*
Y1209842D03*
Y1206102D03*
Y1202362D03*
Y1198621D03*
Y1194881D03*
X227362Y1221062D03*
X231102D03*
X268503D03*
X275984D03*
X279724D03*
X283464D03*
X287204D03*
X290944D03*
X216141D03*
X753642Y1170570D03*
Y1181791D03*
Y1174310D03*
X757382D03*
Y1178051D03*
Y1181791D03*
X755512Y1194881D03*
X753642Y1144389D03*
X757382D03*
Y1148129D03*
Y1151869D03*
Y1155610D03*
X753642Y1151869D03*
Y1155610D03*
X757382Y1166830D03*
Y1170570D03*
X753642Y1166830D03*
X757382Y1159350D03*
X753642D03*
X738681Y1155610D03*
Y1148129D03*
X749901Y1144389D03*
Y1151869D03*
X742421Y1155610D03*
X746161Y1148129D03*
X738681Y1144389D03*
X742421Y1148129D03*
Y1144389D03*
X749902Y1155610D03*
Y1148129D03*
X738681Y1166830D03*
X746161Y1170570D03*
Y1166830D03*
X738681Y1159350D03*
X749901Y1166830D03*
Y1159350D03*
X738681Y1170570D03*
X746161Y1159350D03*
X742421D03*
Y1166830D03*
Y1170570D03*
X749902D03*
X749901Y1181791D03*
Y1174310D03*
X738681D03*
Y1178051D03*
X742421Y1181791D03*
X738681Y1185531D03*
Y1189271D03*
X746161Y1185531D03*
Y1178051D03*
Y1174310D03*
X742421Y1185531D03*
Y1189271D03*
Y1174310D03*
X746161Y1181791D03*
X742421Y1178051D03*
X738681Y1204232D03*
X751772Y1194881D03*
X748031D03*
X738681Y1193011D03*
Y1196751D03*
X742421Y1193011D03*
Y1196751D03*
Y1200491D03*
X738681D03*
X742421Y1204232D03*
X738681Y1211712D03*
X742421D03*
Y1215452D03*
Y1207972D03*
X738681Y1215452D03*
Y1118208D03*
X742421D03*
X738681Y1114468D03*
X742421D03*
X738681Y1136909D03*
Y1140649D03*
X742421D03*
Y1136909D03*
X746161Y1144389D03*
Y1155610D03*
Y1151869D03*
X742421D03*
X738681D03*
X734941Y1174310D03*
X731201Y1178051D03*
X719980Y1204232D03*
X727460D03*
X731201D03*
X727460Y1200491D03*
X723720Y1204232D03*
X719980Y1200491D03*
X723720D03*
X734941D03*
Y1204232D03*
Y1211712D03*
X727460Y1207972D03*
X723720Y1211712D03*
Y1207972D03*
X719980Y1211712D03*
Y1207972D03*
X727460Y1211712D03*
X731201Y1207972D03*
Y1215452D03*
X734941D03*
X723720D03*
X719980D03*
X731201Y1211712D03*
X734941Y1207972D03*
Y1121948D03*
Y1118208D03*
X727460Y1121948D03*
X719980D03*
X723720D03*
X727460Y1118208D03*
X731201Y1121948D03*
Y1118208D03*
Y1114468D03*
X734941D03*
X727460D03*
X719980Y1118208D03*
Y1114468D03*
X734941Y1129429D03*
Y1125688D03*
Y1133169D03*
X723720Y1125688D03*
X719980D03*
X727460Y1129429D03*
Y1125688D03*
X731201D03*
X719980Y1129429D03*
X723720D03*
X734941Y1181791D03*
Y1178051D03*
X731201Y1174310D03*
X716240Y1215452D03*
X708760D03*
X712500D03*
X705019Y1215451D03*
Y1211711D03*
X708760D03*
X705020Y1114468D03*
X712500D03*
X716240D03*
X705020Y1118208D03*
X712500D03*
X708760D03*
X716240Y1125688D03*
X712500D03*
X708760D03*
X705020D03*
Y1129429D03*
X708760D03*
X712500D03*
X716240D03*
Y1204232D03*
X708760D03*
X712500D03*
X705020D03*
X712500Y1200491D03*
X705020D03*
X708760D03*
X716240D03*
Y1211712D03*
Y1207972D03*
X712500D03*
Y1211712D03*
X708760Y1207972D03*
X705020D03*
X716240Y1121948D03*
X705020D03*
X708760D03*
X712500D03*
X708760Y1114468D03*
X716240Y1118208D03*
X693799Y1121948D03*
X697539D03*
X701279D03*
X693799Y1114468D03*
Y1118208D03*
X701279Y1114468D03*
X697539Y1118208D03*
Y1114468D03*
X701279Y1118208D03*
X686417Y1132677D03*
X693799Y1125688D03*
X697539D03*
X701279D03*
Y1129429D03*
X697539D03*
X693799D03*
X697539Y1204232D03*
X693799D03*
X701279D03*
Y1200491D03*
X697539D03*
X693799D03*
Y1207972D03*
X697539D03*
Y1211712D03*
X701279Y1207972D03*
Y1211712D03*
X693799D03*
X682579Y1204232D03*
X678838D03*
X671358D03*
X675098D03*
X686319D03*
Y1200491D03*
X675098D03*
X671358D03*
X678838D03*
X682579D03*
Y1207972D03*
X675098Y1211712D03*
X678838Y1207972D03*
X675098D03*
X671358D03*
X686319D03*
Y1211712D03*
Y1215452D03*
X682579Y1211712D03*
X678839D03*
Y1215452D03*
X671358Y1211712D03*
Y1215452D03*
X675098D03*
X682579Y1118208D03*
Y1121948D03*
X671358Y1114468D03*
Y1118208D03*
X675098D03*
X678838D03*
X675098Y1121948D03*
X678838D03*
X671358D03*
X686319D03*
Y1118208D03*
Y1114468D03*
X682579D03*
X678839D03*
X675098D03*
X682579Y1125688D03*
X675098D03*
X671358D03*
X678838D03*
X686319D03*
Y1129429D03*
X675098D03*
X671358D03*
X678838D03*
X682579D03*
X656398Y1204232D03*
X660138D03*
X663878D03*
X667618D03*
Y1200491D03*
X656398D03*
X663878D03*
X660138D03*
X663878Y1207972D03*
X660138D03*
X656398D03*
X667618D03*
Y1211712D03*
X663878D03*
X656398D03*
X660138Y1215452D03*
X656398D03*
X663878D03*
X667618D03*
X660138Y1211712D03*
X656398Y1118208D03*
Y1121948D03*
X663878Y1118208D03*
X660138D03*
Y1121948D03*
X663878D03*
X667618Y1118208D03*
Y1121948D03*
X660138Y1114468D03*
X656398D03*
X663878D03*
X667618D03*
X656398Y1125688D03*
X660138D03*
X663878D03*
X667618D03*
Y1129429D03*
X660138D03*
X656398D03*
X663878D03*
X652657Y1211712D03*
X641437D03*
X652657Y1215452D03*
X641437D03*
X648917D03*
X645177D03*
X641437Y1133169D03*
X637697D03*
X648917D03*
Y1129429D03*
X652657Y1204232D03*
X645177Y1196751D03*
Y1200491D03*
X641437D03*
Y1204232D03*
X645177D03*
X648917D03*
Y1196751D03*
Y1200491D03*
X641437Y1196751D03*
X652657Y1200491D03*
X645177Y1211712D03*
X648917D03*
Y1207972D03*
X645177D03*
X641437D03*
X652657D03*
X637697Y1114468D03*
X648917Y1118208D03*
X645177D03*
X641437D03*
X637697D03*
X648917Y1121948D03*
X645177D03*
X641437D03*
X637697D03*
X652657Y1118208D03*
Y1121948D03*
X645177Y1114468D03*
X641437D03*
X648917D03*
X652657D03*
Y1133169D03*
Y1129429D03*
Y1125688D03*
X648917D03*
X645177D03*
X641437D03*
X637697D03*
X645177Y1129429D03*
X641437D03*
X637697D03*
X645177Y1133169D03*
X622736Y1174310D03*
X630216D03*
Y1178051D03*
X622736Y1178050D03*
Y1114468D03*
X630216Y1118208D03*
X626476D03*
Y1121948D03*
X633957Y1114468D03*
Y1118208D03*
Y1121948D03*
X622736Y1118208D03*
X626476Y1114468D03*
X630216D03*
X633957Y1125688D03*
Y1129429D03*
Y1133169D03*
X622736Y1140649D03*
X630216Y1129428D03*
X626476D03*
X622736Y1129429D03*
Y1144389D03*
Y1148129D03*
Y1155610D03*
Y1166830D03*
Y1170570D03*
X615256Y1114468D03*
X611516D03*
X607776D03*
X615256Y1118208D03*
Y1121948D03*
X611516D03*
X607776D03*
X618996Y1114468D03*
Y1118208D03*
Y1121948D03*
X611516Y1118208D03*
X607776D03*
X615256Y1125688D03*
Y1129429D03*
X611516D03*
X607776D03*
Y1136909D03*
X615256Y1140649D03*
X611516D03*
X607776D03*
X618996D03*
Y1125688D03*
Y1129429D03*
Y1133169D03*
X611516Y1125688D03*
X607776D03*
Y1133169D03*
X618996Y1144389D03*
Y1148129D03*
Y1151870D03*
Y1155610D03*
X607776Y1144389D03*
X615256Y1151869D03*
X611516D03*
X607776Y1148129D03*
Y1151870D03*
X615256Y1155610D03*
X611516D03*
X607776D03*
Y1159350D03*
X615256Y1166830D03*
X611516D03*
X607775D03*
X611516Y1170570D03*
X607775D03*
X618996Y1159350D03*
Y1174310D03*
Y1178051D03*
X607775Y1174310D03*
Y1178051D03*
X611516Y1174310D03*
X615256D03*
X604034D03*
X604035Y1118208D03*
Y1121948D03*
Y1125688D03*
Y1133169D03*
Y1140649D03*
Y1136909D03*
Y1129429D03*
Y1144389D03*
Y1151870D03*
Y1148129D03*
X604036Y1166830D03*
X604035Y1159350D03*
X738681Y1207972D03*
X635827Y1217322D03*
Y1213582D03*
Y1209842D03*
Y1206102D03*
Y1202362D03*
Y1198621D03*
X624606Y1183661D03*
X727461Y1215452D03*
X632086Y1224803D03*
X624606D03*
X620866Y1187401D03*
Y1206102D03*
Y1198621D03*
Y1191141D03*
Y1202362D03*
Y1194881D03*
Y1213582D03*
Y1209842D03*
X628346Y1187401D03*
X624606D03*
Y1191141D03*
X632086Y1202362D03*
X628346D03*
X624606Y1206102D03*
Y1198621D03*
X632086Y1194881D03*
X628346D03*
X632086Y1206102D03*
X628346D03*
X632086Y1198621D03*
X628346D03*
X624606Y1202362D03*
Y1194881D03*
X628346Y1191141D03*
X632086D03*
X624606Y1213582D03*
X632086Y1209842D03*
X628346D03*
X632086Y1213582D03*
X628346D03*
X624606Y1209842D03*
X620866Y1221062D03*
Y1217322D03*
X628346D03*
Y1221062D03*
X624606D03*
Y1217322D03*
X632086Y1221062D03*
Y1217322D03*
X755512Y1221062D03*
Y1217322D03*
Y1209842D03*
Y1202362D03*
X751772Y1224803D03*
Y1221062D03*
Y1217322D03*
Y1209842D03*
Y1202362D03*
X695669Y1221062D03*
X699409D03*
X733071D03*
X736811D03*
X703149D03*
X706890D03*
X710630D03*
X714370D03*
X718110D03*
X721850D03*
X725590D03*
X729331D03*
X740551D03*
X748031D03*
X744291D03*
X748031Y1217322D03*
Y1213582D03*
Y1209842D03*
Y1206102D03*
Y1202362D03*
Y1198621D03*
X620866Y1183661D03*
X691929Y1221062D03*
X635827D03*
X658268D03*
X662008D03*
X665748D03*
X669488D03*
X673228D03*
X684449D03*
X688189D03*
X620866Y1224803D03*
X639567D03*
X635827D03*
X628346D03*
X647047D03*
X654527D03*
X650787D03*
X643307D03*
X662008D03*
X669488D03*
X676968D03*
X684449D03*
X691929D03*
X699409D03*
X714370D03*
X706890D03*
X718110D03*
X736811D03*
X729331D03*
X721850D03*
X733071D03*
X725590D03*
X740551D03*
X744291D03*
X768602Y1193011D03*
X772342D03*
Y1148129D03*
Y1155610D03*
X783563Y1151870D03*
X779823D03*
Y1144389D03*
X783563D03*
X768602Y1155610D03*
Y1148129D03*
X779823Y1159350D03*
X772342Y1170570D03*
X768602D03*
X783563Y1159350D03*
Y1189271D03*
X768602Y1185531D03*
X772342Y1178051D03*
X779823Y1189271D03*
X772342Y1185531D03*
X783563Y1174310D03*
X779823D03*
X783563Y1181791D03*
X768602Y1178051D03*
X779823Y1181791D03*
X764862Y1174310D03*
Y1181791D03*
Y1151869D03*
Y1144389D03*
Y1166830D03*
X639567Y1236023D03*
Y1232283D03*
X632086Y1236023D03*
Y1232283D03*
X639567Y1254724D03*
Y1250984D03*
X632086Y1254724D03*
Y1250984D03*
X635827Y1247243D03*
Y1243503D03*
X654527Y1236023D03*
Y1232283D03*
X647047D03*
Y1236023D03*
X654527Y1254724D03*
Y1250984D03*
X650787Y1243503D03*
Y1247243D03*
X647047Y1250984D03*
Y1254724D03*
X643307Y1247243D03*
Y1243503D03*
X718110D03*
Y1247243D03*
X736811Y1232283D03*
Y1236023D03*
X729331Y1232283D03*
Y1236023D03*
X721850Y1232283D03*
Y1236023D03*
X733071Y1243503D03*
Y1247243D03*
X736811Y1250984D03*
Y1254724D03*
X729331D03*
Y1250984D03*
X725590Y1247243D03*
Y1243503D03*
X721850Y1250984D03*
Y1254724D03*
X744291Y1236023D03*
Y1232283D03*
X740551Y1243503D03*
X744291Y1250984D03*
Y1254724D03*
X740551Y1247243D03*
X1072342Y1077066D03*
Y1099507D03*
Y1095767D03*
Y1106988D03*
Y1103247D03*
Y1121948D03*
Y1118208D03*
Y1114468D03*
Y1110728D03*
Y1140649D03*
Y1129429D03*
Y1125688D03*
Y1155610D03*
Y1151869D03*
Y1073326D03*
Y1092027D03*
Y1088287D03*
Y1084547D03*
Y1080807D03*
X1061121Y1125688D03*
X1057381Y1140649D03*
Y1133169D03*
Y1125688D03*
X1064862D03*
X1068602D03*
X1057381Y1129429D03*
X1061121D03*
X1057381Y1136909D03*
X1064862Y1133169D03*
X1061121Y1136909D03*
X1064862Y1155610D03*
X1068602D03*
X1061121Y1151870D03*
X1064862D03*
Y1148129D03*
X1068602Y1151869D03*
X1061121Y1144389D03*
X1064862D03*
X1057381Y1151870D03*
Y1144389D03*
X1061121Y1148129D03*
X1057381D03*
Y1092027D03*
Y1084547D03*
X1064862Y1092027D03*
X1068602Y1084547D03*
Y1080807D03*
X1057381Y1088287D03*
X1061121D03*
Y1095767D03*
X1068602D03*
X1064862Y1106988D03*
X1068602D03*
X1061121Y1103247D03*
X1064862D03*
Y1099507D03*
X1057381Y1095767D03*
Y1103247D03*
X1068602Y1099507D03*
X1057381Y1106988D03*
X1061121D03*
X1057381Y1099507D03*
X1068602Y1103247D03*
X1064862Y1095767D03*
X1061121Y1099507D03*
X1064862Y1121948D03*
X1068602D03*
X1061121Y1118208D03*
X1064862Y1114468D03*
X1068602D03*
X1061121Y1110728D03*
X1057381Y1118208D03*
Y1110728D03*
Y1114468D03*
X1061121D03*
X1068602Y1110728D03*
Y1118208D03*
X1064862Y1110728D03*
Y1118208D03*
X1057381Y1121948D03*
X1061121D03*
Y1140649D03*
X1064862D03*
X1068602D03*
X1064862Y1136909D03*
X1061121Y1133169D03*
X1064862Y1129429D03*
X1068602D03*
Y1073326D03*
X1064862D03*
X1064861Y1077066D03*
X1061121Y1092027D03*
X1068602D03*
X1064862Y1088287D03*
X1068602D03*
X1061121Y1084547D03*
X1064862D03*
Y1080807D03*
X1061121Y1080806D03*
Y1077066D03*
X1068602D03*
X1141535Y1221062D03*
X1205117Y1213582D03*
Y1209842D03*
X1137795Y1108858D03*
X1205117Y1198621D03*
X1178936Y1221062D03*
X1182676D03*
X1190157D03*
X1205117Y1202362D03*
X1240589Y1193011D03*
X1240649Y1148129D03*
Y1155610D03*
Y1151870D03*
Y1144389D03*
Y1166830D03*
Y1170570D03*
Y1159350D03*
Y1178051D03*
Y1185531D03*
Y1174310D03*
Y1181791D03*
Y1189271D03*
X1236909Y1178051D03*
Y1185531D03*
X1229428Y1181791D03*
Y1189271D03*
X1233169D03*
Y1185531D03*
Y1181791D03*
Y1178051D03*
X1229428Y1174310D03*
X1233169D03*
X1225688D03*
Y1181791D03*
Y1189271D03*
X1236909Y1181791D03*
X1225688Y1185531D03*
X1236909Y1189271D03*
X1229428Y1178051D03*
Y1185531D03*
X1236909Y1174310D03*
X1225688Y1178051D03*
X1233169Y1193011D03*
X1236909D03*
X1229428D03*
X1236909Y1148129D03*
Y1155610D03*
X1233169Y1144389D03*
X1225688D03*
Y1151869D03*
X1229428Y1144389D03*
X1233169Y1155610D03*
X1229428Y1151869D03*
X1233169D03*
Y1148129D03*
X1236909Y1151870D03*
X1225688Y1148129D03*
X1229428D03*
X1225688Y1155610D03*
X1236909Y1144389D03*
X1229428Y1155610D03*
X1236909Y1170570D03*
Y1166830D03*
X1225688D03*
X1229428Y1159350D03*
X1233169D03*
X1225688D03*
X1229428Y1166830D03*
X1233169Y1170570D03*
Y1166830D03*
X1229428Y1170570D03*
X1225688D03*
X1236909Y1159350D03*
X1210728Y1181791D03*
X1206987D03*
X1210728Y1189271D03*
X1218208Y1185531D03*
Y1178051D03*
X1214468Y1189271D03*
X1221948Y1178051D03*
Y1185531D03*
X1206987Y1174310D03*
Y1189271D03*
X1214468Y1185531D03*
Y1181791D03*
Y1178051D03*
Y1174310D03*
X1210728D03*
X1218208Y1189271D03*
Y1174310D03*
X1221948Y1181791D03*
Y1174310D03*
X1218208Y1181791D03*
X1221948Y1189271D03*
X1208858Y1194881D03*
X1218208Y1193011D03*
X1221948Y1155610D03*
X1210728Y1151869D03*
X1206987D03*
X1218208Y1155610D03*
Y1148129D03*
X1214468Y1155610D03*
Y1151869D03*
Y1148129D03*
Y1144389D03*
X1206987D03*
X1210728D03*
X1221948Y1148129D03*
X1218208Y1144389D03*
Y1151869D03*
X1206988Y1155610D03*
Y1148129D03*
X1210728Y1155610D03*
X1221948Y1151869D03*
Y1144389D03*
X1206987Y1159350D03*
X1210728D03*
X1214468D03*
X1210728Y1166830D03*
X1206987D03*
X1218208Y1170570D03*
X1214468D03*
Y1166830D03*
X1221948Y1170570D03*
Y1159350D03*
X1218208Y1166830D03*
Y1159350D03*
X1221948Y1166830D03*
X1210728Y1170570D03*
X1206988D03*
X1192027Y1211712D03*
X1195767D03*
X1192027Y1215452D03*
X1199507Y1211712D03*
Y1215452D03*
Y1207972D03*
X1195767Y1215452D03*
X1192027Y1207972D03*
Y1166830D03*
Y1170570D03*
Y1181791D03*
X1199507Y1185531D03*
X1203247Y1174310D03*
Y1178051D03*
Y1185531D03*
X1192027Y1178051D03*
Y1189271D03*
X1195767D03*
X1192027Y1185531D03*
X1195767D03*
X1199507Y1181791D03*
X1195767Y1178051D03*
Y1174310D03*
X1203247Y1189271D03*
X1199507D03*
X1195767Y1181791D03*
X1192027Y1174310D03*
X1199507Y1178051D03*
X1203247Y1181791D03*
X1195767Y1204232D03*
X1199507Y1193011D03*
X1203247D03*
X1195767Y1196751D03*
Y1193011D03*
X1192027D03*
X1199507Y1196751D03*
Y1200491D03*
Y1204232D03*
X1195767Y1200491D03*
X1192027Y1204232D03*
Y1200491D03*
Y1196751D03*
Y1136909D03*
X1195767Y1140649D03*
X1192027Y1133169D03*
Y1140649D03*
X1195767Y1136909D03*
X1192027Y1125688D03*
Y1129429D03*
X1199507Y1140649D03*
Y1136909D03*
X1195767Y1148129D03*
X1192027Y1144389D03*
X1195767Y1155610D03*
X1192027Y1148129D03*
X1195767Y1151869D03*
X1199507D03*
X1203247D03*
Y1155610D03*
Y1144389D03*
X1192027Y1151870D03*
Y1155610D03*
X1203247Y1148129D03*
X1195767Y1144389D03*
X1199507Y1148129D03*
Y1144389D03*
X1195767Y1170570D03*
Y1159350D03*
X1203247Y1166830D03*
Y1170570D03*
Y1159350D03*
X1195767Y1166830D03*
X1192027Y1159350D03*
Y1118208D03*
Y1121948D03*
X1199507Y1118208D03*
X1195767D03*
Y1114468D03*
X1192027D03*
X1199507D03*
X1188287Y1181791D03*
Y1174310D03*
X1177066Y1189271D03*
X1180806D03*
X1184546Y1178051D03*
X1177066Y1174310D03*
X1184546Y1185531D03*
X1177066Y1181791D03*
X1180806D03*
X1184546Y1189271D03*
Y1174310D03*
X1177066Y1185531D03*
Y1178051D03*
X1180806Y1185531D03*
Y1178051D03*
Y1174310D03*
X1184546Y1181791D03*
X1188287Y1185531D03*
Y1189271D03*
Y1178051D03*
X1184546Y1204232D03*
X1177066D03*
X1180806D03*
X1184546Y1200491D03*
X1177066Y1196751D03*
X1180806D03*
X1184546Y1193011D03*
X1188287Y1204232D03*
Y1196751D03*
X1184566Y1196732D03*
X1188287Y1200491D03*
X1177066Y1193011D03*
X1180806D03*
X1188287D03*
Y1207972D03*
X1184546Y1211712D03*
X1177066Y1207972D03*
Y1211712D03*
X1180806Y1207972D03*
Y1211712D03*
X1184546Y1207972D03*
X1188287Y1215452D03*
X1180806D03*
X1177066D03*
X1188287Y1211712D03*
Y1125688D03*
X1184546Y1136909D03*
X1177066Y1133169D03*
X1180806D03*
X1184546D03*
X1177066Y1140649D03*
X1180806D03*
X1184546Y1125688D03*
Y1129429D03*
X1177066Y1125688D03*
X1180806D03*
X1184546Y1140649D03*
X1188287Y1129429D03*
X1180806Y1136909D03*
X1177066D03*
X1188287D03*
Y1140649D03*
Y1155610D03*
Y1151869D03*
Y1148129D03*
X1177066D03*
X1180806D03*
X1184546Y1144389D03*
Y1148129D03*
Y1151869D03*
X1177066Y1155610D03*
X1184546D03*
X1180806Y1151869D03*
X1177066D03*
Y1144389D03*
X1180806D03*
Y1155610D03*
X1188287Y1144389D03*
X1177066Y1166830D03*
X1188287D03*
Y1159350D03*
Y1170570D03*
X1180806D03*
X1184546D03*
X1177066D03*
X1184546Y1166830D03*
X1180806D03*
X1177066Y1159350D03*
X1180806D03*
X1184546D03*
X1188287Y1118208D03*
Y1121948D03*
X1184546Y1118208D03*
X1180806Y1121948D03*
X1177066D03*
X1184546D03*
X1188287Y1114468D03*
X1177066D03*
Y1118208D03*
X1184546Y1114468D03*
X1158365Y1211712D03*
Y1207972D03*
X1173326D03*
Y1211712D03*
X1162106Y1207972D03*
X1165846D03*
X1173326Y1215452D03*
X1165846D03*
X1169586D03*
X1162105Y1215451D03*
Y1211711D03*
X1165846D03*
X1173326Y1166830D03*
Y1189271D03*
X1158365Y1181791D03*
X1162106D03*
X1165846D03*
X1169586D03*
X1158365Y1189271D03*
X1162106D03*
X1165846D03*
X1169586D03*
X1173326Y1181791D03*
X1169586Y1174310D03*
X1162106D03*
X1158365Y1185531D03*
X1162106D03*
X1169586D03*
X1165846D03*
X1173326D03*
X1165846Y1178051D03*
X1158365D03*
X1162106D03*
X1169586D03*
X1173326D03*
X1165846Y1174310D03*
X1158365D03*
X1173326D03*
X1162106Y1204232D03*
X1158365D03*
X1169586D03*
X1165846D03*
X1158365Y1196751D03*
X1162106D03*
X1165846D03*
X1169586D03*
X1173326Y1204232D03*
Y1196751D03*
X1165846Y1193011D03*
X1169586D03*
X1158365D03*
X1162106D03*
X1173326D03*
X1169586Y1211712D03*
Y1207972D03*
X1162106Y1133169D03*
X1165846D03*
X1169586D03*
X1158365Y1140649D03*
X1162106D03*
X1165846D03*
X1169586D03*
X1158365Y1125688D03*
X1162106D03*
X1165846D03*
X1169586D03*
X1173326Y1133169D03*
Y1125688D03*
Y1140649D03*
X1158365Y1133169D03*
X1173326Y1136909D03*
X1169586D03*
X1165846D03*
X1158365D03*
X1162106D03*
X1173326Y1148129D03*
X1158365D03*
X1162106D03*
X1165846D03*
X1169586D03*
X1162106Y1155610D03*
X1169586D03*
X1173326Y1151869D03*
X1158365D03*
X1162106D03*
X1169586D03*
X1165846D03*
X1173326Y1144389D03*
X1165846D03*
X1158365D03*
X1162106D03*
X1169586D03*
X1173326Y1155610D03*
X1165846D03*
X1158365D03*
Y1170570D03*
X1165846D03*
X1169586Y1166830D03*
X1158365Y1159350D03*
X1162106Y1166830D03*
X1165846Y1159350D03*
X1173326D03*
Y1170570D03*
X1165846Y1166830D03*
X1169586Y1170570D03*
X1158365Y1166830D03*
X1162106Y1170570D03*
X1169586Y1159350D03*
X1162106D03*
X1169586Y1121948D03*
X1165846D03*
X1162106D03*
X1158365D03*
X1173326D03*
X1162106Y1114468D03*
X1169586D03*
X1162106Y1118208D03*
X1173326Y1114468D03*
X1158365Y1118208D03*
X1173326D03*
X1158365Y1114468D03*
X1169586Y1118208D03*
X1165846D03*
X1154625Y1204232D03*
X1150885D03*
X1154625Y1196751D03*
X1143405Y1204232D03*
X1154625Y1193011D03*
X1150885Y1207972D03*
X1154625D03*
Y1211712D03*
X1143405Y1207972D03*
Y1211712D03*
Y1215452D03*
X1150885Y1211712D03*
X1143405Y1148129D03*
X1150885D03*
X1154625D03*
X1143405Y1155610D03*
X1154625D03*
X1143405Y1144389D03*
X1150885Y1151869D03*
X1154625D03*
Y1144389D03*
X1150885D03*
X1143405Y1151870D03*
X1150885Y1155610D03*
X1154625Y1166830D03*
X1150885Y1159350D03*
X1154625D03*
Y1170570D03*
Y1181791D03*
Y1189271D03*
Y1174310D03*
Y1185531D03*
Y1178051D03*
X1150885Y1121948D03*
X1143405D03*
Y1118208D03*
Y1114468D03*
X1154625Y1121948D03*
Y1118208D03*
X1150885D03*
X1154625Y1114468D03*
X1150885D03*
X1154625Y1125688D03*
X1150885Y1133464D03*
X1154625Y1133169D03*
X1143503Y1132677D03*
X1143405Y1140649D03*
Y1125688D03*
X1150885Y1140649D03*
X1154625D03*
X1150885Y1125688D03*
X1143405Y1136909D03*
X1154625D03*
X1150885D03*
X1139665Y1204232D03*
X1135924D03*
X1128444D03*
X1132184D03*
X1139665Y1207972D03*
X1132184Y1211712D03*
X1135924Y1207972D03*
X1132184D03*
X1128444D03*
X1139665Y1211712D03*
X1135925D03*
X1128444Y1215452D03*
Y1211712D03*
X1139665Y1125688D03*
X1128444Y1140649D03*
X1132184D03*
X1135924D03*
X1132184Y1125688D03*
X1128444D03*
X1135924D03*
Y1133169D03*
X1132184D03*
X1128444D03*
X1139665Y1136909D03*
X1135924D03*
X1132184D03*
X1128444D03*
X1135924Y1148129D03*
X1132184D03*
X1128444D03*
X1139665D03*
X1128444Y1155610D03*
X1135924D03*
X1128444Y1144389D03*
X1135924D03*
X1132184D03*
X1139665D03*
X1135925Y1151870D03*
X1132184D03*
X1128444D03*
X1139665D03*
Y1155610D03*
X1132184D03*
X1139665Y1121948D03*
X1128444Y1118208D03*
X1132184D03*
X1135924D03*
X1132184Y1121948D03*
X1135924D03*
X1128444D03*
X1139665Y1118208D03*
Y1114468D03*
X1135925D03*
X1139665Y1133169D03*
Y1140649D03*
X1124704Y1204232D03*
X1120964D03*
X1117224D03*
X1113484D03*
Y1207972D03*
X1117224D03*
X1120964D03*
X1124704Y1211712D03*
Y1207972D03*
Y1215452D03*
X1120964D03*
Y1211712D03*
X1113484D03*
X1117224D03*
X1113484Y1155610D03*
X1109743Y1144389D03*
X1120964Y1155610D03*
X1109743Y1151869D03*
X1124704Y1144389D03*
X1113484D03*
X1117224D03*
X1120964D03*
X1113484Y1151870D03*
X1117224D03*
X1120964D03*
X1124704D03*
Y1155610D03*
X1109743D03*
Y1148129D03*
X1117224Y1155610D03*
Y1121948D03*
Y1118208D03*
X1120964D03*
X1109743Y1121948D03*
X1113484D03*
X1109743Y1118208D03*
X1113484D03*
X1124704Y1121948D03*
Y1118208D03*
X1120964Y1121948D03*
X1117224Y1114468D03*
X1113484D03*
X1120964D03*
X1124704D03*
X1109743D03*
Y1136909D03*
X1124704Y1125688D03*
Y1140649D03*
Y1133169D03*
X1113484D03*
X1117224D03*
X1120964D03*
X1109743Y1125688D03*
X1120964D03*
X1117224D03*
X1113484D03*
X1120964Y1140649D03*
X1117224D03*
X1113484D03*
X1109743Y1129429D03*
Y1133169D03*
X1124704Y1136909D03*
X1113484D03*
X1117224D03*
X1120964D03*
X1109743Y1140649D03*
X1120964Y1148129D03*
X1113484D03*
X1117224D03*
X1124704D03*
X1098523Y1140649D03*
X1102263D03*
X1094783Y1136909D03*
X1102263D03*
X1094783Y1133169D03*
X1098523D03*
X1102263D03*
X1094783Y1129429D03*
X1098523D03*
X1102263D03*
X1094783Y1125688D03*
X1098523D03*
X1102263D03*
X1106003D03*
X1094783Y1140649D03*
X1106003D03*
Y1136909D03*
X1098523D03*
X1106003Y1133169D03*
Y1129429D03*
X1094783Y1151870D03*
Y1155610D03*
X1102263Y1151870D03*
X1094783Y1148129D03*
Y1144389D03*
X1102263D03*
X1106003Y1148129D03*
Y1155610D03*
Y1151869D03*
Y1144389D03*
X1098523D03*
Y1151870D03*
X1102263Y1148129D03*
Y1155610D03*
X1094783Y1121948D03*
X1098523D03*
X1102263D03*
X1106003D03*
X1094783Y1118208D03*
X1098523D03*
X1102263D03*
X1106003D03*
X1094783Y1114468D03*
X1102263D03*
X1098523D03*
X1106003D03*
X1083562Y1121948D03*
Y1118208D03*
X1087302D03*
X1079822Y1114468D03*
X1083562Y1110728D03*
X1091043Y1121948D03*
Y1118208D03*
Y1114468D03*
X1079822Y1118208D03*
Y1110728D03*
X1083562Y1114468D03*
X1087302D03*
X1091043Y1125688D03*
Y1140649D03*
X1083562Y1136909D03*
X1087302D03*
X1079822Y1129429D03*
X1083562Y1129428D03*
X1087302D03*
X1079822Y1140649D03*
X1083562D03*
X1087302D03*
X1091043Y1136909D03*
Y1133169D03*
Y1129429D03*
X1087302Y1151870D03*
Y1155610D03*
Y1148129D03*
X1083562Y1144389D03*
X1087302D03*
X1091043Y1151870D03*
Y1148129D03*
Y1144389D03*
X1083562Y1148129D03*
X1079822Y1144389D03*
Y1148129D03*
X1083562Y1151870D03*
X1079822Y1155610D03*
X1083562Y1092027D03*
Y1088287D03*
Y1077066D03*
X1079822Y1088287D03*
Y1084547D03*
Y1080807D03*
Y1092027D03*
X1083562Y1084547D03*
X1079822Y1077066D03*
X1083562Y1080807D03*
Y1099507D03*
Y1095767D03*
X1079822Y1106988D03*
X1083562D03*
X1079822Y1103247D03*
Y1099507D03*
Y1095767D03*
X1083562Y1103247D03*
Y1073326D03*
X1079822D03*
X1076082D03*
Y1092027D03*
Y1088287D03*
Y1077066D03*
Y1084547D03*
Y1080807D03*
Y1106988D03*
Y1095767D03*
Y1103247D03*
Y1099507D03*
Y1114468D03*
Y1121948D03*
Y1118208D03*
Y1110728D03*
Y1133169D03*
Y1129429D03*
Y1125688D03*
Y1140649D03*
Y1155610D03*
Y1151870D03*
Y1148129D03*
Y1144389D03*
X1130314Y1108858D03*
X1104132Y1071455D03*
X1119093D03*
X1195767Y1207972D03*
X1163976Y1221062D03*
X1156495D03*
X1205117Y1206102D03*
X1184547Y1215452D03*
X1167716Y1221062D03*
X1197637D03*
X1171456D03*
X1115354Y1224803D03*
Y1228543D03*
X1119094Y1236023D03*
Y1232283D03*
X1122834Y1228543D03*
Y1224803D03*
X1126574Y1232283D03*
Y1236023D03*
Y1224803D03*
Y1228543D03*
X1122834Y1232283D03*
Y1236023D03*
X1119094Y1224803D03*
Y1228543D03*
X1115354Y1232283D03*
Y1236023D03*
X1130314Y1224803D03*
Y1228543D03*
X1141535Y1236023D03*
Y1232283D03*
X1134054Y1236023D03*
Y1232283D03*
X1137795Y1228543D03*
Y1224803D03*
X1141535Y1228543D03*
Y1224803D03*
X1137795Y1232283D03*
Y1236023D03*
X1134054Y1228543D03*
Y1224803D03*
X1130314Y1232283D03*
Y1236023D03*
X1152755Y1232283D03*
Y1236023D03*
X1156495Y1228543D03*
Y1224803D03*
X1149015Y1228543D03*
Y1224803D03*
X1145275Y1232283D03*
Y1236023D03*
X1163976Y1228543D03*
Y1224803D03*
X1171456Y1228543D03*
Y1224803D03*
X1167716Y1232283D03*
X1175196D03*
Y1236023D03*
X1167716D03*
X1160235Y1232283D03*
Y1236023D03*
X1178936Y1228543D03*
Y1224803D03*
X1182676Y1232283D03*
Y1236023D03*
X1190157Y1232283D03*
Y1236023D03*
X1186417Y1228543D03*
Y1224803D03*
X1205117Y1228543D03*
Y1224803D03*
X1197637Y1232283D03*
X1201377Y1228543D03*
X1197637Y1236023D03*
X1201377Y1224803D03*
X1205117Y1232283D03*
Y1236023D03*
X1193897Y1228543D03*
Y1224803D03*
X1212598D03*
Y1228543D03*
X1220078Y1224803D03*
Y1228543D03*
X1216338Y1232283D03*
Y1236023D03*
X1223818D03*
Y1232283D03*
X1216338Y1224803D03*
Y1228543D03*
X1212598Y1232283D03*
Y1236023D03*
X1223818Y1228543D03*
X1220078Y1232283D03*
Y1236023D03*
X1208858D03*
Y1232283D03*
Y1224803D03*
Y1228543D03*
X1227558D03*
X1235039D03*
X1238779D03*
X1231298Y1232283D03*
Y1236023D03*
X1238779Y1224803D03*
X1235039D03*
X1231298D03*
Y1228543D03*
X1227558Y1236023D03*
Y1232283D03*
X1238779D03*
X1235039D03*
Y1236023D03*
X1238779D03*
X1220078Y1202362D03*
X1216338D03*
X1212598Y1206102D03*
Y1198621D03*
X1223818Y1206102D03*
X1220078D03*
X1216338D03*
X1212598Y1202362D03*
X1223818D03*
Y1198621D03*
X1220078D03*
X1216338D03*
X1208858Y1206102D03*
Y1198621D03*
Y1202362D03*
X1220078Y1217322D03*
X1216338D03*
X1212598Y1213582D03*
X1216338Y1209842D03*
X1220078D03*
X1223818Y1217322D03*
X1220078Y1221062D03*
X1216338D03*
X1212598D03*
Y1217322D03*
X1216338Y1213582D03*
X1220078D03*
X1223818D03*
Y1209842D03*
X1212598D03*
X1208858Y1213582D03*
Y1221062D03*
Y1217322D03*
Y1209842D03*
X1238779Y1198621D03*
X1231298Y1202362D03*
X1227558D03*
X1235039Y1206102D03*
X1238779D03*
Y1202362D03*
X1235039D03*
X1231298Y1206102D03*
X1227558D03*
X1238779Y1213582D03*
X1235039D03*
X1238779Y1221062D03*
X1235039D03*
X1231298Y1217322D03*
X1227558D03*
Y1209842D03*
X1231298D03*
X1238779Y1217322D03*
X1235039D03*
X1231298Y1221062D03*
X1238779Y1209842D03*
X1235039D03*
X1231298Y1213582D03*
X1227558D03*
X1092913Y1075196D03*
X1089172Y1082677D03*
Y1086417D03*
X1092913Y1078936D03*
X1089172Y1090157D03*
X1092913D03*
X1089172Y1097637D03*
Y1093897D03*
X1092913Y1101376D03*
Y1093897D03*
Y1097637D03*
X1089172Y1101377D03*
X1107873Y1075196D03*
X1100393D03*
X1104133Y1086417D03*
Y1090157D03*
Y1082677D03*
X1107873Y1090157D03*
Y1078936D03*
X1100393D03*
Y1090157D03*
X1096653Y1082677D03*
Y1086417D03*
Y1090157D03*
X1104133Y1093897D03*
Y1097637D03*
X1107873Y1101376D03*
Y1093897D03*
Y1097637D03*
X1104133Y1101377D03*
X1100393Y1101376D03*
Y1097637D03*
Y1093897D03*
X1096653Y1097637D03*
Y1093897D03*
Y1101377D03*
X1115354Y1075196D03*
X1122834D03*
X1115354Y1090157D03*
Y1078936D03*
X1119094Y1082677D03*
Y1086417D03*
Y1090157D03*
X1122834D03*
X1126574D03*
Y1086417D03*
Y1082677D03*
X1122834Y1078936D03*
X1111613Y1082677D03*
Y1086417D03*
Y1090157D03*
X1126574Y1093897D03*
Y1097637D03*
X1119094Y1093897D03*
Y1097637D03*
X1115354Y1101376D03*
X1122834D03*
Y1093897D03*
X1115354D03*
X1122834Y1097637D03*
X1115354D03*
X1119094Y1101377D03*
X1126574D03*
X1111613Y1097637D03*
Y1093897D03*
Y1101377D03*
X1130314Y1075196D03*
X1137795D03*
X1130314Y1090157D03*
Y1078936D03*
X1134054Y1082677D03*
Y1086417D03*
Y1090157D03*
X1137795D03*
Y1078936D03*
X1134054Y1097637D03*
Y1093897D03*
X1137794Y1101376D03*
X1130314D03*
Y1097637D03*
Y1093897D03*
X1137795D03*
Y1097637D03*
X1134054Y1101377D03*
X1092913Y1105117D03*
X1107873D03*
X1104133D03*
X1100393D03*
X1096653D03*
X1115354D03*
X1122834D03*
X1119094D03*
X1126574D03*
X1111613D03*
X1137794D03*
X1130314D03*
X1134054D03*
X1149015Y1221062D03*
X1122834D03*
X1126574Y1108858D03*
X1193897Y1221062D03*
X1119094D03*
X1201377D03*
X1130314D03*
X1115354D03*
X1205117D03*
X1111612Y1071455D03*
X1134053D03*
X1096652D03*
X1089171D03*
X1242520Y1228543D03*
Y1221062D03*
Y1198621D03*
Y1206102D03*
Y1213582D03*
X1126573Y1071455D03*
X1137795Y1221062D03*
X1152755D03*
X1122834Y1108858D03*
X1145275Y1221062D03*
X1134054D03*
X1115354Y1108858D03*
X1104133D03*
X1134054D03*
X1119094D03*
X1160235Y1221062D03*
X1126574D03*
X1205117Y1217322D03*
X1111613Y1108858D03*
X1175196Y1221062D03*
X1107873Y1108858D03*
X1100393D03*
X1186417Y1221062D03*
X1139665Y1178051D03*
X1135924D03*
X1132184D03*
X1128444D03*
X1139665Y1185531D03*
X1132184D03*
X1128444D03*
X1135924D03*
X1139665Y1174310D03*
X1132184D03*
X1128444Y1193011D03*
X1132184D03*
X1135924D03*
X1139665D03*
X1135924Y1170570D03*
X1128444D03*
X1120964Y1193011D03*
X1117224D03*
X1113484D03*
X1124704D03*
X1113484Y1170570D03*
X1120964D03*
X1113484Y1178051D03*
X1117224D03*
X1120964D03*
X1124704D03*
X1120964Y1185531D03*
X1113484D03*
X1117224D03*
X1124704D03*
X1109743Y1174310D03*
Y1181791D03*
X1117224Y1174310D03*
X1124704D03*
X1106003Y1215452D03*
X1098523D03*
X1102263D03*
X1106003Y1178051D03*
Y1185531D03*
X1098523D03*
X1102263Y1174310D03*
X1098523Y1178051D03*
X1102263Y1181791D03*
X1106003Y1193011D03*
Y1170570D03*
X1098523D03*
X1091043Y1181791D03*
Y1178051D03*
Y1174310D03*
X1085432Y1224803D03*
Y1228543D03*
X1089172Y1232283D03*
Y1236023D03*
X1092913Y1224803D03*
Y1228543D03*
X1100393Y1224803D03*
Y1228543D03*
X1104133Y1236023D03*
Y1232283D03*
X1107873Y1228543D03*
Y1224803D03*
X1096653Y1232283D03*
Y1236023D03*
X1205117Y1247243D03*
X1220078D03*
X1223818Y1250984D03*
Y1254724D03*
X1216338D03*
Y1250984D03*
X1212598Y1247243D03*
X1208858Y1250984D03*
Y1254724D03*
X1238779Y1247243D03*
X1235039D03*
X1231298Y1250984D03*
Y1254724D03*
X1227558Y1247243D03*
X1550000Y1105117D03*
X1564960D03*
X1557480D03*
X1572441D03*
X1579921D03*
X1594881D03*
X1587401D03*
X1561220Y1093897D03*
Y1097637D03*
X1564960Y1101376D03*
X1557480D03*
X1553740Y1097637D03*
Y1093897D03*
X1583661D03*
Y1097637D03*
X1576181Y1093897D03*
Y1097637D03*
X1572441Y1101376D03*
X1579921D03*
X1568700Y1097637D03*
Y1093897D03*
X1598622Y1097637D03*
X1591141D03*
Y1093897D03*
X1594881Y1101376D03*
X1587401D03*
X1546259Y1097637D03*
Y1093897D03*
X1550000Y1101376D03*
Y1213582D03*
Y1198621D03*
Y1209842D03*
Y1217322D03*
Y1202362D03*
Y1206102D03*
X1647244Y1221062D03*
X1643504D03*
X1639763D03*
X1636023D03*
X1602362D03*
X1662204D03*
X1650984D03*
X1665945Y1224803D03*
X1650984D03*
X1658464D03*
X1654724D03*
X1643504D03*
X1636023D03*
X1647244D03*
X1639763D03*
X1628543D03*
X1621063D03*
X1632283D03*
X1606102D03*
X1613582D03*
X1591141D03*
X1598622D03*
X1568700D03*
X1576181D03*
X1583661D03*
X1553740D03*
X1561220D03*
X1564960D03*
X1557480D03*
X1550000D03*
X1546259D03*
X1538779D03*
X1542519D03*
X1546259Y1213582D03*
X1542519D03*
Y1217322D03*
Y1221062D03*
X1538779D03*
X1546259D03*
Y1217322D03*
X1535039Y1224803D03*
X1658464Y1221062D03*
X1669685Y1202362D03*
X1665945Y1209842D03*
Y1217322D03*
Y1221062D03*
X1669685Y1209842D03*
Y1217322D03*
Y1221062D03*
X1654724D03*
X1535039Y1183661D03*
X1542519Y1187401D03*
X1583661Y1221062D03*
X1579921D03*
X1576181D03*
X1572441D03*
X1624803D03*
X1632283D03*
X1609842D03*
X1628543D03*
X1613582D03*
X1621063D03*
X1535039D03*
X1546259Y1209842D03*
X1542519D03*
X1546259Y1202362D03*
X1542519D03*
X1546259Y1206102D03*
X1542519D03*
X1546259Y1194881D03*
X1542519D03*
X1546259Y1198621D03*
X1542519D03*
Y1191141D03*
X1546259D03*
X1538779Y1213582D03*
Y1209842D03*
Y1217322D03*
Y1191141D03*
Y1206102D03*
Y1198621D03*
Y1202362D03*
Y1194881D03*
Y1187401D03*
X1535039Y1213582D03*
Y1209842D03*
Y1217322D03*
Y1206102D03*
Y1198621D03*
Y1191141D03*
Y1202362D03*
Y1194881D03*
Y1187401D03*
X1557480Y1221062D03*
X1553740D03*
X1550000D03*
X1587401D03*
X1641634Y1215452D03*
X1652854Y1207972D03*
X1514468Y1166829D03*
Y1159350D03*
Y1155610D03*
Y1148129D03*
Y1151870D03*
Y1144389D03*
Y1136909D03*
Y1129429D03*
Y1140649D03*
Y1133169D03*
Y1125688D03*
Y1121948D03*
X1527559Y1179921D03*
X1518207Y1174310D03*
X1521948D03*
X1518209Y1166830D03*
X1521948Y1170570D03*
X1525689D03*
X1521948Y1166830D03*
X1525689D03*
X1529429D03*
X1518208Y1159350D03*
X1521949D03*
X1518208Y1155610D03*
Y1148129D03*
X1521949Y1155610D03*
X1525689D03*
X1529429D03*
X1518208Y1151870D03*
X1521949D03*
Y1148129D03*
X1525689Y1151869D03*
X1529429D03*
X1518208Y1144389D03*
X1521949D03*
Y1133169D03*
X1518208Y1136909D03*
X1521949Y1125688D03*
X1518208Y1129429D03*
X1525689Y1125688D03*
X1518208Y1140649D03*
X1521949D03*
X1525689D03*
X1529429D03*
X1521949Y1136909D03*
X1518208Y1133169D03*
X1521949Y1129429D03*
X1525689D03*
X1529429D03*
X1518208Y1125688D03*
X1529429D03*
X1518208Y1121948D03*
X1521949D03*
X1525689D03*
X1529429D03*
X1540649Y1174310D03*
X1544389Y1178051D03*
Y1174310D03*
X1536909Y1170570D03*
Y1166830D03*
X1533169Y1159350D03*
X1536909Y1155610D03*
Y1144389D03*
Y1148129D03*
X1533169Y1155610D03*
Y1151870D03*
Y1148129D03*
Y1144389D03*
Y1133169D03*
Y1129429D03*
X1536909D03*
X1540649Y1129428D03*
X1544389D03*
X1533169Y1125688D03*
Y1140649D03*
X1536909D03*
X1533169Y1121948D03*
X1540649D03*
X1548130D03*
X1551870D03*
X1555610D03*
X1559350D03*
X1563090D03*
Y1129429D03*
Y1133169D03*
X1548130D03*
X1551870D03*
X1555610D03*
X1559350D03*
X1548130Y1129429D03*
X1551870D03*
X1555610D03*
X1559350D03*
X1548130Y1125688D03*
X1551870D03*
X1555610D03*
X1559350D03*
X1563090D03*
X1559350Y1215452D03*
X1563090D03*
X1555610Y1207972D03*
X1559350D03*
X1563090D03*
Y1211712D03*
X1559350D03*
X1555610D03*
Y1196751D03*
X1563090Y1200491D03*
Y1196751D03*
Y1204232D03*
X1559350D03*
X1555610D03*
Y1200491D03*
X1559350D03*
Y1196751D03*
X1570571Y1121948D03*
Y1204232D03*
X1566830D03*
Y1200491D03*
X1578051Y1129429D03*
X1570571D03*
X1574311D03*
X1566830Y1125688D03*
X1578051D03*
X1574311D03*
X1570571D03*
X1566830Y1129429D03*
Y1133169D03*
X1578051Y1121948D03*
X1574311D03*
X1566830D03*
X1574311Y1211712D03*
X1578051D03*
X1570571Y1215452D03*
X1574311D03*
X1570571Y1211712D03*
X1566830Y1215452D03*
X1578051D03*
X1570571Y1207972D03*
X1574311D03*
X1578051D03*
X1566830Y1211712D03*
Y1207972D03*
X1574311Y1200491D03*
X1578051D03*
X1570571D03*
X1578051Y1204232D03*
X1574311D03*
X1581791Y1211712D03*
Y1207972D03*
X1589271Y1211712D03*
X1593011Y1200491D03*
X1581791D03*
X1585531D03*
X1589271D03*
Y1204232D03*
X1585531D03*
X1581791D03*
X1593011D03*
Y1129429D03*
X1581791D03*
X1585531D03*
X1589271D03*
X1593011Y1125688D03*
X1581791D03*
X1585531D03*
X1589271D03*
X1585531Y1121948D03*
X1593011D03*
X1589271D03*
X1581791D03*
X1585531Y1211712D03*
Y1215452D03*
X1581791D03*
X1593012Y1211712D03*
X1585531Y1207972D03*
X1589271D03*
X1593011D03*
X1596752Y1125688D03*
X1600492D03*
X1600590Y1132677D03*
X1600492Y1121948D03*
X1607972D03*
X1611712D03*
X1596752D03*
X1607972Y1211712D03*
X1596752D03*
X1600492Y1215452D03*
Y1211712D03*
Y1207972D03*
X1611712Y1211712D03*
Y1207972D03*
X1607972D03*
X1596752D03*
X1607972Y1200491D03*
X1611712D03*
X1596752D03*
X1600492D03*
Y1204232D03*
X1596752D03*
X1607972D03*
X1611712D03*
X1596752Y1129429D03*
X1600492D03*
X1607972D03*
X1611712D03*
Y1125688D03*
X1607972D03*
X1615452Y1129429D03*
X1619193D03*
X1622933D03*
X1626673D03*
Y1125688D03*
X1622933D03*
X1619193D03*
X1615452D03*
Y1121948D03*
X1619193D03*
X1622933D03*
X1626673D03*
X1622933Y1211711D03*
X1619192D03*
X1626673Y1215452D03*
X1619192Y1215451D03*
X1622933Y1215452D03*
X1615452Y1207972D03*
Y1211712D03*
X1626673Y1207972D03*
Y1211712D03*
X1622933Y1207972D03*
X1619193D03*
X1626673Y1200491D03*
X1615452D03*
X1619193D03*
X1622933D03*
Y1204232D03*
X1626673D03*
X1615452D03*
X1619193D03*
X1634153Y1129429D03*
X1637893D03*
X1630413D03*
X1637893Y1125688D03*
X1634153D03*
X1630413D03*
X1641633Y1129429D03*
Y1125688D03*
Y1121948D03*
X1630413D03*
X1634153D03*
X1637893D03*
X1634153Y1215452D03*
X1637893D03*
X1630413D03*
X1641633Y1207972D03*
X1630413Y1211712D03*
X1637893D03*
Y1207972D03*
X1634153Y1211712D03*
X1630413Y1207972D03*
X1634153D03*
X1641633Y1211712D03*
X1634153Y1200491D03*
X1637893D03*
X1630413D03*
X1641633D03*
X1637893Y1204232D03*
X1634153D03*
X1630413D03*
X1641633D03*
X1652854Y1140649D03*
X1649114Y1129429D03*
X1645374Y1121948D03*
X1649114D03*
X1652854Y1200491D03*
X1656594Y1204232D03*
Y1200491D03*
Y1196751D03*
X1660334D03*
X1652854Y1193011D03*
Y1196751D03*
X1660334Y1193011D03*
Y1200491D03*
Y1204232D03*
X1652854D03*
X1656594Y1193011D03*
X1645374Y1204232D03*
Y1178051D03*
X1656594D03*
X1660334Y1181791D03*
Y1189271D03*
X1656594Y1174310D03*
X1649114D03*
X1656594Y1189271D03*
X1652854D03*
X1649114Y1178051D03*
X1645374Y1174310D03*
X1660334Y1185531D03*
Y1178051D03*
Y1174310D03*
X1656594Y1185531D03*
X1649114Y1181791D03*
X1652854Y1174310D03*
Y1178051D03*
X1656594Y1181791D03*
X1652854Y1185531D03*
X1656594Y1159350D03*
Y1166830D03*
Y1170570D03*
X1652854Y1166830D03*
Y1170570D03*
X1660334Y1159350D03*
Y1170570D03*
Y1166830D03*
X1652854Y1159350D03*
X1656594Y1144389D03*
Y1148129D03*
X1652854Y1144389D03*
X1660334Y1148129D03*
X1656594Y1155610D03*
X1660334Y1144389D03*
Y1155610D03*
Y1151869D03*
X1656594D03*
X1652854D03*
Y1155610D03*
Y1148129D03*
X1656594Y1136909D03*
Y1140649D03*
Y1133169D03*
X1645374Y1125688D03*
X1649114D03*
X1652854Y1136909D03*
X1649114Y1133169D03*
Y1207972D03*
X1656594D03*
Y1215452D03*
X1645374Y1211712D03*
X1656594D03*
X1652854Y1215452D03*
X1649114D03*
X1645374D03*
X1652854Y1211712D03*
X1660334D03*
Y1215452D03*
Y1207972D03*
X1645374D03*
X1649114Y1211712D03*
Y1204232D03*
Y1200491D03*
X1665945Y1194881D03*
X1671555Y1189271D03*
X1667815D03*
X1664074Y1181791D03*
X1667815D03*
Y1174310D03*
X1671555D03*
Y1178051D03*
Y1181791D03*
Y1185531D03*
X1664074Y1174310D03*
Y1189271D03*
X1667815Y1170570D03*
X1664075D03*
X1671555Y1166830D03*
Y1170570D03*
X1664074Y1166830D03*
X1667815D03*
X1671555Y1159350D03*
X1667815D03*
X1664074D03*
X1664075Y1155610D03*
Y1148129D03*
X1667815Y1155610D03*
Y1144389D03*
X1664074D03*
X1671555D03*
Y1148129D03*
Y1151869D03*
Y1155610D03*
X1664074Y1151869D03*
X1667815D03*
X1606102Y1221062D03*
X1617322D03*
X1529429Y1106988D03*
X1525689Y1118208D03*
X1521949D03*
X1525689Y1110728D03*
X1518208Y1118208D03*
X1529429D03*
X1521949Y1114468D03*
X1525689D03*
X1529429D03*
Y1110728D03*
X1533169Y1114468D03*
X1536909D03*
X1533169Y1103247D03*
Y1099507D03*
X1536909Y1095767D03*
X1533169Y1106988D03*
X1536909D03*
Y1103247D03*
Y1099507D03*
X1533169Y1095767D03*
X1536909Y1092027D03*
Y1077066D03*
X1533169Y1084547D03*
Y1080807D03*
Y1092027D03*
Y1088287D03*
X1536909D03*
Y1084547D03*
Y1080807D03*
X1533169Y1077066D03*
X1536909Y1073326D03*
X1533169D03*
X1540649Y1114468D03*
X1533169Y1110728D03*
X1536909D03*
X1544389Y1114468D03*
X1533169Y1118208D03*
X1536909D03*
X1540649D03*
X1544389D03*
X1548130D03*
X1551870D03*
X1555610D03*
X1559350D03*
X1563090D03*
X1548130Y1114468D03*
X1551870D03*
X1563090D03*
X1555610D03*
X1559350D03*
X1566830Y1118208D03*
X1570571D03*
X1566830Y1114468D03*
X1578051D03*
X1570571D03*
X1574311D03*
Y1118208D03*
X1578051D03*
X1581791D03*
Y1114468D03*
X1593012D03*
X1593011Y1118208D03*
X1589271D03*
X1585531D03*
X1611712Y1114468D03*
X1607972Y1118208D03*
X1611712D03*
X1607972Y1114468D03*
X1596752D03*
Y1118208D03*
X1600492Y1114468D03*
Y1118208D03*
X1622933D03*
X1626673D03*
Y1114468D03*
X1622933D03*
X1619193D03*
X1615452D03*
X1619193Y1118208D03*
X1615452D03*
X1630413D03*
X1634153D03*
X1641633Y1114468D03*
X1630413D03*
X1634153D03*
X1637893D03*
Y1118208D03*
X1641633D03*
X1656594Y1114468D03*
X1649114D03*
X1645374D03*
X1652854D03*
Y1118208D03*
X1656594D03*
X1649114D03*
X1645374D03*
X1518208Y1099507D03*
X1521949Y1095767D03*
Y1073326D03*
X1521948Y1077066D03*
X1518208D03*
Y1080806D03*
X1521949Y1080807D03*
Y1084547D03*
X1518208D03*
X1521949Y1088287D03*
X1518208Y1092027D03*
X1521949D03*
X1518208Y1088287D03*
Y1103247D03*
Y1095767D03*
X1521949Y1099507D03*
X1514468Y1084547D03*
Y1092027D03*
Y1088287D03*
Y1095767D03*
Y1103247D03*
Y1099507D03*
Y1106988D03*
X1693996Y1151870D03*
X1697736D03*
X1693996Y1144389D03*
X1697736D03*
Y1159350D03*
X1693996D03*
X1697736Y1174310D03*
X1693996Y1189271D03*
X1697736D03*
Y1181791D03*
X1693996D03*
Y1174310D03*
X1686515Y1193011D03*
X1682775D03*
X1679035Y1151869D03*
Y1144389D03*
X1682775Y1148129D03*
X1686515Y1155610D03*
Y1148129D03*
X1682775Y1155610D03*
X1679035Y1166830D03*
X1686515Y1170570D03*
X1682775D03*
X1679035Y1181791D03*
Y1189271D03*
Y1174310D03*
X1686515Y1185531D03*
X1682775Y1178051D03*
X1686515D03*
X1682775Y1185531D03*
X1523819Y1232283D03*
Y1236023D03*
X1531299D03*
Y1232283D03*
X1538779D03*
Y1236023D03*
X1546259Y1232283D03*
Y1236023D03*
Y1250984D03*
Y1254724D03*
X1550000Y1243503D03*
Y1247243D03*
X1561220Y1236023D03*
Y1232283D03*
X1553740D03*
Y1236023D03*
X1557480Y1243503D03*
Y1247243D03*
X1561220Y1254724D03*
Y1250984D03*
X1564960Y1247243D03*
Y1243503D03*
X1553740Y1250984D03*
Y1254724D03*
X1568700Y1232283D03*
Y1236023D03*
Y1250984D03*
Y1254724D03*
X1632283Y1247243D03*
Y1243503D03*
X1636023Y1236023D03*
Y1232283D03*
X1643504Y1236023D03*
Y1232283D03*
X1636023Y1254724D03*
Y1250984D03*
X1639763Y1243503D03*
Y1247243D03*
X1643504Y1250984D03*
Y1254724D03*
X1647244Y1247243D03*
Y1243503D03*
X1658464Y1232283D03*
Y1236023D03*
X1650984D03*
Y1232283D03*
X1654724Y1247243D03*
X1658464Y1254724D03*
Y1250984D03*
X1654724Y1243503D03*
X1650984Y1254724D03*
Y1250984D03*
G54D62*
X970071Y1365652D03*
G54D50*
X881370Y883086D03*
X919163D03*
X922313D03*
X925462D03*
X928612D03*
X881370Y886236D03*
X922313D03*
X925462D03*
X928612D03*
X884585Y886354D03*
X884519Y848442D03*
X887669D03*
Y851592D03*
X884519D03*
X890818Y854742D03*
X887669D03*
X884519D03*
X897118Y857891D03*
X887669D03*
X884519D03*
X897118Y864189D03*
X887669D03*
X884519Y867338D03*
X887669D03*
X890818Y870488D03*
X884519D03*
X887669D03*
X884519Y873638D03*
X887669D03*
X884519Y876787D03*
X916014D03*
X912864D03*
X909714D03*
Y873638D03*
Y870488D03*
X906565Y873638D03*
Y870488D03*
Y867338D03*
X900267Y873638D03*
Y870488D03*
Y867338D03*
Y864189D03*
X897118Y876787D03*
Y873638D03*
Y870488D03*
Y867338D03*
X893968Y876787D03*
X890818Y873638D03*
Y876787D03*
X887669D03*
X922313Y842143D03*
X909714Y854742D03*
X919163Y857891D03*
X906565D03*
X909714D03*
X922313D03*
X906565Y864189D03*
X909714D03*
X922313D03*
X916014D03*
X909714Y867338D03*
X916014D03*
Y870488D03*
X919163D03*
X922313D03*
Y873638D03*
X919163D03*
X916014D03*
X922313Y876787D03*
X919163D03*
Y842143D03*
X916014D03*
X912864Y848442D03*
Y845293D03*
Y842143D03*
X909714Y845293D03*
Y842143D03*
Y848442D03*
X906565D03*
Y854742D03*
Y842143D03*
X900267Y848442D03*
Y857891D03*
Y854742D03*
Y842143D03*
Y845293D03*
X897118Y848442D03*
Y854742D03*
Y845293D03*
X893968D03*
Y842143D03*
X890818Y845293D03*
Y842143D03*
X887669Y845293D03*
X919163Y838994D03*
Y835844D03*
X928612D03*
X925462Y851592D03*
X928612Y876787D03*
X925462D03*
X928612Y873638D03*
X925462Y870488D03*
X928612D03*
X925462Y873638D03*
X900266Y835844D03*
X906565Y845293D03*
X900267Y838992D03*
X906565Y838994D03*
X909714D03*
Y851592D03*
X912864D03*
Y864189D03*
Y857891D03*
Y854742D03*
Y870488D03*
Y867338D03*
X890818Y848442D03*
X881370D03*
X887669Y842143D03*
X884519D03*
X881370Y845293D03*
X884519D03*
X893968Y848442D03*
Y835846D03*
X886093Y835318D03*
X881370Y835844D03*
Y851592D03*
X893967Y851591D03*
X890818Y851592D03*
X893968Y864189D03*
Y857891D03*
Y854742D03*
X881370Y876787D03*
Y870488D03*
Y867338D03*
X893968Y870488D03*
Y873638D03*
Y867338D03*
X878220Y835844D03*
Y845293D03*
Y848442D03*
Y851592D03*
X877800Y876500D03*
X893968Y838994D03*
X897118Y842143D03*
X929611Y858669D03*
X925462Y845293D03*
Y857891D03*
X928612Y864189D03*
X919163Y867338D03*
Y864189D03*
X922313Y867338D03*
X925462D03*
Y864189D03*
X919163Y845293D03*
X916014Y848442D03*
X922313Y851592D03*
X916014D03*
Y845293D03*
X922313D03*
X919163Y854742D03*
X922313D03*
X1320055Y886562D03*
X1323205D03*
Y883413D03*
X1326355D03*
X1323205Y880263D03*
X1320055D03*
X1326355D03*
X1329504D03*
X1320055Y877114D03*
X1323205D03*
X1329504D03*
X1332654D03*
X1326355D03*
X1320055Y873964D03*
X1323204Y873965D03*
X1326355Y873964D03*
X1329504D03*
X1332654D03*
Y883413D03*
Y880263D03*
X1329504Y886562D03*
X1326355D03*
X1329504Y883413D03*
X1316906D03*
X1320055Y889712D03*
X1323204Y889713D03*
X1326355Y889712D03*
G54D48*
X1030635Y774546D03*
Y784546D03*
Y794546D03*
Y804546D03*
Y814546D03*
G54D38*
X909360Y230906D03*
Y274606D03*
G54D44*
X286250Y374862D03*
X1200423D03*
X183435Y630650D03*
X640522D03*
X1097608D03*
G54D51*
X885126Y889742D03*
X169389Y1155610D03*
X165649Y1151870D03*
X330800Y1174500D03*
X622736Y1151870D03*
Y1159350D03*
X792277Y1173065D03*
X787887Y1174500D03*
X792382Y1191664D03*
X1079822Y1151870D03*
X1083562Y1155610D03*
X1074650Y1070006D03*
X1536909Y1159350D03*
Y1151870D03*
G54D45*
X190325Y374862D03*
X1104498D03*
X279360Y630650D03*
X736447D03*
X1193533D03*
G54D69*
X1638101Y421555D03*
X1667116D03*
G54D49*
X1030635Y824546D03*
G54D42*
X743337Y374862D03*
G54D64*
X923336Y226772D03*
G54D61*
X525630Y1463741D03*
X534292Y1468071D03*
Y1462953D03*
Y1498780D03*
X525630Y1576339D03*
Y1581457D03*
X534292Y1493662D03*
X525630Y1566103D03*
Y1560985D03*
X534292Y1514134D03*
Y1509016D03*
X525630Y1504685D03*
Y1509804D03*
Y1494449D03*
Y1489331D03*
X534292Y1483426D03*
Y1478308D03*
X525630Y1479095D03*
Y1473977D03*
Y1458622D03*
X707520Y1452717D03*
Y1462953D03*
Y1468071D03*
Y1478308D03*
Y1483426D03*
Y1493662D03*
Y1498780D03*
Y1509016D03*
Y1514134D03*
Y1565315D03*
Y1570434D03*
Y1580670D03*
X1209803Y1452717D03*
X1201141Y1458622D03*
Y1463741D03*
X1209803Y1462953D03*
Y1468071D03*
X1201141Y1473977D03*
Y1479095D03*
X1209803Y1478308D03*
Y1483426D03*
X1201141Y1489331D03*
Y1494449D03*
X1209803Y1493662D03*
Y1498780D03*
X1201141Y1504685D03*
Y1509804D03*
X1209803Y1509016D03*
Y1514134D03*
X1201141Y1560985D03*
Y1566103D03*
X1209803Y1565315D03*
Y1570434D03*
X1201141Y1576339D03*
Y1581457D03*
X1209803Y1580670D03*
Y1585788D03*
X1201141Y1591693D03*
Y1596811D03*
X1209803Y1596024D03*
Y1601142D03*
X1201141Y1607048D03*
Y1612166D03*
X1209803Y1611378D03*
Y1616496D03*
X1192480Y1452717D03*
X1175157D03*
X1157834D03*
X1140511D03*
X1547598Y1458622D03*
Y1463741D03*
X1556260Y1462953D03*
Y1468071D03*
X1547598Y1473977D03*
Y1479095D03*
X1556260Y1478308D03*
Y1483426D03*
X1547598Y1489331D03*
Y1494449D03*
X1556260Y1493662D03*
Y1498780D03*
X1547598Y1504685D03*
Y1509804D03*
X1556260Y1509016D03*
Y1514134D03*
X1512953Y1622402D03*
X1478307D03*
X1383032Y1565315D03*
Y1570434D03*
X1374370Y1576339D03*
Y1581457D03*
X1383032Y1580670D03*
Y1585788D03*
X1374370Y1591693D03*
Y1596811D03*
X1383032Y1596024D03*
Y1601142D03*
X1374370Y1607048D03*
Y1612166D03*
X1383032Y1611378D03*
Y1616496D03*
X1374370Y1622402D03*
X1729488Y1493662D03*
Y1498780D03*
Y1509016D03*
Y1452717D03*
Y1462953D03*
Y1468071D03*
Y1478308D03*
Y1483426D03*
Y1514134D03*
G54D47*
X515504Y701351D03*
G54D43*
X647412Y374862D03*
G54D60*
X153405Y144095D03*
X255767D03*
X358129D03*
X508130D03*
X610492D03*
X815217Y144095D03*
X965217D03*
X1067579D03*
X1169941D03*
X1272302Y144095D03*
X1422303D03*
X1524665D03*
X1627028Y144095D03*
X1729390D03*
G54D66*
X1554695Y630650D03*
G54D53*
X632086Y1075196D03*
X639567D03*
X647047D03*
X654527D03*
X662008D03*
X669488D03*
X676968D03*
X632086Y1078936D03*
X639567D03*
X647047D03*
X654527D03*
X662008D03*
X669488D03*
X676968D03*
X635827Y1082677D03*
X643307D03*
X650787D03*
X658268D03*
X665748D03*
X673228D03*
X680709D03*
X635827Y1086417D03*
X643307D03*
X650787D03*
X658268D03*
X665748D03*
X673228D03*
X680709D03*
X186220Y1247243D03*
Y1243503D03*
X189960Y1254724D03*
X178740Y1247243D03*
X182480Y1250984D03*
X171259Y1247243D03*
X174999Y1250984D03*
X171259Y1243503D03*
X178740D03*
X182480Y1254724D03*
X174999D03*
X171259Y1198621D03*
X174999Y1206102D03*
X171259Y1213582D03*
X174999D03*
Y1191141D03*
X171259D03*
X174999Y1198621D03*
X171259Y1206102D03*
X152559Y1250984D03*
X156299Y1243503D03*
Y1247243D03*
X163779Y1243503D03*
X160039Y1250984D03*
X163779Y1247243D03*
X167519Y1250984D03*
X152559Y1254724D03*
X167519D03*
X160039D03*
X167519Y1209842D03*
X163779D03*
Y1217322D03*
X167519D03*
X152559D03*
X160039Y1236023D03*
X163779Y1224803D03*
X156299D03*
X167519Y1232283D03*
X156299Y1228543D03*
X163779D03*
X167519Y1236023D03*
X160039Y1232283D03*
X152559Y1236023D03*
Y1232283D03*
X156299Y1202362D03*
Y1194881D03*
X152559Y1202362D03*
Y1194881D03*
X163779D03*
Y1202362D03*
X167519Y1194881D03*
Y1202362D03*
X156299Y1217322D03*
Y1209842D03*
X152559D03*
X148818Y1239763D03*
X145078D03*
Y1198621D03*
X148818D03*
X145078Y1206102D03*
X148818D03*
X145078Y1221062D03*
X148818D03*
Y1213582D03*
X145078D03*
Y1228543D03*
X148818D03*
Y1247243D03*
X145078D03*
Y1191141D03*
X148818D03*
X219881Y1078936D03*
X223622Y1082677D03*
Y1086417D03*
X219881Y1075196D03*
X208661Y1082677D03*
X216141Y1086417D03*
X201181Y1082677D03*
X216141D03*
X201181Y1086417D03*
X208661D03*
X204921Y1078936D03*
Y1075196D03*
X212401D03*
Y1078936D03*
X186220Y1082677D03*
Y1086417D03*
X189960Y1078936D03*
X193700Y1086417D03*
Y1082677D03*
X197440Y1078936D03*
X189960Y1075196D03*
X197440D03*
X174999Y1078936D03*
X182480D03*
X178740Y1082677D03*
Y1086417D03*
X174999Y1075196D03*
X182480D03*
X283464Y1243503D03*
Y1247243D03*
X287204Y1250984D03*
Y1254724D03*
X279724Y1232283D03*
Y1236023D03*
X287204Y1232283D03*
X283464Y1224803D03*
Y1228543D03*
X287204Y1236023D03*
X268503Y1228543D03*
X264763Y1236023D03*
X268503Y1243503D03*
X275984D03*
Y1247243D03*
X264763Y1232283D03*
X268503Y1224803D03*
X275984D03*
X272244Y1236023D03*
X275984Y1228543D03*
X272244Y1232283D03*
X261023Y1224803D03*
X253543Y1228543D03*
X249803Y1232283D03*
X246062Y1228543D03*
X257283Y1232283D03*
Y1236023D03*
X246062Y1224803D03*
X261023Y1228543D03*
X253543Y1224803D03*
X249803Y1236023D03*
X238582Y1224803D03*
Y1228543D03*
X242322Y1236023D03*
Y1232283D03*
X234842D03*
Y1236023D03*
X231102Y1228543D03*
Y1224803D03*
X665748D03*
X658268D03*
X688189D03*
X680709D03*
X673228D03*
X703149D03*
X695669D03*
X710630D03*
X748031D03*
X755512Y1213582D03*
Y1206102D03*
Y1198621D03*
X751772Y1213582D03*
Y1206102D03*
Y1198621D03*
X770472Y1243503D03*
Y1247243D03*
X774212Y1254724D03*
Y1250984D03*
X777953Y1247243D03*
X781693D03*
X777953Y1239763D03*
X781693D03*
X669488Y1236023D03*
Y1232283D03*
X662008D03*
Y1236023D03*
X669488Y1254724D03*
Y1250984D03*
X665748Y1243503D03*
Y1247243D03*
X662008Y1250984D03*
Y1254724D03*
X658268Y1247243D03*
Y1243503D03*
X676968Y1232283D03*
Y1236023D03*
X684449Y1232283D03*
Y1236023D03*
Y1254724D03*
Y1250984D03*
X688189Y1247243D03*
Y1243503D03*
X680709D03*
Y1247243D03*
X676968Y1250984D03*
Y1254724D03*
X673228Y1247243D03*
Y1243503D03*
X699409Y1236023D03*
Y1232283D03*
X691929D03*
Y1236023D03*
X703149Y1243503D03*
Y1247243D03*
X699409Y1254724D03*
Y1250984D03*
X695669Y1243503D03*
Y1247243D03*
X691929Y1250984D03*
Y1254724D03*
X714370Y1236023D03*
Y1232283D03*
X706890D03*
Y1236023D03*
X714370Y1254724D03*
Y1250984D03*
X710630Y1247243D03*
Y1243503D03*
X706890Y1250984D03*
Y1254724D03*
X748031Y1247243D03*
Y1243503D03*
X770472Y1224803D03*
Y1228543D03*
X777953D03*
X781693D03*
X774212Y1232283D03*
Y1236023D03*
X781693Y1213582D03*
X777953D03*
X781693Y1221062D03*
X777953D03*
X774212Y1217322D03*
X770472D03*
Y1209842D03*
X774212D03*
X781693Y1198621D03*
X777953D03*
X774212Y1202362D03*
X770472D03*
X777953Y1206102D03*
X781693D03*
X762992Y1243503D03*
Y1247243D03*
X766732Y1250984D03*
Y1254724D03*
X759252D03*
Y1250984D03*
X755512Y1247243D03*
Y1243503D03*
X762992Y1224803D03*
Y1228543D03*
X759252Y1232283D03*
Y1236023D03*
X766732D03*
Y1232283D03*
X751772Y1250984D03*
Y1254724D03*
Y1236023D03*
Y1232283D03*
X1149015Y1236023D03*
Y1232283D03*
X1152755Y1224803D03*
X1156495Y1232283D03*
Y1236023D03*
X1152755Y1228543D03*
X1145275Y1224803D03*
Y1228543D03*
X1163976Y1236023D03*
Y1232283D03*
X1167716Y1228543D03*
Y1224803D03*
X1175196D03*
Y1228543D03*
X1171456Y1232283D03*
Y1236023D03*
X1160235Y1224803D03*
Y1228543D03*
X1178936Y1236023D03*
Y1232283D03*
X1182676Y1224803D03*
Y1228543D03*
X1186417Y1236023D03*
Y1232283D03*
X1190157Y1228543D03*
Y1224803D03*
X1197637D03*
Y1228543D03*
X1201377Y1232283D03*
Y1236023D03*
X1193897D03*
Y1232283D03*
X1089172Y1075196D03*
Y1078936D03*
X1092913Y1086417D03*
Y1082677D03*
X1104133Y1075196D03*
X1096653D03*
X1104133Y1078936D03*
X1107873Y1082677D03*
Y1086417D03*
X1100393D03*
Y1082677D03*
X1096653Y1078936D03*
X1126574Y1075196D03*
X1119094D03*
X1111613D03*
X1126574Y1078936D03*
X1122834Y1086417D03*
Y1082677D03*
X1119094Y1078936D03*
X1115354Y1086417D03*
Y1082677D03*
X1111613Y1078936D03*
X1134054Y1075196D03*
X1137795Y1086417D03*
Y1082677D03*
X1134054Y1078936D03*
X1130314Y1082677D03*
Y1086417D03*
X1070472Y1209842D03*
X1066732D03*
Y1217322D03*
X1070472D03*
X1062991Y1213582D03*
X1081692Y1187401D03*
Y1194881D03*
Y1202362D03*
Y1217322D03*
Y1209842D03*
X1089172Y1191141D03*
X1085432D03*
Y1198621D03*
X1089172D03*
X1085432Y1206102D03*
X1089172D03*
X1059251Y1221062D03*
Y1228543D03*
X1062991Y1221062D03*
X1070472Y1224803D03*
Y1228543D03*
X1077952Y1224803D03*
Y1228543D03*
X1066732Y1232283D03*
Y1236023D03*
X1074212D03*
Y1232283D03*
X1062991Y1228543D03*
X1077952Y1243503D03*
Y1247243D03*
X1074212Y1250984D03*
Y1254724D03*
X1066732D03*
Y1250984D03*
X1070472Y1247243D03*
Y1243503D03*
X1062991Y1247243D03*
Y1239763D03*
X1085432Y1213582D03*
X1089172D03*
X1081692Y1232283D03*
Y1236023D03*
X1089172Y1250984D03*
Y1254724D03*
X1081692D03*
Y1250984D03*
X1085432Y1247243D03*
Y1243503D03*
X1092913D03*
Y1247243D03*
X1100393Y1243503D03*
Y1247243D03*
X1104133Y1254724D03*
Y1250984D03*
X1107873Y1243503D03*
X1096653Y1250984D03*
Y1254724D03*
X1059251Y1239763D03*
Y1191141D03*
Y1198621D03*
Y1206102D03*
Y1213582D03*
X1077952Y1187401D03*
X1070472D03*
X1066732D03*
X1077952Y1194881D03*
Y1202362D03*
X1066732Y1194881D03*
X1070472D03*
X1066732Y1202362D03*
X1070472D03*
X1062991Y1191141D03*
Y1198621D03*
Y1206102D03*
X1077952Y1217322D03*
Y1209842D03*
X1059251Y1247243D03*
X1182676D03*
X1186417Y1250984D03*
Y1254724D03*
X1190157Y1247243D03*
X1197637D03*
X1201377Y1254724D03*
Y1250984D03*
X1193897Y1254724D03*
Y1250984D03*
X1557480Y1086417D03*
Y1082677D03*
X1553740Y1078936D03*
X1583661Y1075196D03*
X1576181D03*
X1568700D03*
X1583661Y1078936D03*
X1579921Y1086417D03*
Y1082677D03*
X1576181Y1078936D03*
X1572441Y1086417D03*
Y1082677D03*
X1568700Y1078936D03*
X1591141Y1075196D03*
X1594882Y1086417D03*
Y1082677D03*
X1591141Y1078936D03*
X1587401Y1082677D03*
Y1086417D03*
X1546259Y1078936D03*
X1550000Y1086417D03*
Y1082677D03*
X1561220Y1075196D03*
X1553740D03*
X1561220Y1078936D03*
X1564960Y1082677D03*
Y1086417D03*
X1546259Y1075196D03*
X1662204Y1224803D03*
X1617322D03*
X1624803D03*
X1602362D03*
X1609842D03*
X1594882D03*
X1587401D03*
X1579921D03*
X1572441D03*
X1669685Y1198621D03*
Y1206102D03*
X1665945Y1213582D03*
X1669685D03*
X1665945Y1198621D03*
X1695866Y1213582D03*
X1692126D03*
X1695866Y1221062D03*
X1692126D03*
X1688385Y1217322D03*
X1684645D03*
Y1209842D03*
X1688385D03*
X1695866Y1198621D03*
X1692126D03*
X1688385Y1202362D03*
X1684645D03*
X1692126Y1206102D03*
X1695866D03*
Y1239763D03*
X1692126D03*
X1695866Y1247243D03*
X1692126D03*
X1688385Y1250984D03*
Y1254724D03*
X1684645Y1247243D03*
Y1243503D03*
X1665945Y1250984D03*
Y1254724D03*
X1684645Y1228543D03*
X1692126D03*
X1695866D03*
X1688385Y1232283D03*
Y1236023D03*
X1576181D03*
Y1232283D03*
X1583661D03*
Y1236023D03*
X1572441Y1243503D03*
Y1247243D03*
X1576181Y1254724D03*
Y1250984D03*
X1579921Y1247243D03*
Y1243503D03*
X1583661Y1250984D03*
Y1254724D03*
X1598622Y1236023D03*
Y1232283D03*
X1591141Y1236023D03*
Y1232283D03*
X1587401Y1243503D03*
Y1247243D03*
X1591141Y1254724D03*
Y1250984D03*
X1594882Y1247243D03*
Y1243503D03*
X1598622Y1250984D03*
Y1254724D03*
X1606102Y1236023D03*
Y1232283D03*
X1613582D03*
Y1236023D03*
X1606102Y1254724D03*
Y1250984D03*
X1609842Y1247243D03*
Y1243503D03*
X1613582Y1250984D03*
Y1254724D03*
X1602362Y1243503D03*
Y1247243D03*
X1621063Y1236023D03*
Y1232283D03*
X1628543D03*
Y1236023D03*
X1621063Y1254724D03*
Y1250984D03*
X1624803Y1243503D03*
Y1247243D03*
X1628543Y1250984D03*
Y1254724D03*
X1617322Y1247243D03*
Y1243503D03*
X1662204D03*
Y1247243D03*
X1677165Y1224803D03*
Y1228543D03*
X1673425Y1232283D03*
Y1236023D03*
X1680905D03*
Y1232283D03*
X1665945Y1236023D03*
Y1232283D03*
X1677165Y1243503D03*
Y1247243D03*
X1680905Y1250984D03*
Y1254724D03*
X1673425D03*
Y1250984D03*
X1669685Y1247243D03*
Y1243503D03*
G54D65*
X1650620Y630650D03*
X1561585Y374862D03*
G54D58*
X51043Y144095D03*
X712854D03*
G54D70*
X1817323Y56693D03*
G54D39*
X893284Y235040D03*
X899352Y310261D03*
X917882Y326517D03*
X463950Y334359D03*
X460950Y342233D03*
X463950Y350107D03*
X212980Y392695D03*
X205680Y399782D03*
X212980Y406868D03*
X205680Y413955D03*
X212980Y421041D03*
X205680Y428128D03*
X212980Y435215D03*
X205680Y442302D03*
X1209184Y461917D03*
X721092Y469037D03*
X1178178D03*
X212980Y471081D03*
X713792Y476124D03*
X1170878D03*
X205680Y478168D03*
X721092Y483210D03*
X1178178D03*
X212980Y485254D03*
X713792Y490297D03*
X1170878D03*
X205680Y492341D03*
X721092Y513171D03*
X1178178D03*
X212980Y515215D03*
X713792Y520258D03*
X1170878D03*
X205680Y522302D03*
X721092Y527344D03*
X1178178D03*
X212980Y529388D03*
X713792Y534431D03*
X1170878D03*
X205680Y536475D03*
X1089096Y543562D03*
X721092Y563210D03*
X1178178D03*
X713792Y570297D03*
X1170878D03*
X721092Y577384D03*
X1178178D03*
X713792Y584471D03*
X1170878D03*
X721092Y591557D03*
X1178178D03*
X713792Y598644D03*
X1170878D03*
X721092Y605730D03*
X1178178D03*
X713792Y612817D03*
X1170878D03*
X559070Y686509D03*
X561570Y694509D03*
X559070Y702509D03*
X561570Y710509D03*
X533092Y127096D03*
Y112923D03*
X543494Y134209D03*
Y120035D03*
X635454Y127096D03*
Y112923D03*
X645856Y134209D03*
Y120035D03*
X748218Y134209D03*
X737816Y127096D03*
X748218Y120035D03*
X737816Y112923D03*
X840178Y127096D03*
Y112923D03*
X850580Y134209D03*
Y120035D03*
X990178Y127096D03*
Y112923D03*
X1000580Y134209D03*
Y120035D03*
X1092540Y112923D03*
Y127096D03*
X1102942Y134209D03*
Y120035D03*
X1205304Y134209D03*
X1194902Y127096D03*
X1205304Y120035D03*
X1194902Y112923D03*
X1297264Y127096D03*
Y112923D03*
X1307666Y134209D03*
Y120035D03*
X1576940Y442302D03*
Y413955D03*
Y428128D03*
Y399782D03*
X1584240Y435215D03*
Y421041D03*
Y406868D03*
Y392695D03*
X1576940Y478168D03*
X1584240Y471081D03*
X1576940Y492341D03*
Y536475D03*
Y522302D03*
X1584240Y529388D03*
Y515215D03*
Y485254D03*
X1754906Y822634D03*
G54D55*
X213969Y1460153D03*
Y1449153D03*
X227249Y1460153D03*
Y1449153D03*
G54D68*
X1766929Y333464D03*
G54D67*
X1817323Y1567323D03*
G54D40*
X1080351Y329955D03*
X940997Y333613D03*
X670067Y392695D03*
X1127153D03*
X662767Y399782D03*
X1119853D03*
X670067Y406868D03*
X1127153D03*
X662767Y413955D03*
X1119853D03*
X670067Y421041D03*
X1127153D03*
X662767Y428128D03*
X1119853D03*
X670067Y435215D03*
X1127153D03*
X662767Y442302D03*
X1119853D03*
X295011Y461917D03*
X752097D03*
X264005Y469037D03*
X670067Y471081D03*
X1127153D03*
X256705Y476124D03*
X662767Y478168D03*
X1119853D03*
X264005Y483210D03*
X670067Y485254D03*
X1127153D03*
X256705Y490297D03*
X662767Y492341D03*
X1119853D03*
X264005Y513171D03*
X670067Y515215D03*
X1127153D03*
X256705Y520258D03*
X662767Y522302D03*
X1119853D03*
X264005Y527344D03*
X670067Y529388D03*
X1127153D03*
X256705Y534431D03*
X662767Y536475D03*
X1119853D03*
X174923Y543562D03*
X632009D03*
X264005Y563210D03*
X256705Y570297D03*
X264005Y577384D03*
X256705Y584471D03*
X264005Y591557D03*
X256705Y598644D03*
X264005Y605730D03*
X256705Y612817D03*
X486837Y703006D03*
X217907Y1428752D03*
X76005Y127096D03*
Y112923D03*
X86407Y134209D03*
Y120035D03*
X178367Y127096D03*
Y112923D03*
X188769Y134209D03*
Y120035D03*
X280729Y112923D03*
Y127096D03*
X291131Y134209D03*
Y120035D03*
X393493Y134209D03*
X383091Y127096D03*
X393493Y120035D03*
X383091Y112923D03*
X415203Y1497818D03*
X385091Y1299153D03*
X454385Y1303545D03*
X1009333Y1344993D03*
X1366535Y353200D03*
Y337452D03*
X1363535Y345326D03*
Y329578D03*
X1546183Y543564D03*
X1627965Y584471D03*
Y570297D03*
Y534431D03*
Y520258D03*
Y490297D03*
Y612817D03*
Y598644D03*
X1635265Y563210D03*
Y527344D03*
Y513171D03*
Y605730D03*
Y591557D03*
Y577384D03*
X1447265Y127096D03*
Y112923D03*
X1457667Y134209D03*
Y120035D03*
X1549627Y127096D03*
X1560029Y134209D03*
X1549627Y112923D03*
X1560029Y120035D03*
X1651989Y127096D03*
Y112923D03*
X1662391Y134209D03*
Y120035D03*
X1754351Y127096D03*
Y112923D03*
X1764753Y120035D03*
Y134209D03*
G54D46*
X820079Y388583D03*
X1020866D03*
G54D41*
X184851Y334492D03*
X26789Y1373669D03*
X1796847Y1517889D03*
X1809883Y120792D03*
G54D56*
X28819Y81575D03*
X233543D03*
X335906D03*
X485886Y81595D03*
X588248Y81594D03*
X690611Y81595D03*
X792973D03*
X942973D03*
X1045335D03*
X1147697D03*
X1250060D03*
X1400060D03*
X1502441Y81575D03*
X1604784Y81595D03*
X1707146D03*
G54D57*
X116731Y1066535D03*
X352952Y1263386D03*
X1030905Y1066535D03*
X1724212Y1263386D03*
G54D63*
X770472Y1490945D03*
G54D54*
X573818Y1066535D03*
X116731Y1263386D03*
X810038D03*
X1030905D03*
X1267125D03*
%LPD*%
G75*
G36*
G01X567118Y829247D02*
X567496Y829327D01*
G02X567679Y829273I42J-195D01*
G01X571735Y825217D01*
G02X571794Y825076I-141J-142D01*
G01Y818672D01*
G02X571668Y818486I-200J0D01*
G01X571448Y818399D01*
G03X571424Y818424I-954J-892D01*
G01X567369Y822478D01*
G02X567324Y822692I142J142D01*
G01X567477Y823089D01*
X567572Y823158D01*
X567632Y823161D01*
G03X569061Y824661I-73J1500D01*
G03X566057I-1502J0D01*
G03X566110Y824266I1502J0D01*
G01X566124Y824214D01*
X566096Y824110D01*
X566058Y824072D01*
G02X565775I-142J142D01*
G01X565665Y824183D01*
G02X565606Y824324I141J142D01*
G01Y827476D01*
G02X565665Y827617I200J-1D01*
G01X566728Y828680D01*
G03X567023Y829134I-924J923D01*
G01X567042Y829182D01*
X567118Y829247D01*
G37*
G36*
G01X728962Y1197968D02*
X729708D01*
G02X729880Y1197870I0J-200D01*
G01X730083Y1197528D01*
X730085Y1197423D01*
X730059Y1197376D01*
G03X729899Y1196751I1141J-625D01*
G03X731201Y1195449I1302J0D01*
G03X732043Y1195758I0J1302D01*
G01X732088Y1195796D01*
X732203Y1195812D01*
X732586Y1195635D01*
G02X732702Y1195453I-84J-182D01*
G01Y1184953D01*
G02X732643Y1184811I-200J0D01*
G01X731369Y1183537D01*
G02X731227Y1183478I-142J141D01*
G01X726036D01*
G03X725894Y1183419I0J-200D01*
G01X725807Y1183332D01*
G03X725748Y1183190I141J-142D01*
G01Y1170910D01*
G03X725807Y1170768I200J0D01*
G01X726144Y1170431D01*
X726172Y1170377D01*
X726177Y1170346D01*
G03X727460Y1169268I1283J224D01*
G03X728717Y1170231I0J1302D01*
G01X728735Y1170297D01*
X728842Y1170379D01*
X729819D01*
X729926Y1170297D01*
X729944Y1170231D01*
G03X732458I1257J339D01*
G01X732476Y1170297D01*
X732583Y1170379D01*
X733559D01*
X733666Y1170297D01*
X733684Y1170231D01*
G03X734783Y1169278I1257J339D01*
G01X734859Y1169268D01*
X734959Y1169155D01*
Y1168245D01*
X734859Y1168132D01*
X734783Y1168122D01*
G03Y1165538I158J-1292D01*
G01X734859Y1165528D01*
X734959Y1165415D01*
Y1160765D01*
X734859Y1160652D01*
X734783Y1160642D01*
G03Y1158058I158J-1292D01*
G01X734859Y1158048D01*
X734959Y1157935D01*
Y1157025D01*
X734859Y1156912D01*
X734783Y1156902D01*
G03Y1154318I158J-1292D01*
G01X734859Y1154308D01*
X734959Y1154195D01*
Y1153285D01*
X734859Y1153172D01*
X734783Y1153162D01*
G03Y1150578I158J-1292D01*
G01X734859Y1150568D01*
X734959Y1150455D01*
Y1149544D01*
X734859Y1149431D01*
X734783Y1149421D01*
G03Y1146837I158J-1292D01*
G01X734859Y1146827D01*
X734959Y1146714D01*
Y1145804D01*
X734859Y1145691D01*
X734783Y1145681D01*
G03Y1143097I158J-1292D01*
G01X734859Y1143087D01*
X734959Y1142974D01*
Y1142064D01*
X734859Y1141951D01*
X734783Y1141941D01*
G03Y1139357I158J-1292D01*
G01X734859Y1139347D01*
X734959Y1139234D01*
Y1138324D01*
X734859Y1138211D01*
X734783Y1138201D01*
G03X733639Y1136922I158J-1292D01*
G01Y1136908D01*
G03X733693Y1136537I1302J0D01*
G02X733643Y1136339I-192J-57D01*
G01X732790Y1135486D01*
X732762Y1135457D01*
X732688Y1135427D01*
X728774D01*
G02X728593Y1135541I0J200D01*
G01X728439Y1135868D01*
G02X728465Y1136081I180J86D01*
G03X728762Y1136909I-1006J828D01*
G03X726158I-1302J0D01*
G03X726173Y1136709I1302J-3D01*
G03X726455Y1136080I1287J199D01*
G02X726481Y1135868I-155J-127D01*
G01X726327Y1135541D01*
G02X726146Y1135427I-181J86D01*
G01X725034D01*
G02X724853Y1135542I0J200D01*
G01X724673Y1135922D01*
X724688Y1136036D01*
X724725Y1136081D01*
G03X725022Y1136909I-1006J828D01*
G03X722418I-1302J0D01*
G03X722715Y1136081I1303J0D01*
G01X722752Y1136036D01*
X722767Y1135922D01*
X722587Y1135542D01*
G02X722406Y1135427I-181J85D01*
G01X721294D01*
G02X721113Y1135542I0J200D01*
G01X720933Y1135922D01*
X720948Y1136036D01*
X720985Y1136081D01*
G03X721282Y1136909I-1006J828D01*
G03X718678I-1302J0D01*
G03X718975Y1136081I1303J0D01*
G01X719012Y1136036D01*
X719027Y1135922D01*
X718847Y1135542D01*
G02X718666Y1135427I-181J85D01*
G01X717554D01*
G02X717373Y1135542I0J200D01*
G01X717193Y1135922D01*
X717208Y1136036D01*
X717245Y1136081D01*
G03X717542Y1136909I-1006J828D01*
G03X714938I-1302J0D01*
G03X715235Y1136081I1303J0D01*
G01X715272Y1136036D01*
X715287Y1135922D01*
X715107Y1135542D01*
G02X714926Y1135427I-181J85D01*
G01X713814D01*
G02X713633Y1135542I0J200D01*
G01X713453Y1135922D01*
X713468Y1136036D01*
X713505Y1136081D01*
G03X713802Y1136909I-1006J828D01*
G03X711198I-1302J0D01*
G03X711495Y1136081I1303J0D01*
G01X711532Y1136036D01*
X711547Y1135922D01*
X711367Y1135542D01*
G02X711186Y1135427I-181J85D01*
G01X710074D01*
G02X709893Y1135542I0J200D01*
G01X709713Y1135922D01*
X709728Y1136036D01*
X709765Y1136081D01*
G03X710062Y1136909I-1006J828D01*
G03X707458I-1302J0D01*
G03X707755Y1136081I1303J0D01*
G01X707792Y1136036D01*
X707807Y1135922D01*
X707627Y1135542D01*
G02X707446Y1135427I-181J85D01*
G01X706334D01*
G02X706153Y1135542I0J200D01*
G01X705973Y1135922D01*
X705988Y1136036D01*
X706025Y1136081D01*
G03X706322Y1136909I-1006J828D01*
G03X703718I-1302J0D01*
G03X704015Y1136081I1303J0D01*
G01X704052Y1136036D01*
X704067Y1135922D01*
X703887Y1135542D01*
G02X703706Y1135427I-181J85D01*
G01X702593D01*
G02X702412Y1135542I0J200D01*
G01X702232Y1135922D01*
X702247Y1136036D01*
X702284Y1136081D01*
G03X702581Y1136909I-1006J828D01*
G03X699977I-1302J0D01*
G03X700274Y1136081I1303J0D01*
G01X700311Y1136036D01*
X700326Y1135922D01*
X700146Y1135542D01*
G02X699965Y1135427I-181J85D01*
G01X698853D01*
G02X698672Y1135542I0J200D01*
G01X698492Y1135922D01*
X698507Y1136036D01*
X698544Y1136081D01*
G03X698841Y1136909I-1006J828D01*
G03X696237I-1302J0D01*
G03X696534Y1136081I1303J0D01*
G01X696571Y1136036D01*
X696586Y1135922D01*
X696406Y1135542D01*
G02X696225Y1135427I-181J85D01*
G01X695113D01*
G02X694932Y1135542I0J200D01*
G01X694752Y1135922D01*
X694767Y1136036D01*
X694804Y1136081D01*
G03X695101Y1136909I-1006J828D01*
G03X692497I-1302J0D01*
G03X692794Y1136081I1303J0D01*
G01X692831Y1136036D01*
X692846Y1135922D01*
X692666Y1135542D01*
G02X692485Y1135427I-181J85D01*
G01X687633D01*
G02X687452Y1135542I0J200D01*
G01X687272Y1135922D01*
X687287Y1136036D01*
X687324Y1136081D01*
G03X687621Y1136909I-1006J828D01*
G03X685017I-1302J0D01*
G03X685314Y1136081I1303J0D01*
G01X685351Y1136036D01*
X685366Y1135922D01*
X685186Y1135542D01*
G02X685005Y1135427I-181J85D01*
G01X683893D01*
G02X683712Y1135542I0J200D01*
G01X683532Y1135922D01*
X683547Y1136036D01*
X683584Y1136081D01*
G03X683881Y1136909I-1006J828D01*
G03X681277I-1302J0D01*
G03X681574Y1136081I1303J0D01*
G01X681611Y1136036D01*
X681626Y1135922D01*
X681446Y1135542D01*
G02X681265Y1135427I-181J85D01*
G01X680152D01*
G02X679971Y1135542I0J200D01*
G01X679791Y1135922D01*
X679806Y1136036D01*
X679843Y1136081D01*
G03X680140Y1136909I-1006J828D01*
G03X677536I-1302J0D01*
G03X677833Y1136081I1303J0D01*
G01X677870Y1136036D01*
X677885Y1135922D01*
X677705Y1135542D01*
G02X677524Y1135427I-181J85D01*
G01X676412D01*
G02X676231Y1135542I0J200D01*
G01X676051Y1135922D01*
X676066Y1136036D01*
X676103Y1136081D01*
G03X676400Y1136909I-1006J828D01*
G03X673796I-1302J0D01*
G03X674093Y1136081I1303J0D01*
G01X674130Y1136036D01*
X674145Y1135922D01*
X673965Y1135542D01*
G02X673784Y1135427I-181J85D01*
G01X672672D01*
G02X672491Y1135542I0J200D01*
G01X672311Y1135922D01*
X672326Y1136036D01*
X672363Y1136081D01*
G03X672660Y1136909I-1006J828D01*
G03X670056I-1302J0D01*
G03X670353Y1136081I1303J0D01*
G01X670390Y1136036D01*
X670405Y1135922D01*
X670225Y1135542D01*
G02X670044Y1135427I-181J85D01*
G01X668932D01*
G02X668751Y1135542I0J200D01*
G01X668571Y1135922D01*
X668586Y1136036D01*
X668623Y1136081D01*
G03X668920Y1136909I-1006J828D01*
G03X666316I-1302J0D01*
G03X666613Y1136081I1303J0D01*
G01X666650Y1136036D01*
X666665Y1135922D01*
X666485Y1135542D01*
G02X666304Y1135427I-181J85D01*
G01X665192D01*
G02X665011Y1135542I0J200D01*
G01X664831Y1135922D01*
X664846Y1136036D01*
X664883Y1136081D01*
G03X665180Y1136909I-1006J828D01*
G03X662576I-1302J0D01*
G03X662873Y1136081I1303J0D01*
G01X662910Y1136036D01*
X662925Y1135922D01*
X662745Y1135542D01*
G02X662564Y1135427I-181J85D01*
G01X661452D01*
G02X661271Y1135542I0J200D01*
G01X661091Y1135922D01*
X661106Y1136036D01*
X661143Y1136081D01*
G03X661440Y1136909I-1006J828D01*
G03X658836I-1302J0D01*
G03X659133Y1136081I1303J0D01*
G01X659170Y1136036D01*
X659185Y1135922D01*
X659005Y1135542D01*
G02X658824Y1135427I-181J85D01*
G01X657712D01*
G02X657531Y1135542I0J200D01*
G01X657351Y1135922D01*
X657366Y1136036D01*
X657403Y1136081D01*
G03X657700Y1136909I-1006J828D01*
G03X655096I-1302J0D01*
G03X655393Y1136081I1303J0D01*
G01X655430Y1136036D01*
X655445Y1135922D01*
X655265Y1135542D01*
G02X655084Y1135427I-181J85D01*
G01X654263D01*
G02X654121Y1135486I0J200D01*
G01X653674Y1135933D01*
X653663Y1136079D01*
X653707Y1136139D01*
G03X653959Y1136909I-1050J770D01*
G03X652657Y1138211I-1302J0D01*
G03X651887Y1137959I0J-1302D01*
G01X651827Y1137915D01*
X651681Y1137926D01*
X650458Y1139149D01*
G03X650316Y1139208I-142J-141D01*
G01X650263D01*
G02X650084Y1139320I1J200D01*
G01X649900Y1139694D01*
X649912Y1139807D01*
X649947Y1139853D01*
G03X650219Y1140649I-1029J796D01*
G03X647615I-1302J0D01*
G03X647887Y1139853I1301J0D01*
G01X647922Y1139807D01*
X647934Y1139694D01*
X647750Y1139320D01*
G02X647571Y1139208I-180J88D01*
G01X646523D01*
G02X646344Y1139320I1J200D01*
G01X646160Y1139694D01*
X646172Y1139807D01*
X646207Y1139853D01*
G03X646479Y1140649I-1029J796D01*
G03X643875I-1302J0D01*
G03X644147Y1139853I1301J0D01*
G01X644182Y1139807D01*
X644194Y1139694D01*
X644010Y1139320D01*
G02X643831Y1139208I-180J88D01*
G01X642783D01*
G02X642604Y1139320I1J200D01*
G01X642420Y1139694D01*
X642432Y1139807D01*
X642467Y1139853D01*
G03X642739Y1140649I-1029J796D01*
G03X640135I-1302J0D01*
G03X640407Y1139853I1301J0D01*
G01X640442Y1139807D01*
X640454Y1139694D01*
X640270Y1139320D01*
G02X640091Y1139208I-180J88D01*
G01X639043D01*
G02X638864Y1139320I1J200D01*
G01X638680Y1139694D01*
X638692Y1139807D01*
X638727Y1139853D01*
G03X638999Y1140649I-1029J796D01*
G03X636395I-1302J0D01*
G03X636667Y1139853I1301J0D01*
G01X636702Y1139807D01*
X636714Y1139694D01*
X636530Y1139320D01*
G02X636351Y1139208I-180J88D01*
G01X635303D01*
G02X635124Y1139320I1J200D01*
G01X634940Y1139694D01*
X634952Y1139807D01*
X634987Y1139853D01*
G03X635259Y1140649I-1029J796D01*
G03X632655I-1302J0D01*
G03X632927Y1139853I1301J0D01*
G01X632962Y1139807D01*
X632974Y1139694D01*
X632790Y1139320D01*
G02X632611Y1139208I-180J88D01*
G01X631562D01*
G02X631383Y1139320I1J200D01*
G01X631199Y1139694D01*
X631211Y1139807D01*
X631246Y1139853D01*
G03X631518Y1140649I-1029J796D01*
G03X628914I-1302J0D01*
G03X629186Y1139853I1301J0D01*
G01X629221Y1139807D01*
X629233Y1139694D01*
X629049Y1139320D01*
G02X628870Y1139208I-180J88D01*
G01X627371D01*
G02X627229Y1139267I0J200D01*
G01X627209Y1139287D01*
G02Y1139569I142J141D01*
G01X627221Y1139581D01*
X627234Y1139591D01*
G03X627778Y1140649I-757J1058D01*
G03X626997Y1141842I-1302J0D01*
G01X626942Y1141866D01*
X626877Y1141966D01*
Y1142306D01*
G03X626818Y1142448I-200J0D01*
G01Y1142988D01*
G02X626853Y1143101I200J0D01*
G01X626871Y1143127D01*
X626917Y1143164D01*
X626946Y1143175D01*
G03Y1145603I-470J1214D01*
G01X626917Y1145614D01*
X626871Y1145651D01*
X626853Y1145677D01*
G02X626818Y1145790I165J113D01*
G01Y1146728D01*
G02X626853Y1146841I200J0D01*
G01X626871Y1146867D01*
X626917Y1146904D01*
X626946Y1146915D01*
G03Y1149343I-470J1214D01*
G01X626917Y1149354D01*
X626871Y1149391D01*
X626853Y1149417D01*
G02X626818Y1149530I165J113D01*
G01Y1150469D01*
G02X626853Y1150582I200J0D01*
G01X626871Y1150608D01*
X626917Y1150645D01*
X626946Y1150656D01*
G03Y1153084I-470J1214D01*
G01X626917Y1153095D01*
X626871Y1153132D01*
X626853Y1153158D01*
G02X626818Y1153271I165J113D01*
G01Y1154061D01*
X626893Y1154165D01*
X626954Y1154186D01*
G03Y1157034I-478J1424D01*
G01X626893Y1157055D01*
X626818Y1157159D01*
Y1157949D01*
G02X626853Y1158062I200J0D01*
G01X626871Y1158088D01*
X626917Y1158125D01*
X626946Y1158136D01*
G03Y1160564I-470J1214D01*
G01X626917Y1160575D01*
X626871Y1160612D01*
X626853Y1160638D01*
G02X626818Y1160751I165J113D01*
G01Y1169096D01*
G02X626875Y1169236I200J0D01*
G01X626876Y1169237D01*
X628380Y1170741D01*
G02X628473Y1170794I142J-141D01*
G01X628524Y1170806D01*
X628619Y1170782D01*
X628657Y1170748D01*
X628884Y1170543D01*
X628917Y1170478D01*
X628920Y1170440D01*
G03X631512I1296J131D01*
G01X631515Y1170478D01*
X631548Y1170543D01*
X631775Y1170748D01*
G02X631910Y1170800I135J-148D01*
G01X632301D01*
X632370Y1170773D01*
X632398Y1170748D01*
X632625Y1170543D01*
X632658Y1170478D01*
X632661Y1170440D01*
G03X635253I1296J131D01*
G01X635256Y1170478D01*
X635289Y1170543D01*
X635516Y1170748D01*
G02X635651Y1170800I135J-148D01*
G01X636041D01*
X636110Y1170773D01*
X636138Y1170748D01*
X636365Y1170543D01*
X636398Y1170478D01*
X636401Y1170440D01*
G03X637697Y1169268I1296J131D01*
G03X638999Y1170570I0J1302D01*
G03X637979Y1171841I-1302J0D01*
G01X637910Y1171856D01*
X637822Y1171966D01*
Y1172914D01*
X637910Y1173024D01*
X637979Y1173039D01*
G03Y1175581I-282J1271D01*
G01X637910Y1175596D01*
X637822Y1175706D01*
Y1176655D01*
X637910Y1176765D01*
X637979Y1176780D01*
G03Y1179322I-282J1271D01*
G01X637910Y1179337D01*
X637822Y1179447D01*
Y1180395D01*
X637910Y1180505D01*
X637979Y1180520D01*
G03Y1183062I-282J1271D01*
G01X637910Y1183077D01*
X637822Y1183187D01*
Y1184135D01*
X637910Y1184245D01*
X637979Y1184260D01*
G03Y1186802I-282J1271D01*
G01X637910Y1186817D01*
X637822Y1186927D01*
Y1187875D01*
X637910Y1187985D01*
X637979Y1188000D01*
G03X638999Y1189247I-282J1271D01*
G01Y1189250D01*
G02X639057Y1189385I200J-6D01*
G01X639989Y1190317D01*
G02X639991Y1190319I142J-140D01*
G02X640131Y1190376I140J-143D01*
G01X650286D01*
G03X650428Y1190435I0J200D01*
G01X651541Y1191548D01*
G03X651600Y1191690I-141J142D01*
G01Y1191713D01*
X651658Y1191808D01*
X651812Y1191888D01*
G02X652005Y1191884I93J-177D01*
G03X652657Y1191709I652J1127D01*
G03Y1194313I0J1302D01*
G03X652154Y1194212I0J-1303D01*
G01X652107Y1194192D01*
X652009Y1194202D01*
X651689Y1194415D01*
G02X651600Y1194581I111J166D01*
G01Y1195181D01*
G02X651689Y1195347I200J0D01*
G01X652009Y1195560D01*
X652107Y1195570D01*
X652154Y1195550D01*
G03X652657Y1195449I503J1202D01*
G03X653959Y1196751I0J1302D01*
G03X653799Y1197376I-1301J0D01*
G01X653773Y1197423D01*
X653775Y1197528D01*
X653978Y1197870D01*
G02X654150Y1197968I172J-102D01*
G01X654905D01*
G02X655077Y1197870I0J-200D01*
G01X655280Y1197528D01*
X655282Y1197423D01*
X655256Y1197376D01*
G03X655096Y1196751I1141J-625D01*
G03X657700I1302J0D01*
G03X657540Y1197376I-1301J0D01*
G01X657514Y1197423D01*
X657516Y1197528D01*
X657719Y1197870D01*
G02X657891Y1197968I172J-102D01*
G01X658645D01*
G02X658817Y1197870I0J-200D01*
G01X659020Y1197528D01*
X659022Y1197423D01*
X658996Y1197376D01*
G03X658836Y1196751I1141J-625D01*
G03X661440I1302J0D01*
G03X661280Y1197376I-1301J0D01*
G01X661254Y1197423D01*
X661256Y1197528D01*
X661459Y1197870D01*
G02X661631Y1197968I172J-102D01*
G01X662385D01*
G02X662557Y1197870I0J-200D01*
G01X662760Y1197528D01*
X662762Y1197423D01*
X662736Y1197376D01*
G03X662576Y1196751I1141J-625D01*
G03X665180I1302J0D01*
G03X665020Y1197376I-1301J0D01*
G01X664994Y1197423D01*
X664996Y1197528D01*
X665199Y1197870D01*
G02X665371Y1197968I172J-102D01*
G01X666125D01*
G02X666297Y1197870I0J-200D01*
G01X666500Y1197528D01*
X666502Y1197423D01*
X666476Y1197376D01*
G03X666316Y1196751I1141J-625D01*
G03X668920I1302J0D01*
G03X668760Y1197376I-1301J0D01*
G01X668734Y1197423D01*
X668736Y1197528D01*
X668939Y1197870D01*
G02X669111Y1197968I172J-102D01*
G01X669865D01*
G02X670037Y1197870I0J-200D01*
G01X670240Y1197528D01*
X670242Y1197423D01*
X670216Y1197376D01*
G03X670056Y1196751I1141J-625D01*
G03X672660I1302J0D01*
G03X672500Y1197376I-1301J0D01*
G01X672474Y1197423D01*
X672476Y1197528D01*
X672679Y1197870D01*
G02X672851Y1197968I172J-102D01*
G01X673605D01*
G02X673777Y1197870I0J-200D01*
G01X673980Y1197528D01*
X673982Y1197423D01*
X673956Y1197376D01*
G03X673796Y1196751I1141J-625D01*
G03X676400I1302J0D01*
G03X676240Y1197376I-1301J0D01*
G01X676214Y1197423D01*
X676216Y1197528D01*
X676419Y1197870D01*
G02X676591Y1197968I172J-102D01*
G01X677345D01*
G02X677517Y1197870I0J-200D01*
G01X677720Y1197528D01*
X677722Y1197423D01*
X677696Y1197376D01*
G03X677536Y1196751I1141J-625D01*
G03X680140I1302J0D01*
G03X679980Y1197376I-1301J0D01*
G01X679954Y1197423D01*
X679956Y1197528D01*
X680159Y1197870D01*
G02X680331Y1197968I172J-102D01*
G01X681086D01*
G02X681258Y1197870I0J-200D01*
G01X681461Y1197528D01*
X681463Y1197423D01*
X681437Y1197376D01*
G03X681277Y1196751I1141J-625D01*
G03X683881I1302J0D01*
G03X683721Y1197376I-1301J0D01*
G01X683695Y1197423D01*
X683697Y1197528D01*
X683900Y1197870D01*
G02X684072Y1197968I172J-102D01*
G01X684826D01*
G02X684998Y1197870I0J-200D01*
G01X685201Y1197528D01*
X685203Y1197423D01*
X685177Y1197376D01*
G03X685017Y1196751I1141J-625D01*
G03X687621I1302J0D01*
G03X687461Y1197376I-1301J0D01*
G01X687435Y1197423D01*
X687437Y1197528D01*
X687640Y1197870D01*
G02X687812Y1197968I172J-102D01*
G01X692306D01*
G02X692478Y1197870I0J-200D01*
G01X692681Y1197528D01*
X692683Y1197423D01*
X692657Y1197376D01*
G03X692497Y1196751I1141J-625D01*
G03X695101I1302J0D01*
G03X694941Y1197376I-1301J0D01*
G01X694915Y1197423D01*
X694917Y1197528D01*
X695120Y1197870D01*
G02X695292Y1197968I172J-102D01*
G01X696046D01*
G02X696218Y1197870I0J-200D01*
G01X696421Y1197528D01*
X696423Y1197423D01*
X696397Y1197376D01*
G03X696237Y1196751I1141J-625D01*
G03X698841I1302J0D01*
G03X698681Y1197376I-1301J0D01*
G01X698655Y1197423D01*
X698657Y1197528D01*
X698860Y1197870D01*
G02X699032Y1197968I172J-102D01*
G01X699786D01*
G02X699958Y1197870I0J-200D01*
G01X700161Y1197528D01*
X700163Y1197423D01*
X700137Y1197376D01*
G03X699977Y1196751I1141J-625D01*
G03X702581I1302J0D01*
G03X702421Y1197376I-1301J0D01*
G01X702395Y1197423D01*
X702397Y1197528D01*
X702600Y1197870D01*
G02X702772Y1197968I172J-102D01*
G01X703527D01*
G02X703699Y1197870I0J-200D01*
G01X703902Y1197528D01*
X703904Y1197423D01*
X703878Y1197376D01*
G03X703718Y1196751I1141J-625D01*
G03X706322I1302J0D01*
G03X706162Y1197376I-1301J0D01*
G01X706136Y1197423D01*
X706138Y1197528D01*
X706341Y1197870D01*
G02X706513Y1197968I172J-102D01*
G01X707267D01*
G02X707439Y1197870I0J-200D01*
G01X707642Y1197528D01*
X707644Y1197423D01*
X707618Y1197376D01*
G03X707458Y1196751I1141J-625D01*
G03X710062I1302J0D01*
G03X709902Y1197376I-1301J0D01*
G01X709876Y1197423D01*
X709878Y1197528D01*
X710081Y1197870D01*
G02X710253Y1197968I172J-102D01*
G01X711007D01*
G02X711179Y1197870I0J-200D01*
G01X711382Y1197528D01*
X711384Y1197423D01*
X711358Y1197376D01*
G03X711198Y1196751I1141J-625D01*
G03X713802I1302J0D01*
G03X713642Y1197376I-1301J0D01*
G01X713616Y1197423D01*
X713618Y1197528D01*
X713821Y1197870D01*
G02X713993Y1197968I172J-102D01*
G01X714747D01*
G02X714919Y1197870I0J-200D01*
G01X715122Y1197528D01*
X715124Y1197423D01*
X715098Y1197376D01*
G03X714938Y1196751I1141J-625D01*
G03X717542I1302J0D01*
G03X717382Y1197376I-1301J0D01*
G01X717356Y1197423D01*
X717358Y1197528D01*
X717561Y1197870D01*
G02X717733Y1197968I172J-102D01*
G01X718487D01*
G02X718659Y1197870I0J-200D01*
G01X718862Y1197528D01*
X718864Y1197423D01*
X718838Y1197376D01*
G03X718678Y1196751I1141J-625D01*
G03X721282I1302J0D01*
G03X721122Y1197376I-1301J0D01*
G01X721096Y1197423D01*
X721098Y1197528D01*
X721301Y1197870D01*
G02X721473Y1197968I172J-102D01*
G01X722227D01*
G02X722399Y1197870I0J-200D01*
G01X722602Y1197528D01*
X722604Y1197423D01*
X722578Y1197376D01*
G03X722418Y1196751I1141J-625D01*
G03X725022I1302J0D01*
G03X724862Y1197376I-1301J0D01*
G01X724836Y1197423D01*
X724838Y1197528D01*
X725041Y1197870D01*
G02X725213Y1197968I172J-102D01*
G01X725998D01*
G02X726170Y1197869I-1J-200D01*
G01X726372Y1197524D01*
Y1197418D01*
X726346Y1197372D01*
G03X726178Y1196732I1135J-640D01*
G03X728782I1302J0D01*
G03X728614Y1197372I-1303J0D01*
G01X728588Y1197418D01*
Y1197524D01*
X728790Y1197869D01*
G02X728962Y1197968I173J-101D01*
G37*
G36*
G01X1643135D02*
X1643881D01*
G02X1644053Y1197870I0J-200D01*
G01X1644256Y1197528D01*
X1644258Y1197423D01*
X1644232Y1197376D01*
G03X1644072Y1196751I1141J-625D01*
G03X1645374Y1195449I1302J0D01*
G03X1646216Y1195758I0J1302D01*
G01X1646261Y1195796D01*
X1646376Y1195812D01*
X1646759Y1195635D01*
G02X1646875Y1195453I-84J-182D01*
G01Y1184953D01*
G02X1646816Y1184811I-200J0D01*
G01X1645542Y1183537D01*
G02X1645400Y1183478I-142J141D01*
G01X1640209D01*
G03X1640067Y1183419I0J-200D01*
G01X1639980Y1183332D01*
G03X1639921Y1183190I141J-142D01*
G01Y1170910D01*
G03X1639980Y1170768I200J0D01*
G01X1640317Y1170431D01*
X1640345Y1170377D01*
X1640350Y1170346D01*
G03X1641633Y1169268I1283J224D01*
G03X1642890Y1170231I0J1302D01*
G01X1642908Y1170297D01*
X1643015Y1170379D01*
X1643992D01*
X1644099Y1170297D01*
X1644117Y1170231D01*
G03X1646631I1257J339D01*
G01X1646649Y1170297D01*
X1646756Y1170379D01*
X1647732D01*
X1647839Y1170297D01*
X1647857Y1170231D01*
G03X1648956Y1169278I1257J339D01*
G01X1649032Y1169268D01*
X1649132Y1169155D01*
Y1168245D01*
X1649032Y1168132D01*
X1648956Y1168122D01*
G03Y1165538I158J-1292D01*
G01X1649032Y1165528D01*
X1649132Y1165415D01*
Y1160765D01*
X1649032Y1160652D01*
X1648956Y1160642D01*
G03Y1158058I158J-1292D01*
G01X1649032Y1158048D01*
X1649132Y1157935D01*
Y1157025D01*
X1649032Y1156912D01*
X1648956Y1156902D01*
G03Y1154318I158J-1292D01*
G01X1649032Y1154308D01*
X1649132Y1154195D01*
Y1153285D01*
X1649032Y1153172D01*
X1648956Y1153162D01*
G03Y1150578I158J-1292D01*
G01X1649032Y1150568D01*
X1649132Y1150455D01*
Y1149544D01*
X1649032Y1149431D01*
X1648956Y1149421D01*
G03Y1146837I158J-1292D01*
G01X1649032Y1146827D01*
X1649132Y1146714D01*
Y1145804D01*
X1649032Y1145691D01*
X1648956Y1145681D01*
G03Y1143097I158J-1292D01*
G01X1649032Y1143087D01*
X1649132Y1142974D01*
Y1142064D01*
X1649032Y1141951D01*
X1648956Y1141941D01*
G03Y1139357I158J-1292D01*
G01X1649032Y1139347D01*
X1649132Y1139234D01*
Y1138324D01*
X1649032Y1138211D01*
X1648956Y1138201D01*
G03X1647812Y1136922I158J-1292D01*
G01Y1136908D01*
G03X1647866Y1136537I1302J0D01*
G02X1647816Y1136339I-192J-57D01*
G01X1646963Y1135486D01*
X1646935Y1135457D01*
X1646861Y1135427D01*
X1642947D01*
G02X1642766Y1135541I0J200D01*
G01X1642612Y1135868D01*
G02X1642638Y1136081I180J86D01*
G03X1642935Y1136909I-1006J828D01*
G03X1640331I-1302J0D01*
G03X1640346Y1136709I1302J-3D01*
G03X1640628Y1136080I1287J199D01*
G02X1640654Y1135868I-155J-127D01*
G01X1640500Y1135541D01*
G02X1640319Y1135427I-181J86D01*
G01X1639207D01*
G02X1639026Y1135542I0J200D01*
G01X1638846Y1135922D01*
X1638861Y1136036D01*
X1638898Y1136081D01*
G03X1639195Y1136909I-1006J828D01*
G03X1636591I-1302J0D01*
G03X1636888Y1136081I1303J0D01*
G01X1636925Y1136036D01*
X1636940Y1135922D01*
X1636760Y1135542D01*
G02X1636579Y1135427I-181J85D01*
G01X1635467D01*
G02X1635286Y1135542I0J200D01*
G01X1635106Y1135922D01*
X1635121Y1136036D01*
X1635158Y1136081D01*
G03X1635455Y1136909I-1006J828D01*
G03X1632851I-1302J0D01*
G03X1633148Y1136081I1303J0D01*
G01X1633185Y1136036D01*
X1633200Y1135922D01*
X1633020Y1135542D01*
G02X1632839Y1135427I-181J85D01*
G01X1631727D01*
G02X1631546Y1135542I0J200D01*
G01X1631366Y1135922D01*
X1631381Y1136036D01*
X1631418Y1136081D01*
G03X1631715Y1136909I-1006J828D01*
G03X1629111I-1302J0D01*
G03X1629408Y1136081I1303J0D01*
G01X1629445Y1136036D01*
X1629460Y1135922D01*
X1629280Y1135542D01*
G02X1629099Y1135427I-181J85D01*
G01X1627987D01*
G02X1627806Y1135542I0J200D01*
G01X1627626Y1135922D01*
X1627641Y1136036D01*
X1627678Y1136081D01*
G03X1627975Y1136909I-1006J828D01*
G03X1625371I-1302J0D01*
G03X1625668Y1136081I1303J0D01*
G01X1625705Y1136036D01*
X1625720Y1135922D01*
X1625540Y1135542D01*
G02X1625359Y1135427I-181J85D01*
G01X1624247D01*
G02X1624066Y1135542I0J200D01*
G01X1623886Y1135922D01*
X1623901Y1136036D01*
X1623938Y1136081D01*
G03X1624235Y1136909I-1006J828D01*
G03X1621631I-1302J0D01*
G03X1621928Y1136081I1303J0D01*
G01X1621965Y1136036D01*
X1621980Y1135922D01*
X1621800Y1135542D01*
G02X1621619Y1135427I-181J85D01*
G01X1620507D01*
G02X1620326Y1135542I0J200D01*
G01X1620146Y1135922D01*
X1620161Y1136036D01*
X1620198Y1136081D01*
G03X1620495Y1136909I-1006J828D01*
G03X1617891I-1302J0D01*
G03X1618188Y1136081I1303J0D01*
G01X1618225Y1136036D01*
X1618240Y1135922D01*
X1618060Y1135542D01*
G02X1617879Y1135427I-181J85D01*
G01X1616766D01*
G02X1616585Y1135542I0J200D01*
G01X1616405Y1135922D01*
X1616420Y1136036D01*
X1616457Y1136081D01*
G03X1616754Y1136909I-1006J828D01*
G03X1614150I-1302J0D01*
G03X1614447Y1136081I1303J0D01*
G01X1614484Y1136036D01*
X1614499Y1135922D01*
X1614319Y1135542D01*
G02X1614138Y1135427I-181J85D01*
G01X1613026D01*
G02X1612845Y1135542I0J200D01*
G01X1612665Y1135922D01*
X1612680Y1136036D01*
X1612717Y1136081D01*
G03X1613014Y1136909I-1006J828D01*
G03X1610410I-1302J0D01*
G03X1610707Y1136081I1303J0D01*
G01X1610744Y1136036D01*
X1610759Y1135922D01*
X1610579Y1135542D01*
G02X1610398Y1135427I-181J85D01*
G01X1609286D01*
G02X1609105Y1135542I0J200D01*
G01X1608925Y1135922D01*
X1608940Y1136036D01*
X1608977Y1136081D01*
G03X1609274Y1136909I-1006J828D01*
G03X1606670I-1302J0D01*
G03X1606967Y1136081I1303J0D01*
G01X1607004Y1136036D01*
X1607019Y1135922D01*
X1606839Y1135542D01*
G02X1606658Y1135427I-181J85D01*
G01X1601806D01*
G02X1601625Y1135542I0J200D01*
G01X1601445Y1135922D01*
X1601460Y1136036D01*
X1601497Y1136081D01*
G03X1601794Y1136909I-1006J828D01*
G03X1599190I-1302J0D01*
G03X1599487Y1136081I1303J0D01*
G01X1599524Y1136036D01*
X1599539Y1135922D01*
X1599359Y1135542D01*
G02X1599178Y1135427I-181J85D01*
G01X1598066D01*
G02X1597885Y1135542I0J200D01*
G01X1597705Y1135922D01*
X1597720Y1136036D01*
X1597757Y1136081D01*
G03X1598054Y1136909I-1006J828D01*
G03X1595450I-1302J0D01*
G03X1595747Y1136081I1303J0D01*
G01X1595784Y1136036D01*
X1595799Y1135922D01*
X1595619Y1135542D01*
G02X1595438Y1135427I-181J85D01*
G01X1594325D01*
G02X1594144Y1135542I0J200D01*
G01X1593964Y1135922D01*
X1593979Y1136036D01*
X1594016Y1136081D01*
G03X1594313Y1136909I-1006J828D01*
G03X1591709I-1302J0D01*
G03X1592006Y1136081I1303J0D01*
G01X1592043Y1136036D01*
X1592058Y1135922D01*
X1591878Y1135542D01*
G02X1591697Y1135427I-181J85D01*
G01X1590585D01*
G02X1590404Y1135542I0J200D01*
G01X1590224Y1135922D01*
X1590239Y1136036D01*
X1590276Y1136081D01*
G03X1590573Y1136909I-1006J828D01*
G03X1587969I-1302J0D01*
G03X1588266Y1136081I1303J0D01*
G01X1588303Y1136036D01*
X1588318Y1135922D01*
X1588138Y1135542D01*
G02X1587957Y1135427I-181J85D01*
G01X1586845D01*
G02X1586664Y1135542I0J200D01*
G01X1586484Y1135922D01*
X1586499Y1136036D01*
X1586536Y1136081D01*
G03X1586833Y1136909I-1006J828D01*
G03X1584229I-1302J0D01*
G03X1584526Y1136081I1303J0D01*
G01X1584563Y1136036D01*
X1584578Y1135922D01*
X1584398Y1135542D01*
G02X1584217Y1135427I-181J85D01*
G01X1583105D01*
G02X1582924Y1135542I0J200D01*
G01X1582744Y1135922D01*
X1582759Y1136036D01*
X1582796Y1136081D01*
G03X1583093Y1136909I-1006J828D01*
G03X1580489I-1302J0D01*
G03X1580786Y1136081I1303J0D01*
G01X1580823Y1136036D01*
X1580838Y1135922D01*
X1580658Y1135542D01*
G02X1580477Y1135427I-181J85D01*
G01X1579365D01*
G02X1579184Y1135542I0J200D01*
G01X1579004Y1135922D01*
X1579019Y1136036D01*
X1579056Y1136081D01*
G03X1579353Y1136909I-1006J828D01*
G03X1576749I-1302J0D01*
G03X1577046Y1136081I1303J0D01*
G01X1577083Y1136036D01*
X1577098Y1135922D01*
X1576918Y1135542D01*
G02X1576737Y1135427I-181J85D01*
G01X1575625D01*
G02X1575444Y1135542I0J200D01*
G01X1575264Y1135922D01*
X1575279Y1136036D01*
X1575316Y1136081D01*
G03X1575613Y1136909I-1006J828D01*
G03X1573009I-1302J0D01*
G03X1573306Y1136081I1303J0D01*
G01X1573343Y1136036D01*
X1573358Y1135922D01*
X1573178Y1135542D01*
G02X1572997Y1135427I-181J85D01*
G01X1571885D01*
G02X1571704Y1135542I0J200D01*
G01X1571524Y1135922D01*
X1571539Y1136036D01*
X1571576Y1136081D01*
G03X1571873Y1136909I-1006J828D01*
G03X1569269I-1302J0D01*
G03X1569566Y1136081I1303J0D01*
G01X1569603Y1136036D01*
X1569618Y1135922D01*
X1569438Y1135542D01*
G02X1569257Y1135427I-181J85D01*
G01X1568436D01*
G02X1568294Y1135486I0J200D01*
G01X1567847Y1135933D01*
X1567836Y1136079D01*
X1567880Y1136139D01*
G03X1568132Y1136909I-1050J770D01*
G03X1566830Y1138211I-1302J0D01*
G03X1566060Y1137959I0J-1302D01*
G01X1566000Y1137915D01*
X1565854Y1137926D01*
X1564631Y1139149D01*
G03X1564489Y1139208I-142J-141D01*
G01X1564436D01*
G02X1564257Y1139320I1J200D01*
G01X1564073Y1139694D01*
X1564085Y1139807D01*
X1564120Y1139853D01*
G03X1564392Y1140649I-1029J796D01*
G03X1561788I-1302J0D01*
G03X1562060Y1139853I1301J0D01*
G01X1562095Y1139807D01*
X1562107Y1139694D01*
X1561923Y1139320D01*
G02X1561744Y1139208I-180J88D01*
G01X1560696D01*
G02X1560517Y1139320I1J200D01*
G01X1560333Y1139694D01*
X1560345Y1139807D01*
X1560380Y1139853D01*
G03X1560652Y1140649I-1029J796D01*
G03X1558048I-1302J0D01*
G03X1558320Y1139853I1301J0D01*
G01X1558355Y1139807D01*
X1558367Y1139694D01*
X1558183Y1139320D01*
G02X1558004Y1139208I-180J88D01*
G01X1556956D01*
G02X1556777Y1139320I1J200D01*
G01X1556593Y1139694D01*
X1556605Y1139807D01*
X1556640Y1139853D01*
G03X1556912Y1140649I-1029J796D01*
G03X1554308I-1302J0D01*
G03X1554580Y1139853I1301J0D01*
G01X1554615Y1139807D01*
X1554627Y1139694D01*
X1554443Y1139320D01*
G02X1554264Y1139208I-180J88D01*
G01X1553216D01*
G02X1553037Y1139320I1J200D01*
G01X1552853Y1139694D01*
X1552865Y1139807D01*
X1552900Y1139853D01*
G03X1553172Y1140649I-1029J796D01*
G03X1550568I-1302J0D01*
G03X1550840Y1139853I1301J0D01*
G01X1550875Y1139807D01*
X1550887Y1139694D01*
X1550703Y1139320D01*
G02X1550524Y1139208I-180J88D01*
G01X1549476D01*
G02X1549297Y1139320I1J200D01*
G01X1549113Y1139694D01*
X1549125Y1139807D01*
X1549160Y1139853D01*
G03X1549432Y1140649I-1029J796D01*
G03X1546828I-1302J0D01*
G03X1547100Y1139853I1301J0D01*
G01X1547135Y1139807D01*
X1547147Y1139694D01*
X1546963Y1139320D01*
G02X1546784Y1139208I-180J88D01*
G01X1545735D01*
G02X1545556Y1139320I1J200D01*
G01X1545372Y1139694D01*
X1545384Y1139807D01*
X1545419Y1139853D01*
G03X1545691Y1140649I-1029J796D01*
G03X1543087I-1302J0D01*
G03X1543359Y1139853I1301J0D01*
G01X1543394Y1139807D01*
X1543406Y1139694D01*
X1543222Y1139320D01*
G02X1543043Y1139208I-180J88D01*
G01X1541544D01*
G02X1541402Y1139267I0J200D01*
G01X1541382Y1139287D01*
G02Y1139569I142J141D01*
G01X1541394Y1139581D01*
X1541407Y1139591D01*
G03X1541951Y1140649I-757J1058D01*
G03X1541170Y1141842I-1302J0D01*
G01X1541115Y1141866D01*
X1541050Y1141966D01*
Y1142306D01*
G03X1540991Y1142448I-200J0D01*
G01Y1142988D01*
G02X1541026Y1143101I200J0D01*
G01X1541044Y1143127D01*
X1541090Y1143164D01*
X1541119Y1143175D01*
G03Y1145603I-470J1214D01*
G01X1541090Y1145614D01*
X1541044Y1145651D01*
X1541026Y1145677D01*
G02X1540991Y1145790I165J113D01*
G01Y1146728D01*
G02X1541026Y1146841I200J0D01*
G01X1541044Y1146867D01*
X1541090Y1146904D01*
X1541119Y1146915D01*
G03Y1149343I-470J1214D01*
G01X1541090Y1149354D01*
X1541044Y1149391D01*
X1541026Y1149417D01*
G02X1540991Y1149530I165J113D01*
G01Y1150469D01*
G02X1541026Y1150582I200J0D01*
G01X1541044Y1150608D01*
X1541090Y1150645D01*
X1541119Y1150656D01*
G03Y1153084I-470J1214D01*
G01X1541090Y1153095D01*
X1541044Y1153132D01*
X1541026Y1153158D01*
G02X1540991Y1153271I165J113D01*
G01Y1154061D01*
X1541066Y1154165D01*
X1541127Y1154186D01*
G03Y1157034I-478J1424D01*
G01X1541066Y1157055D01*
X1540991Y1157159D01*
Y1157949D01*
G02X1541026Y1158062I200J0D01*
G01X1541044Y1158088D01*
X1541090Y1158125D01*
X1541119Y1158136D01*
G03Y1160564I-470J1214D01*
G01X1541090Y1160575D01*
X1541044Y1160612D01*
X1541026Y1160638D01*
G02X1540991Y1160751I165J113D01*
G01Y1169096D01*
G02X1541048Y1169236I200J0D01*
G01X1541049Y1169237D01*
X1542553Y1170741D01*
G02X1542646Y1170794I142J-141D01*
G01X1542697Y1170806D01*
X1542792Y1170782D01*
X1542830Y1170748D01*
X1543057Y1170543D01*
X1543090Y1170478D01*
X1543093Y1170440D01*
G03X1545685I1296J131D01*
G01X1545688Y1170478D01*
X1545721Y1170543D01*
X1545948Y1170748D01*
G02X1546083Y1170800I135J-148D01*
G01X1546474D01*
X1546543Y1170773D01*
X1546571Y1170748D01*
X1546798Y1170543D01*
X1546831Y1170478D01*
X1546834Y1170440D01*
G03X1549426I1296J131D01*
G01X1549429Y1170478D01*
X1549462Y1170543D01*
X1549689Y1170748D01*
G02X1549824Y1170800I135J-148D01*
G01X1550214D01*
X1550283Y1170773D01*
X1550311Y1170748D01*
X1550538Y1170543D01*
X1550571Y1170478D01*
X1550574Y1170440D01*
G03X1551870Y1169268I1296J131D01*
G03X1553172Y1170570I0J1302D01*
G03X1552152Y1171841I-1302J0D01*
G01X1552083Y1171856D01*
X1551995Y1171966D01*
Y1172914D01*
X1552083Y1173024D01*
X1552152Y1173039D01*
G03Y1175581I-282J1271D01*
G01X1552083Y1175596D01*
X1551995Y1175706D01*
Y1176655D01*
X1552083Y1176765D01*
X1552152Y1176780D01*
G03Y1179322I-282J1271D01*
G01X1552083Y1179337D01*
X1551995Y1179447D01*
Y1180395D01*
X1552083Y1180505D01*
X1552152Y1180520D01*
G03Y1183062I-282J1271D01*
G01X1552083Y1183077D01*
X1551995Y1183187D01*
Y1184135D01*
X1552083Y1184245D01*
X1552152Y1184260D01*
G03Y1186802I-282J1271D01*
G01X1552083Y1186817D01*
X1551995Y1186927D01*
Y1187875D01*
X1552083Y1187985D01*
X1552152Y1188000D01*
G03X1553172Y1189247I-282J1271D01*
G01Y1189250D01*
G02X1553230Y1189385I200J-6D01*
G01X1554162Y1190317D01*
G02X1554164Y1190319I142J-140D01*
G02X1554304Y1190376I140J-143D01*
G01X1564459D01*
G03X1564601Y1190435I0J200D01*
G01X1565714Y1191548D01*
G03X1565773Y1191690I-141J142D01*
G01Y1191713D01*
X1565831Y1191808D01*
X1565985Y1191888D01*
G02X1566178Y1191884I93J-177D01*
G03X1566830Y1191709I652J1127D01*
G03Y1194313I0J1302D01*
G03X1566327Y1194212I0J-1303D01*
G01X1566280Y1194192D01*
X1566182Y1194202D01*
X1565862Y1194415D01*
G02X1565773Y1194581I111J166D01*
G01Y1195181D01*
G02X1565862Y1195347I200J0D01*
G01X1566182Y1195560D01*
X1566280Y1195570D01*
X1566327Y1195550D01*
G03X1566830Y1195449I503J1202D01*
G03X1568132Y1196751I0J1302D01*
G03X1567972Y1197376I-1301J0D01*
G01X1567946Y1197423D01*
X1567948Y1197528D01*
X1568151Y1197870D01*
G02X1568323Y1197968I172J-102D01*
G01X1569078D01*
G02X1569250Y1197870I0J-200D01*
G01X1569453Y1197528D01*
X1569455Y1197423D01*
X1569429Y1197376D01*
G03X1569269Y1196751I1141J-625D01*
G03X1571873I1302J0D01*
G03X1571713Y1197376I-1301J0D01*
G01X1571687Y1197423D01*
X1571689Y1197528D01*
X1571892Y1197870D01*
G02X1572064Y1197968I172J-102D01*
G01X1572818D01*
G02X1572990Y1197870I0J-200D01*
G01X1573193Y1197528D01*
X1573195Y1197423D01*
X1573169Y1197376D01*
G03X1573009Y1196751I1141J-625D01*
G03X1575613I1302J0D01*
G03X1575453Y1197376I-1301J0D01*
G01X1575427Y1197423D01*
X1575429Y1197528D01*
X1575632Y1197870D01*
G02X1575804Y1197968I172J-102D01*
G01X1576558D01*
G02X1576730Y1197870I0J-200D01*
G01X1576933Y1197528D01*
X1576935Y1197423D01*
X1576909Y1197376D01*
G03X1576749Y1196751I1141J-625D01*
G03X1579353I1302J0D01*
G03X1579193Y1197376I-1301J0D01*
G01X1579167Y1197423D01*
X1579169Y1197528D01*
X1579372Y1197870D01*
G02X1579544Y1197968I172J-102D01*
G01X1580298D01*
G02X1580470Y1197870I0J-200D01*
G01X1580673Y1197528D01*
X1580675Y1197423D01*
X1580649Y1197376D01*
G03X1580489Y1196751I1141J-625D01*
G03X1583093I1302J0D01*
G03X1582933Y1197376I-1301J0D01*
G01X1582907Y1197423D01*
X1582909Y1197528D01*
X1583112Y1197870D01*
G02X1583284Y1197968I172J-102D01*
G01X1584038D01*
G02X1584210Y1197870I0J-200D01*
G01X1584413Y1197528D01*
X1584415Y1197423D01*
X1584389Y1197376D01*
G03X1584229Y1196751I1141J-625D01*
G03X1586833I1302J0D01*
G03X1586673Y1197376I-1301J0D01*
G01X1586647Y1197423D01*
X1586649Y1197528D01*
X1586852Y1197870D01*
G02X1587024Y1197968I172J-102D01*
G01X1587778D01*
G02X1587950Y1197870I0J-200D01*
G01X1588153Y1197528D01*
X1588155Y1197423D01*
X1588129Y1197376D01*
G03X1587969Y1196751I1141J-625D01*
G03X1590573I1302J0D01*
G03X1590413Y1197376I-1301J0D01*
G01X1590387Y1197423D01*
X1590389Y1197528D01*
X1590592Y1197870D01*
G02X1590764Y1197968I172J-102D01*
G01X1591518D01*
G02X1591690Y1197870I0J-200D01*
G01X1591893Y1197528D01*
X1591895Y1197423D01*
X1591869Y1197376D01*
G03X1591709Y1196751I1141J-625D01*
G03X1594313I1302J0D01*
G03X1594153Y1197376I-1301J0D01*
G01X1594127Y1197423D01*
X1594129Y1197528D01*
X1594332Y1197870D01*
G02X1594504Y1197968I172J-102D01*
G01X1595259D01*
G02X1595431Y1197870I0J-200D01*
G01X1595634Y1197528D01*
X1595636Y1197423D01*
X1595610Y1197376D01*
G03X1595450Y1196751I1141J-625D01*
G03X1598054I1302J0D01*
G03X1597894Y1197376I-1301J0D01*
G01X1597868Y1197423D01*
X1597870Y1197528D01*
X1598073Y1197870D01*
G02X1598245Y1197968I172J-102D01*
G01X1598999D01*
G02X1599171Y1197870I0J-200D01*
G01X1599374Y1197528D01*
X1599376Y1197423D01*
X1599350Y1197376D01*
G03X1599190Y1196751I1141J-625D01*
G03X1601794I1302J0D01*
G03X1601634Y1197376I-1301J0D01*
G01X1601608Y1197423D01*
X1601610Y1197528D01*
X1601813Y1197870D01*
G02X1601985Y1197968I172J-102D01*
G01X1606479D01*
G02X1606651Y1197870I0J-200D01*
G01X1606854Y1197528D01*
X1606856Y1197423D01*
X1606830Y1197376D01*
G03X1606670Y1196751I1141J-625D01*
G03X1609274I1302J0D01*
G03X1609114Y1197376I-1301J0D01*
G01X1609088Y1197423D01*
X1609090Y1197528D01*
X1609293Y1197870D01*
G02X1609465Y1197968I172J-102D01*
G01X1610219D01*
G02X1610391Y1197870I0J-200D01*
G01X1610594Y1197528D01*
X1610596Y1197423D01*
X1610570Y1197376D01*
G03X1610410Y1196751I1141J-625D01*
G03X1613014I1302J0D01*
G03X1612854Y1197376I-1301J0D01*
G01X1612828Y1197423D01*
X1612830Y1197528D01*
X1613033Y1197870D01*
G02X1613205Y1197968I172J-102D01*
G01X1613959D01*
G02X1614131Y1197870I0J-200D01*
G01X1614334Y1197528D01*
X1614336Y1197423D01*
X1614310Y1197376D01*
G03X1614150Y1196751I1141J-625D01*
G03X1616754I1302J0D01*
G03X1616594Y1197376I-1301J0D01*
G01X1616568Y1197423D01*
X1616570Y1197528D01*
X1616773Y1197870D01*
G02X1616945Y1197968I172J-102D01*
G01X1617700D01*
G02X1617872Y1197870I0J-200D01*
G01X1618075Y1197528D01*
X1618077Y1197423D01*
X1618051Y1197376D01*
G03X1617891Y1196751I1141J-625D01*
G03X1620495I1302J0D01*
G03X1620335Y1197376I-1301J0D01*
G01X1620309Y1197423D01*
X1620311Y1197528D01*
X1620514Y1197870D01*
G02X1620686Y1197968I172J-102D01*
G01X1621440D01*
G02X1621612Y1197870I0J-200D01*
G01X1621815Y1197528D01*
X1621817Y1197423D01*
X1621791Y1197376D01*
G03X1621631Y1196751I1141J-625D01*
G03X1624235I1302J0D01*
G03X1624075Y1197376I-1301J0D01*
G01X1624049Y1197423D01*
X1624051Y1197528D01*
X1624254Y1197870D01*
G02X1624426Y1197968I172J-102D01*
G01X1625180D01*
G02X1625352Y1197870I0J-200D01*
G01X1625555Y1197528D01*
X1625557Y1197423D01*
X1625531Y1197376D01*
G03X1625371Y1196751I1141J-625D01*
G03X1627975I1302J0D01*
G03X1627815Y1197376I-1301J0D01*
G01X1627789Y1197423D01*
X1627791Y1197528D01*
X1627994Y1197870D01*
G02X1628166Y1197968I172J-102D01*
G01X1628920D01*
G02X1629092Y1197870I0J-200D01*
G01X1629295Y1197528D01*
X1629297Y1197423D01*
X1629271Y1197376D01*
G03X1629111Y1196751I1141J-625D01*
G03X1631715I1302J0D01*
G03X1631555Y1197376I-1301J0D01*
G01X1631529Y1197423D01*
X1631531Y1197528D01*
X1631734Y1197870D01*
G02X1631906Y1197968I172J-102D01*
G01X1632660D01*
G02X1632832Y1197870I0J-200D01*
G01X1633035Y1197528D01*
X1633037Y1197423D01*
X1633011Y1197376D01*
G03X1632851Y1196751I1141J-625D01*
G03X1635455I1302J0D01*
G03X1635295Y1197376I-1301J0D01*
G01X1635269Y1197423D01*
X1635271Y1197528D01*
X1635474Y1197870D01*
G02X1635646Y1197968I172J-102D01*
G01X1636400D01*
G02X1636572Y1197870I0J-200D01*
G01X1636775Y1197528D01*
X1636777Y1197423D01*
X1636751Y1197376D01*
G03X1636591Y1196751I1141J-625D01*
G03X1639195I1302J0D01*
G03X1639035Y1197376I-1301J0D01*
G01X1639009Y1197423D01*
X1639011Y1197528D01*
X1639214Y1197870D01*
G02X1639386Y1197968I172J-102D01*
G01X1640171D01*
G02X1640343Y1197869I-1J-200D01*
G01X1640545Y1197524D01*
Y1197418D01*
X1640519Y1197372D01*
G03X1640351Y1196732I1135J-640D01*
G03X1642955I1302J0D01*
G03X1642787Y1197372I-1303J0D01*
G01X1642761Y1197418D01*
Y1197524D01*
X1642963Y1197869D01*
G02X1643135Y1197968I173J-101D01*
G37*
%LPC*%
G75*
G54D50*
X630216Y1159350D03*
Y1166830D03*
Y1144389D03*
Y1148129D03*
Y1151870D03*
Y1155610D03*
X641437Y1181791D03*
X648917D03*
X645177Y1185531D03*
X641437Y1178051D03*
X645177Y1181791D03*
Y1174310D03*
X648917Y1185531D03*
Y1178051D03*
X641437Y1174310D03*
X648917D03*
X645177Y1178051D03*
X641437Y1159350D03*
X645177Y1166830D03*
X641437Y1170570D03*
X648917Y1159350D03*
Y1170570D03*
X645177Y1159350D03*
X637697D03*
X648917Y1166830D03*
X637697D03*
X641437D03*
X645177Y1170570D03*
Y1151870D03*
X648917Y1155610D03*
Y1148129D03*
X645177D03*
X641437Y1151870D03*
X645177Y1155610D03*
X648917Y1144389D03*
Y1151869D03*
X641437Y1155610D03*
X637697Y1148129D03*
Y1155610D03*
Y1151870D03*
X641437Y1148129D03*
X637697Y1144389D03*
X645177D03*
X663878Y1181791D03*
X660138D03*
X656398D03*
X663878Y1189271D03*
X660138D03*
X656398D03*
X652657D03*
X663878Y1166830D03*
Y1170570D03*
X660138Y1166830D03*
X656398Y1170570D03*
X663878Y1159350D03*
X652657Y1166830D03*
X656398Y1159350D03*
X652657D03*
X660138D03*
Y1170570D03*
X652657D03*
X656398Y1166830D03*
X660138Y1155610D03*
X652657Y1148129D03*
Y1155610D03*
X663878Y1151870D03*
X660138D03*
X656398D03*
X663878Y1144389D03*
X660138D03*
X656398D03*
Y1155610D03*
X652657Y1151869D03*
X663878Y1148129D03*
X660138D03*
X656398D03*
X652657Y1144389D03*
X663878Y1155610D03*
X652657Y1140649D03*
X656398D03*
X660138D03*
X663878D03*
Y1193011D03*
X660138D03*
X656398D03*
X652657Y1185531D03*
X656398Y1174310D03*
X652657Y1178051D03*
X660138Y1174310D03*
X652657Y1181791D03*
Y1174310D03*
X660138Y1185531D03*
X656398D03*
X663878Y1178051D03*
X660138D03*
X656398D03*
X663878Y1185531D03*
Y1174310D03*
X678838Y1155610D03*
X671358D03*
X667618D03*
X675098D03*
X678839Y1151870D03*
X675098D03*
X671358D03*
X667618D03*
X678838Y1144389D03*
X667618Y1140649D03*
X671358D03*
X675098D03*
X678838D03*
X667618Y1193011D03*
X678838D03*
X675098D03*
X671358D03*
X675098Y1185531D03*
X671358D03*
X667618D03*
X678838Y1178051D03*
X675098D03*
X671358D03*
X667618D03*
X678838Y1181791D03*
X675098D03*
X671358D03*
X667618D03*
X678838Y1189271D03*
X675098D03*
X671358D03*
X667618D03*
X678838Y1174310D03*
X671358D03*
X675098D03*
X667618D03*
X678838Y1185531D03*
X671358Y1159350D03*
X678838Y1170570D03*
X675098Y1166830D03*
X671358Y1170570D03*
X678838Y1159350D03*
X667618Y1166830D03*
X671358D03*
X667618Y1170570D03*
Y1159350D03*
X678839Y1166830D03*
X675098Y1170570D03*
Y1159350D03*
Y1144389D03*
X671358D03*
X667618D03*
X678838Y1148129D03*
X675098D03*
X671358D03*
X667618D03*
X697539Y1193011D03*
X693799D03*
X686319D03*
X682579D03*
X693799Y1174310D03*
X682579D03*
X697539Y1185531D03*
X693799D03*
X697539Y1178051D03*
X693799D03*
X686319Y1185531D03*
X682579D03*
X686319Y1178051D03*
X682579D03*
X686319Y1174310D03*
X693799Y1189271D03*
X697539D03*
X693799Y1181791D03*
X697539D03*
X686319D03*
X682579D03*
X686319Y1189271D03*
X682579D03*
X697539Y1174310D03*
X693799Y1166830D03*
X697539Y1170570D03*
Y1159350D03*
X686319D03*
Y1170570D03*
X682579Y1166830D03*
Y1170570D03*
X686319Y1166830D03*
X682579Y1159350D03*
X697539Y1166830D03*
X693799Y1170570D03*
Y1159350D03*
X697539Y1144389D03*
X693799D03*
X686319D03*
X682579D03*
X686319Y1155610D03*
Y1148129D03*
X682579D03*
X693799D03*
X697539D03*
Y1155610D03*
X693799D03*
X682579D03*
X686319Y1151870D03*
X682579D03*
X697539Y1151869D03*
X693799D03*
X682579Y1140649D03*
X686319D03*
X693799D03*
X697539D03*
X705020Y1193011D03*
X701279D03*
X712500D03*
X708760D03*
X712500Y1174310D03*
X708760D03*
X701279D03*
Y1185531D03*
X705020D03*
X712500D03*
X708760D03*
X701279Y1178051D03*
X705020D03*
X712500D03*
X708760D03*
X701279Y1189271D03*
X705020D03*
X708760D03*
X712500D03*
X701279Y1181791D03*
X705020D03*
X708760D03*
X712500D03*
X705020Y1174310D03*
X708760Y1166830D03*
X712500Y1170570D03*
X701279Y1166830D03*
X705020Y1170570D03*
Y1159350D03*
X712500D03*
X701279D03*
Y1170570D03*
X712500Y1166830D03*
X705020D03*
X708760Y1170570D03*
Y1159350D03*
Y1155610D03*
X701279D03*
Y1151869D03*
X705020D03*
X712500D03*
X708760D03*
X701279Y1144389D03*
X705020D03*
X712500D03*
X708760D03*
X701279Y1148129D03*
X705020D03*
X708760D03*
X712500D03*
X705020Y1155610D03*
X712500D03*
X701279Y1140649D03*
X705020D03*
X708760D03*
X712500D03*
X723720Y1185531D03*
X716240D03*
X719980D03*
X723720Y1178051D03*
X716240D03*
X719980D03*
X727460Y1189271D03*
X716240D03*
X719980D03*
X723720D03*
X727460Y1185531D03*
X716240Y1181791D03*
X719980D03*
X723720D03*
Y1170570D03*
X719980D03*
X727460Y1166830D03*
X723720D03*
Y1159350D03*
X727460D03*
X719980D03*
Y1166830D03*
X716240Y1170570D03*
Y1159350D03*
Y1166830D03*
X723720Y1144389D03*
X719980D03*
X716240Y1148129D03*
X719980D03*
X723720D03*
X727460Y1144389D03*
Y1148129D03*
Y1151869D03*
Y1155610D03*
X719980D03*
X723720D03*
X716240D03*
Y1151869D03*
X723720D03*
X719980D03*
X716240Y1144389D03*
X727460Y1140649D03*
X716240D03*
X719980D03*
X723720D03*
X716240Y1193011D03*
X723720D03*
X719980D03*
X727460D03*
X719980Y1174310D03*
X723720D03*
X716240D03*
X731201Y1166830D03*
Y1159350D03*
Y1155610D03*
Y1151869D03*
Y1148129D03*
X1645374D03*
Y1151869D03*
Y1155610D03*
Y1159350D03*
Y1166830D03*
X1630413Y1174310D03*
X1637893D03*
X1634153D03*
X1641633Y1193011D03*
X1634153D03*
X1637893D03*
X1630413D03*
X1637893Y1140649D03*
X1634153D03*
X1630413D03*
X1641633D03*
X1630413Y1144389D03*
X1634153Y1151869D03*
X1637893D03*
X1630413D03*
Y1155610D03*
X1637893D03*
X1634153D03*
X1641633D03*
Y1151869D03*
Y1148129D03*
Y1144389D03*
X1637893Y1148129D03*
X1634153D03*
X1630413D03*
X1634153Y1144389D03*
X1637893D03*
X1630413Y1166830D03*
Y1159350D03*
Y1170570D03*
X1634153Y1166830D03*
Y1159350D03*
X1641633D03*
X1637893D03*
Y1166830D03*
X1641633D03*
X1634153Y1170570D03*
X1637893D03*
Y1181791D03*
X1634153D03*
X1630413D03*
X1641633Y1185531D03*
X1637893Y1189271D03*
X1634153D03*
X1630413D03*
X1641633D03*
X1634153Y1178051D03*
X1630413D03*
X1637893D03*
X1634153Y1185531D03*
X1630413D03*
X1637893D03*
X1626673Y1140649D03*
X1622933D03*
X1619193D03*
X1615452D03*
X1626673Y1155610D03*
X1619193D03*
X1626673Y1148129D03*
X1622933D03*
X1619193D03*
X1615452D03*
X1622933Y1144389D03*
X1626673D03*
X1619193D03*
X1615452D03*
X1622933Y1151869D03*
X1626673D03*
X1619193D03*
X1615452D03*
Y1155610D03*
X1622933D03*
Y1159350D03*
Y1170570D03*
X1619193Y1166830D03*
X1626673D03*
X1615452Y1170570D03*
Y1159350D03*
X1626673D03*
X1619193D03*
Y1170570D03*
X1615452Y1166830D03*
X1626673Y1170570D03*
X1622933Y1166830D03*
X1619193Y1174310D03*
X1626673Y1181791D03*
X1622933D03*
X1619193D03*
X1615452D03*
X1626673Y1189271D03*
X1622933D03*
X1619193D03*
X1615452D03*
X1622933Y1178051D03*
X1626673D03*
X1619193D03*
X1615452D03*
X1622933Y1185531D03*
X1626673D03*
X1619193D03*
X1615452D03*
Y1174310D03*
X1622933D03*
X1626673D03*
X1622933Y1193011D03*
X1626673D03*
X1615452D03*
X1619193D03*
X1611712Y1140649D03*
X1607972D03*
X1600492D03*
X1596752D03*
X1607972Y1151869D03*
X1611712D03*
X1596752Y1151870D03*
X1600492D03*
X1596752Y1155610D03*
X1607972D03*
X1611712D03*
Y1148129D03*
X1607972D03*
X1596752D03*
X1600492D03*
Y1155610D03*
X1596752Y1144389D03*
X1600492D03*
X1607972D03*
X1611712D03*
X1607972Y1159350D03*
Y1170570D03*
X1611712Y1166830D03*
X1596752Y1159350D03*
X1600492Y1166830D03*
X1596752Y1170570D03*
Y1166830D03*
X1600492Y1170570D03*
Y1159350D03*
X1611712D03*
Y1170570D03*
X1607972Y1166830D03*
X1611712Y1174310D03*
X1596752Y1189271D03*
X1600492D03*
X1596752Y1181791D03*
X1600492D03*
X1611712D03*
X1607972D03*
X1611712Y1189271D03*
X1607972D03*
X1600492Y1174310D03*
X1596752Y1178051D03*
X1600492D03*
X1596752Y1185531D03*
X1600492D03*
X1607972Y1178051D03*
X1611712D03*
X1607972Y1185531D03*
X1611712D03*
X1596752Y1174310D03*
X1607972D03*
X1596752Y1193011D03*
X1600492D03*
X1607972D03*
X1611712D03*
X1581791Y1148129D03*
X1585531D03*
X1589271D03*
X1593011D03*
X1581791Y1144389D03*
X1585531D03*
X1589271D03*
Y1159350D03*
Y1170570D03*
X1593012Y1166830D03*
X1581791Y1159350D03*
Y1170570D03*
X1585531Y1166830D03*
X1581791D03*
X1593011Y1159350D03*
X1585531Y1170570D03*
X1589271Y1166830D03*
X1593011Y1170570D03*
X1585531Y1159350D03*
X1593011Y1185531D03*
X1581791Y1174310D03*
X1589271D03*
X1585531D03*
X1593011D03*
X1581791Y1189271D03*
X1585531D03*
X1589271D03*
X1593011D03*
X1581791Y1181791D03*
X1585531D03*
X1589271D03*
X1593011D03*
X1581791Y1178051D03*
X1585531D03*
X1589271D03*
X1593011D03*
X1581791Y1185531D03*
X1585531D03*
X1589271D03*
X1585531Y1193011D03*
X1589271D03*
X1593011D03*
X1581791D03*
X1593011Y1140649D03*
X1589271D03*
X1585531D03*
X1581791D03*
X1593011Y1144389D03*
X1581791Y1151870D03*
X1585531D03*
X1589271D03*
X1593012D03*
X1589271Y1155610D03*
X1581791D03*
X1585531D03*
X1593011D03*
X1578051Y1174310D03*
Y1185531D03*
X1570571Y1178051D03*
X1574311D03*
X1578051D03*
X1570571Y1185531D03*
X1574311D03*
X1566830Y1174310D03*
Y1181791D03*
X1574311Y1174310D03*
X1566830Y1178051D03*
X1570571Y1174310D03*
X1566830Y1185531D03*
X1570571Y1193011D03*
X1574311D03*
X1578051D03*
Y1140649D03*
X1574311D03*
X1570571D03*
X1566830D03*
X1578051Y1155610D03*
X1566830Y1144389D03*
X1570571Y1148129D03*
X1574311D03*
X1578051D03*
X1566830Y1151869D03*
X1570571Y1155610D03*
Y1144389D03*
X1574311D03*
X1578051D03*
X1570571Y1151870D03*
X1574311D03*
X1578051D03*
X1566830Y1155610D03*
Y1148129D03*
X1574311Y1155610D03*
X1570571Y1166830D03*
X1566830Y1170570D03*
X1574311D03*
Y1159350D03*
X1566830D03*
X1570571D03*
X1566830Y1166830D03*
X1578051Y1159350D03*
X1570571Y1170570D03*
X1574311Y1166830D03*
X1578051Y1170570D03*
Y1166830D03*
X1566830Y1189271D03*
X1570571D03*
X1574311D03*
X1578051D03*
X1570571Y1181791D03*
X1574311D03*
X1578051D03*
X1559350Y1144389D03*
X1551870D03*
X1555610Y1148129D03*
X1551870Y1151870D03*
Y1155610D03*
Y1148129D03*
X1555610Y1155610D03*
X1563090Y1151869D03*
Y1144389D03*
X1559350Y1155610D03*
X1555610Y1151870D03*
X1559350Y1148129D03*
X1563090D03*
Y1155610D03*
X1559350Y1151870D03*
Y1170570D03*
X1555610Y1166830D03*
X1551870D03*
X1563090D03*
X1551870Y1159350D03*
X1559350D03*
X1563090Y1170570D03*
Y1159350D03*
X1555610Y1170570D03*
X1559350Y1166830D03*
X1555610Y1159350D03*
X1559350Y1178051D03*
X1563090Y1174310D03*
X1555610D03*
X1563090Y1178051D03*
Y1185531D03*
X1559350Y1174310D03*
Y1181791D03*
X1555610Y1178051D03*
X1559350Y1185531D03*
X1563090Y1181791D03*
X1555610D03*
X1544389Y1155610D03*
Y1151870D03*
Y1148129D03*
Y1144389D03*
Y1166830D03*
Y1159350D03*
%LPD*%
G75*
G54D10*
G01X16304Y1468196D02*
Y1487975D01*
X13069Y1491210D01*
Y1497966D01*
X9701Y1501334D01*
X6489D01*
G01X109306Y149106D02*
X82890D01*
X81119Y150877D01*
X74759D01*
X71422Y147540D01*
G01X211668Y149106D02*
X185252D01*
X183481Y150877D01*
X177121D01*
X173784Y147540D01*
G01X314030Y149106D02*
X287614D01*
X285843Y150877D01*
X279483D01*
X276146Y147540D01*
G01X464031Y149106D02*
X437615D01*
X435844Y150877D01*
X429484D01*
X426147Y147540D01*
G01X566393Y149106D02*
X539977D01*
X538206Y150877D01*
X531846D01*
X528509Y147540D01*
G01X554696Y1018469D02*
X555319Y1017846D01*
Y1004711D01*
X548658Y998050D01*
Y974569D01*
X552238Y970989D01*
Y959102D01*
G01X668755Y149106D02*
X642339D01*
X640568Y150877D01*
X634208D01*
X630871Y147540D01*
G01X771117Y149106D02*
X744701D01*
X742930Y150877D01*
X736570D01*
X733233Y147540D01*
G01X861425Y770500D02*
Y767500D01*
X862099Y766826D01*
Y754598D01*
X863443Y753254D01*
G01D02*
X865888Y750809D01*
Y737979D01*
X879517Y724350D01*
Y713305D01*
X877901Y711689D01*
Y709533D01*
X881197Y706237D01*
Y704236D01*
X889221Y696212D01*
Y679732D01*
X883378Y673889D01*
Y673876D01*
X883318Y673816D01*
Y673731D01*
X883309Y673722D01*
Y666608D01*
G01X867000Y774000D02*
X865500Y775500D01*
Y781425D01*
X861425Y785500D01*
Y788500D01*
G01Y806500D02*
Y804076D01*
X863404Y802097D01*
Y795596D01*
X867000Y792000D01*
G01Y810000D02*
X865843Y811157D01*
Y815497D01*
X861425Y819915D01*
Y824500D01*
G01X867000Y774000D02*
X867936Y773064D01*
Y765868D01*
X865320Y763252D01*
Y756321D01*
X868688Y752953D01*
Y739139D01*
X882746Y725081D01*
Y714343D01*
X883997Y713092D01*
Y705396D01*
X892021Y697372D01*
Y677851D01*
X886304Y672134D01*
Y666650D01*
G01X892461Y666671D02*
Y666769D01*
X892460Y666770D01*
Y674018D01*
X892304Y674174D01*
X896253Y678123D01*
Y737480D01*
X895745Y737988D01*
Y738223D01*
X895579Y738389D01*
Y738510D01*
X887989Y746100D01*
X887988D01*
Y746114D01*
X887928Y746174D01*
Y746259D01*
X887919Y746268D01*
Y767689D01*
X875130Y780478D01*
Y783870D01*
X867000Y792000D01*
G01X900753Y656925D02*
X899389Y658289D01*
Y738660D01*
X890719Y747330D01*
Y768849D01*
X883387Y776181D01*
Y786169D01*
X881337Y788219D01*
X875841D01*
X867218Y796842D01*
Y809782D01*
X867000Y810000D01*
G01X921117Y149106D02*
X894701D01*
X892930Y150877D01*
X886570D01*
X883233Y147540D01*
G01X1023479Y149106D02*
X997063D01*
X995292Y150877D01*
X988932D01*
X985595Y147540D01*
G01X1125841Y149106D02*
X1099425D01*
X1097654Y150877D01*
X1091294D01*
X1087957Y147540D01*
G01X1228203Y149106D02*
X1201787D01*
X1200016Y150877D01*
X1193656D01*
X1190319Y147540D01*
G01X1297852Y1014475D02*
Y1011253D01*
X1277500Y990901D01*
Y935701D01*
X1279350Y933851D01*
X1283450D01*
X1286621Y930680D01*
Y910303D01*
X1283494Y907176D01*
G01X1378204Y149106D02*
X1351788D01*
X1350017Y150877D01*
X1343657D01*
X1340320Y147540D01*
G01X1480566Y149106D02*
X1454150D01*
X1452379Y150877D01*
X1446019D01*
X1442682Y147540D01*
G01X1582928Y149106D02*
X1556512D01*
X1554741Y150877D01*
X1548381D01*
X1545044Y147540D01*
G01X1685290Y149106D02*
X1658874D01*
X1657103Y150877D01*
X1650743D01*
X1647406Y147540D01*
X3704Y5374D03*
X3017Y24773D03*
Y44773D03*
Y64773D03*
Y84773D03*
Y104773D03*
Y124773D03*
Y144773D03*
Y164773D03*
Y184773D03*
Y204773D03*
Y224773D03*
Y244773D03*
Y264773D03*
Y284773D03*
Y304773D03*
X3221Y324773D03*
X3035Y978036D03*
Y998036D03*
Y1018036D03*
Y1038036D03*
Y1058036D03*
Y1078036D03*
Y1098036D03*
Y1118036D03*
Y1138036D03*
Y1158036D03*
Y1178036D03*
Y1198036D03*
Y1238036D03*
Y1258036D03*
Y1278036D03*
Y1298036D03*
Y1318036D03*
Y1338036D03*
Y1358036D03*
Y1378036D03*
Y1398036D03*
Y1418036D03*
Y1438036D03*
Y1458036D03*
Y1478036D03*
Y1498036D03*
Y1538036D03*
Y1558036D03*
Y1578036D03*
X3017Y1639466D03*
X15972Y3000D03*
X8786Y88425D03*
X18298Y102141D03*
X8000Y102500D03*
X7036Y272371D03*
X10971Y333342D03*
X17964Y349298D03*
Y369298D03*
Y389298D03*
Y409298D03*
Y429298D03*
Y449298D03*
Y469298D03*
Y489298D03*
Y509298D03*
Y529298D03*
Y549298D03*
Y569298D03*
Y589298D03*
Y609298D03*
Y629298D03*
Y649298D03*
Y669298D03*
Y689298D03*
Y709298D03*
Y729298D03*
Y749298D03*
Y769298D03*
Y789298D03*
Y809298D03*
Y829298D03*
Y849298D03*
Y869298D03*
Y889298D03*
Y909298D03*
Y929298D03*
X9554Y961954D03*
X17964Y949298D03*
X20079Y1429347D03*
X16304Y1468196D03*
X13606Y1476707D03*
X6690Y1496782D03*
X19365Y1494298D03*
X6489Y1501334D03*
X8042Y1522199D03*
X12327Y1519202D03*
X7983Y1529035D03*
Y1525635D03*
X7922Y1532494D03*
X11995Y1535134D03*
X6567Y1554215D03*
X14375Y1553121D03*
X18409Y1554202D03*
X12000Y1644980D03*
X26956Y4469D03*
X28317Y24773D03*
Y44773D03*
X35638Y53597D03*
X26588Y97667D03*
X22935Y162073D03*
Y159073D03*
X30567Y195176D03*
X28067D03*
X25567D03*
X33067D03*
X29585Y199248D03*
X32585D03*
X29921Y206806D03*
X32585Y202048D03*
X25648Y210509D03*
X28148D03*
X29585Y201748D03*
X27421Y206806D03*
X32201Y238714D03*
X23479Y295619D03*
X34845Y291756D03*
X35650Y487982D03*
Y478982D03*
Y483982D03*
Y499982D03*
X25819Y531726D03*
Y536726D03*
Y552726D03*
Y540726D03*
X32452Y581222D03*
X29652D03*
X35252D03*
Y591215D03*
X29652D03*
X32452D03*
X34254Y611091D03*
X29451Y633560D03*
X36692Y641817D03*
X30369Y663048D03*
X27625Y663094D03*
X25818Y682139D03*
X27854Y671553D03*
X30414Y671508D03*
X28818Y682139D03*
X26596Y874520D03*
X26844Y920354D03*
X24132Y958151D03*
X25371Y980696D03*
X21196Y1065529D03*
Y1063029D03*
X36089Y1062601D03*
Y1065101D03*
X35925Y1075663D03*
X33425D03*
X28996Y1065529D03*
X23796D03*
X26396D03*
Y1063029D03*
X23796D03*
X28996D03*
X28606Y1082678D03*
X23406D03*
X26006D03*
Y1080178D03*
X23406D03*
X28606D03*
X20806Y1082678D03*
Y1080178D03*
X27934Y1204311D03*
X30934D03*
X30410Y1218497D03*
Y1220997D03*
X27934Y1215511D03*
X30934D03*
X34314Y1215403D03*
X27934Y1212711D03*
Y1209911D03*
Y1207111D03*
X30934Y1212711D03*
Y1209911D03*
Y1207111D03*
X30410Y1234797D03*
Y1232297D03*
Y1227897D03*
Y1225397D03*
Y1241697D03*
Y1239197D03*
X22284Y1464612D03*
X35825Y1464845D03*
X21544Y1479662D03*
X33536Y1467485D03*
X21544Y1489648D03*
X25674Y1486291D03*
X32195Y1511279D03*
X32079Y1525641D03*
Y1521641D03*
Y1517641D03*
X35237Y1532096D03*
X31237D03*
X35850Y1556096D03*
X32000Y1644980D03*
X46931Y130670D03*
X49236Y121658D03*
X46932Y137756D03*
X52437D03*
X42690Y451466D03*
X48596Y458466D03*
X39643Y555194D03*
X36843D03*
X49839Y546830D03*
X39643Y563194D03*
X36843D03*
X39643Y571194D03*
X36843D03*
X42192Y641817D03*
X51449Y822718D03*
X47949D03*
X49265Y886660D03*
X52922Y900295D03*
X47916Y947622D03*
X43889Y1062601D03*
X38689D03*
X41289D03*
Y1065101D03*
X38689D03*
X43889D03*
X44960Y1190619D03*
X49500Y1199066D03*
X49638Y1203884D03*
X51197Y1218206D03*
X39452Y1250932D03*
X39225Y1464845D03*
X40996Y1467703D03*
X44195Y1511279D03*
X48195D03*
X40195D03*
X48079Y1525641D03*
Y1529641D03*
Y1521641D03*
X39237Y1532096D03*
X52048Y1556062D03*
X52000Y1644980D03*
X55638Y53597D03*
X56098Y109410D03*
Y116496D03*
X64098Y109410D03*
Y116496D03*
X56098Y123583D03*
Y130670D03*
X64098Y123583D03*
Y130670D03*
Y137756D03*
X69261Y211695D03*
Y208695D03*
X65189Y210713D03*
Y213213D03*
Y208213D03*
X54733Y212978D03*
Y215478D03*
Y207978D03*
Y210478D03*
X65189Y215713D03*
X60562Y264180D03*
X58062D03*
X66956Y267526D03*
Y270026D03*
X58279Y293796D03*
X66293Y285690D03*
X68793D03*
X66293Y288190D03*
X68793D03*
X60779Y293796D03*
X65759Y437508D03*
X61759D03*
X57759D03*
X54936Y449352D03*
X59522Y448874D03*
X68619Y447269D03*
X68497Y450201D03*
X66224Y473045D03*
X58224D03*
X53643Y472905D03*
X66371Y482134D03*
Y484634D03*
X59670Y500086D03*
X64550Y504699D03*
X62050D03*
X59550D03*
X68236Y519458D03*
X61752Y516979D03*
X64252D03*
X59252D03*
X60233Y521804D03*
X68202Y522129D03*
X64495Y527449D03*
X60233Y524304D03*
X56540Y531378D03*
Y528878D03*
X61695Y527449D03*
X68202Y527129D03*
Y524629D03*
Y529629D03*
X67622Y572842D03*
X64408Y572975D03*
X62789Y608311D03*
X66510Y628242D03*
X55318Y629362D03*
X53129Y627948D03*
X55307Y688473D03*
X60849Y826818D03*
X64649D03*
X58949Y821018D03*
X64849Y840418D03*
X60249D03*
X66342Y880067D03*
X67316Y865869D03*
X64175Y897500D03*
X67461Y912983D03*
X63303Y912835D03*
X57178Y981386D03*
X58250Y1220896D03*
X65940Y1209382D03*
X58250Y1227796D03*
Y1230296D03*
Y1237196D03*
Y1234696D03*
Y1223396D03*
X57185Y1480808D03*
X57144Y1491047D03*
X56114Y1556061D03*
X68743Y1583498D03*
X60554Y1612002D03*
X66291Y1633801D03*
X74432Y5374D03*
X73745Y24773D03*
Y44773D03*
X73110Y98551D03*
X73509Y110445D03*
X78501D03*
X73509Y115401D03*
X78501D03*
X83911Y117557D03*
X76660Y103783D03*
X73509Y129574D03*
Y124618D03*
X78501Y129574D03*
Y124618D03*
X83911Y122513D03*
Y131731D03*
Y136687D03*
X71422Y147540D03*
Y151540D03*
X72575Y181426D03*
X75786Y181366D03*
X78581Y181009D03*
X83756Y168697D03*
X75400Y184012D03*
X72783Y184221D03*
X72061Y208695D03*
X71761Y211695D03*
X76819Y213859D03*
Y211359D03*
X80522Y213132D03*
Y215632D03*
X72256Y267526D03*
X69756D03*
Y270026D03*
X72256D03*
X71593Y285690D03*
Y288190D03*
X75819Y290755D03*
X79819D03*
X83819D03*
X71826Y480705D03*
X74326D03*
X69816Y475946D03*
Y478446D03*
X78033Y478586D03*
Y481086D03*
Y476086D03*
Y483586D03*
X73236Y519458D03*
X70736D03*
X71995Y532749D03*
X74795D03*
X75777Y585507D03*
X71184D03*
X71730Y579475D03*
X71228Y590145D03*
X75822Y590190D03*
X75684Y605443D03*
X83684D03*
X81740Y636250D03*
X69670Y633205D03*
Y636005D03*
X81740Y633450D03*
X69670Y638805D03*
X81740Y639050D03*
X78129Y656900D03*
X72314Y680207D03*
Y683407D03*
X82714Y674707D03*
X74414Y681907D03*
X72549Y838818D03*
X71928Y873683D03*
X76991Y946134D03*
X70947Y1201565D03*
Y1205835D03*
X87000Y1597855D03*
X76005Y1580680D03*
X82433Y1580590D03*
X74291Y1633801D03*
X72000Y1644980D03*
X93334Y3000D03*
X88903Y117557D03*
Y122513D03*
Y131731D03*
X87002Y146461D03*
X88903Y136687D03*
X85904Y152367D03*
X87604Y180572D03*
X92287Y180527D03*
X96010Y192421D03*
X92242Y185121D03*
X87604Y185165D03*
X89353Y206767D03*
X86853D03*
X91853D03*
X89483Y221708D03*
X86983D03*
X86398Y224421D03*
X88098Y231021D03*
Y228221D03*
X96333Y221642D03*
X91983Y221708D03*
X93649Y236189D03*
X91149D03*
X88649D03*
X91090Y248765D03*
X88590D03*
X93590D03*
X97747Y265897D03*
X100247D03*
X94087Y270695D03*
X91287D03*
X88787D03*
Y268195D03*
X91287D03*
X94087D03*
X94390Y293645D03*
Y290845D03*
Y288345D03*
X91890Y293645D03*
Y290845D03*
Y288345D03*
X95943Y377953D03*
X90257Y445506D03*
X93456Y649838D03*
X89432Y668293D03*
X92134D03*
X85614Y674707D03*
X87714Y684607D03*
X88875Y840940D03*
X91581Y877859D03*
Y874859D03*
X87853Y899220D03*
X86291Y1633801D03*
X92000Y1644980D03*
X113334Y3000D03*
X109329Y248371D03*
X112474Y716315D03*
X114397Y727974D03*
X113601Y881266D03*
X107641Y865224D03*
X103124Y1172564D03*
X108971D03*
X103124Y1159964D03*
X108971D03*
X103861Y1182703D03*
X109415Y1202103D03*
X106586Y1204932D03*
X112795Y1223749D03*
X107669Y1456451D03*
Y1465913D03*
X116330Y1465513D03*
X107669Y1461182D03*
X116330Y1460782D03*
X107669Y1481267D03*
X116330Y1480867D03*
X107669Y1476536D03*
X116330Y1476136D03*
Y1470244D03*
X107669Y1471805D03*
X116330Y1491490D03*
Y1485598D03*
X107669Y1487159D03*
Y1496621D03*
X116330Y1496221D03*
X107669Y1491890D03*
X116330Y1506845D03*
Y1500952D03*
X107669Y1502514D03*
X116330Y1511576D03*
X107669Y1511976D03*
Y1507245D03*
X116330Y1516307D03*
X107669Y1563544D03*
X116330Y1563144D03*
X107669Y1558813D03*
Y1568275D03*
X116330Y1567875D03*
X107669Y1578898D03*
X116330Y1578498D03*
Y1572606D03*
X107669Y1574167D03*
Y1583629D03*
X116330Y1583229D03*
X107669Y1594253D03*
X116330Y1593853D03*
Y1587960D03*
X107669Y1589522D03*
Y1609607D03*
X116330Y1609207D03*
X107669Y1598984D03*
X116330Y1598584D03*
Y1603315D03*
X107669Y1604876D03*
X116330Y1613938D03*
Y1618669D03*
X107669Y1614338D03*
X112000Y1644980D03*
X129318Y4469D03*
X130679Y24773D03*
Y44773D03*
X128950Y97667D03*
X119333Y116594D03*
Y119594D03*
X131947Y199248D03*
X127929Y195176D03*
X130429D03*
X132929D03*
X134947Y199248D03*
X128010Y210509D03*
X130510D03*
X132283Y206806D03*
X129783D03*
X131947Y201748D03*
X125125Y362403D03*
X118122Y747565D03*
X122887Y884000D03*
X127067Y891495D03*
X124474Y1168197D03*
X130434Y1170164D03*
X131000Y1180266D03*
X124765Y1180691D03*
X121211Y1215195D03*
X126937Y1209607D03*
X124992Y1465913D03*
Y1456451D03*
Y1461182D03*
X133653Y1465513D03*
Y1460782D03*
X124992Y1471805D03*
Y1476536D03*
Y1481267D03*
X133653Y1476136D03*
Y1470244D03*
Y1480867D03*
Y1496221D03*
X124992Y1487159D03*
Y1491890D03*
Y1496621D03*
X133653Y1491490D03*
Y1485598D03*
Y1506845D03*
Y1500952D03*
Y1511576D03*
X124992Y1511976D03*
Y1507245D03*
Y1502514D03*
X133653Y1516307D03*
X124992Y1558813D03*
Y1563544D03*
X133653Y1563144D03*
Y1567875D03*
X124992Y1574167D03*
Y1578898D03*
X133653Y1578498D03*
Y1572606D03*
X124992Y1568275D03*
Y1589522D03*
Y1594253D03*
X133653Y1593853D03*
Y1587960D03*
X124992Y1583629D03*
X133653Y1583229D03*
X124992Y1609607D03*
Y1604876D03*
Y1598984D03*
X133653Y1609207D03*
Y1598584D03*
Y1603315D03*
X124992Y1614338D03*
X133653Y1613938D03*
Y1618669D03*
X132000Y1644980D03*
X138000Y53597D03*
X149827Y130670D03*
X149822Y137756D03*
X135429Y195176D03*
X134947Y202048D03*
X134563Y238714D03*
X148061Y378600D03*
X148692Y391001D03*
Y394401D03*
Y405174D03*
X140690Y401513D03*
Y398113D03*
X148692Y408574D03*
X138290Y412287D03*
X148692Y419347D03*
Y422747D03*
X138290Y415687D03*
Y426460D03*
X148692Y433521D03*
X138290Y429860D03*
X148692Y436921D03*
X138290Y440633D03*
X148176Y458711D03*
X136604Y450750D03*
X138290Y444033D03*
X145376Y458711D03*
X138290Y469387D03*
Y472787D03*
X148692Y476499D03*
X138290Y483560D03*
X148692Y490673D03*
X138290Y486960D03*
X148692Y479899D03*
Y494073D03*
Y524033D03*
Y520633D03*
X138290Y516921D03*
Y513521D03*
Y531094D03*
X148692Y538206D03*
Y534806D03*
X138290Y527694D03*
X142315Y1456451D03*
Y1461182D03*
Y1465913D03*
Y1471805D03*
Y1476536D03*
Y1481267D03*
Y1487159D03*
Y1491890D03*
Y1496621D03*
Y1507245D03*
Y1502514D03*
Y1511976D03*
Y1558813D03*
Y1563544D03*
Y1574167D03*
Y1578898D03*
Y1568275D03*
Y1589522D03*
Y1594253D03*
Y1583629D03*
Y1609607D03*
Y1604876D03*
Y1598984D03*
Y1614338D03*
X158000Y53597D03*
X158460Y116496D03*
Y109410D03*
X166460Y116496D03*
Y109410D03*
X158460Y130670D03*
Y123583D03*
X166460D03*
Y130670D03*
X155051Y137756D03*
X166460D03*
X157095Y210478D03*
Y207978D03*
Y215478D03*
Y212978D03*
X160424Y264180D03*
X162924D03*
X163141Y293796D03*
X160641D03*
X166528Y312392D03*
X157375Y555234D03*
X159637Y1461182D03*
X150976Y1465513D03*
Y1460782D03*
X159637Y1465913D03*
Y1456451D03*
X150976Y1476136D03*
Y1470244D03*
Y1480867D03*
X159637Y1471805D03*
Y1476536D03*
Y1481267D03*
Y1496621D03*
X150976Y1491490D03*
Y1485598D03*
Y1496221D03*
X159637Y1487159D03*
Y1491890D03*
X150976Y1500952D03*
Y1511576D03*
X159637Y1507245D03*
Y1502514D03*
Y1511976D03*
X150976Y1506845D03*
Y1516307D03*
X159637Y1558813D03*
Y1563544D03*
X150976Y1563144D03*
X159637Y1578898D03*
X150976Y1567875D03*
Y1578498D03*
Y1572606D03*
X159637Y1568275D03*
Y1574167D03*
X150976Y1583229D03*
Y1593853D03*
Y1587960D03*
X159637Y1583629D03*
Y1589522D03*
Y1594253D03*
X150976Y1609207D03*
Y1598584D03*
Y1603315D03*
X159637Y1609607D03*
Y1604876D03*
Y1598984D03*
X150976Y1613938D03*
Y1618669D03*
X159637Y1614338D03*
X152000Y1644980D03*
X176794Y5374D03*
X176107Y24773D03*
Y44773D03*
X175472Y98551D03*
X175871Y110445D03*
X180863Y115401D03*
Y110445D03*
X175871Y115401D03*
X179022Y103783D03*
X180863Y129574D03*
Y124618D03*
X175871Y129574D03*
Y124618D03*
X173784Y147540D03*
Y151540D03*
X178148Y181366D03*
X180943Y181009D03*
X174937Y181426D03*
X175145Y184221D03*
X177762Y184012D03*
X171623Y211695D03*
X182884Y213132D03*
X179181Y211359D03*
Y213859D03*
X174123Y211695D03*
X167551Y208213D03*
Y213213D03*
Y210713D03*
X171623Y208695D03*
X174423D03*
X167551Y215713D03*
X182884Y215632D03*
X174618Y267526D03*
Y270026D03*
X169318Y267526D03*
X172118D03*
Y270026D03*
X169318D03*
X173955Y285690D03*
Y288190D03*
X171155Y285690D03*
X168655Y288190D03*
X171155D03*
X168655Y285690D03*
X182181Y290755D03*
X178181D03*
X177369Y389154D03*
Y396240D03*
Y403327D03*
Y410413D03*
Y417500D03*
Y424587D03*
Y431673D03*
Y438760D03*
Y445847D03*
Y467539D03*
Y474626D03*
Y488799D03*
Y481713D03*
Y495886D03*
Y511673D03*
Y518760D03*
Y525847D03*
Y532933D03*
Y540020D03*
Y547106D03*
X176650Y602197D03*
X177114Y595108D03*
X168299Y1465513D03*
Y1460782D03*
X176960Y1465914D03*
Y1456452D03*
Y1461183D03*
X168299Y1476136D03*
Y1470244D03*
Y1480867D03*
X176960Y1476537D03*
Y1471806D03*
Y1481268D03*
X168299Y1491490D03*
Y1485598D03*
Y1496221D03*
X176960Y1491891D03*
Y1487160D03*
Y1496622D03*
Y1507246D03*
Y1502515D03*
X168299Y1506845D03*
Y1500952D03*
Y1511576D03*
X176960Y1511977D03*
X168299Y1516307D03*
Y1563144D03*
X176960Y1563544D03*
Y1558813D03*
Y1568275D03*
X168299Y1578498D03*
Y1572606D03*
Y1567875D03*
Y1583229D03*
X176960Y1583629D03*
X168299Y1593853D03*
Y1587960D03*
X176960Y1594253D03*
Y1589522D03*
X168299Y1609207D03*
Y1598584D03*
Y1603315D03*
X176960Y1609607D03*
Y1598984D03*
Y1604876D03*
X168299Y1613938D03*
Y1618669D03*
X176960Y1614338D03*
X172000Y1644980D03*
X195697Y3000D03*
X186273Y117557D03*
X191265D03*
X185957Y106186D03*
X186273Y131731D03*
Y122513D03*
X191265D03*
Y131731D03*
X189364Y146461D03*
X186273Y136687D03*
X191265D03*
X188266Y152367D03*
X194649Y180527D03*
X189966Y180572D03*
X186118Y168697D03*
X198372Y192421D03*
X189966Y185165D03*
X194604Y185121D03*
X189215Y206767D03*
X191715D03*
X194215D03*
X194345Y221708D03*
X198695Y221642D03*
X190460Y228221D03*
Y231021D03*
X191845Y221708D03*
X188760Y224421D03*
X189345Y221708D03*
X191011Y236189D03*
X193511D03*
X196011D03*
X190952Y248765D03*
X193452D03*
X195952D03*
X196449Y268195D03*
X193649D03*
X196449Y270695D03*
X193649D03*
X191149D03*
Y268195D03*
X196752Y293645D03*
Y290845D03*
Y288345D03*
X194252Y293645D03*
Y290845D03*
Y288345D03*
X186181Y290755D03*
X191988Y389154D03*
X185169D03*
Y396240D03*
X186448Y404911D03*
X190518Y396240D03*
X194603Y422864D03*
X186589Y426299D03*
X185402Y412571D03*
X195295Y414823D03*
X194673Y429832D03*
X194278Y436447D03*
X186900Y445847D03*
X196313Y447953D03*
X185169Y467539D03*
X195480D03*
X185169Y474626D03*
X194222Y472772D03*
X194956Y487711D03*
X195069Y479104D03*
X185430Y480828D03*
X187380Y498834D03*
X195480Y495886D03*
X190829Y516841D03*
X194080Y510565D03*
X185169Y518760D03*
Y511673D03*
Y525847D03*
X185654Y552872D03*
X185776Y550123D03*
X185099Y562443D03*
X186867Y560675D03*
X187408Y572334D03*
X185640Y574102D03*
X191125Y602400D03*
Y598400D03*
Y594400D03*
Y606400D03*
Y614400D03*
X193723Y656942D03*
X185622Y1465513D03*
Y1460782D03*
Y1480868D03*
Y1476137D03*
Y1470244D03*
Y1485599D03*
X192000Y1644980D03*
X203248Y55513D03*
X199473Y68581D03*
X199486Y80581D03*
X202195Y117261D03*
X211691Y248371D03*
X200109Y265897D03*
X202609D03*
X215380Y389153D03*
X210580D03*
X203280Y389154D03*
X204675Y382109D03*
X215380Y396240D03*
X208080Y403327D03*
X215380Y403326D03*
X210580D03*
X208080Y410413D03*
X210580D03*
X215380D03*
X203280Y396240D03*
Y403327D03*
Y410413D03*
X208080Y396240D03*
X210580D03*
X208080Y417500D03*
X215380Y417499D03*
X210580D03*
X208080Y424586D03*
X210580D03*
X215380D03*
X203280Y417500D03*
Y424586D03*
X208080Y431673D03*
Y438760D03*
X210580D03*
X215380D03*
Y431673D03*
X210580D03*
X203280D03*
Y438760D03*
Y445847D03*
X208080D03*
X215380Y467539D03*
X210580D03*
X203280D03*
X208080Y474626D03*
X210580D03*
X215380D03*
X203280D03*
X215380Y488799D03*
X203280D03*
X208080D03*
X210580D03*
X203280Y481713D03*
X210580Y481712D03*
X208080D03*
X215380D03*
X208080Y495886D03*
X203280D03*
X215380Y518760D03*
X210580D03*
X208080D03*
X210580Y511673D03*
X215380D03*
X203280D03*
Y518760D03*
X210580Y532933D03*
X208080D03*
Y540020D03*
Y525846D03*
X210580D03*
X215380D03*
Y532933D03*
X203280Y525847D03*
Y532933D03*
Y540020D03*
Y547106D03*
Y554193D03*
X212460Y560500D03*
X203740Y567914D03*
Y565414D03*
Y570414D03*
X204674Y558917D03*
Y561420D03*
X203740Y575414D03*
Y572914D03*
X200495Y577937D03*
X203280Y602205D03*
Y595118D03*
X209429Y625300D03*
X205941Y668934D03*
X213296Y1438215D03*
X215697Y3000D03*
X231681Y4469D03*
X231312Y97667D03*
X221695Y116594D03*
Y119594D03*
X230291Y195176D03*
X230372Y210509D03*
X228760Y316122D03*
X228267Y392718D03*
Y408718D03*
Y400718D03*
Y404718D03*
Y412718D03*
X221375Y455024D03*
X225500Y530000D03*
X225000Y540500D03*
X223925Y543925D03*
X224500Y555000D03*
X222646Y607542D03*
X217945Y1423924D03*
X217799Y1433684D03*
X222253Y1438483D03*
X229260Y1469587D03*
X218171Y1474460D03*
X224780Y1478149D03*
X217985Y1483055D03*
X225765Y1471985D03*
X224176Y1492816D03*
X221899Y1488800D03*
X218021Y1494724D03*
X222843Y1498442D03*
X217614Y1489671D03*
X222908Y1502028D03*
X226957Y1510442D03*
X226135Y1502442D03*
X230758Y1505046D03*
X226971Y1514578D03*
X216342Y1515642D03*
X227552Y1530675D03*
X232622Y1531104D03*
X226971Y1522578D03*
X219981Y1530797D03*
X223322Y1518578D03*
X222119Y1539941D03*
X227882Y1540816D03*
X233753Y1539752D03*
X233042Y24773D03*
Y44773D03*
X240363Y53597D03*
X232791Y195176D03*
X235291D03*
X237309Y199248D03*
X234309D03*
X237791Y195176D03*
X237309Y202048D03*
X232872Y210509D03*
X234645Y206806D03*
X232145D03*
X234309Y201748D03*
X236925Y238714D03*
X236349Y339428D03*
X245362Y546712D03*
X247333Y599506D03*
X241967Y616063D03*
X243278Y618288D03*
X243078Y636486D03*
X240249Y628328D03*
X241084Y638243D03*
X246583Y665140D03*
X250102Y656321D03*
X246102D03*
X241850Y678462D03*
X235790Y754332D03*
X248556Y824003D03*
X247600Y848500D03*
X232675Y1466801D03*
X240466Y1503857D03*
X243268Y1501903D03*
X243535Y1511473D03*
X245500Y1517033D03*
X237633Y1511909D03*
X240808Y1519942D03*
X235687Y1522578D03*
X237580Y1528604D03*
X245937Y1524237D03*
X239949Y1541327D03*
X260363Y53597D03*
X260822Y116496D03*
Y109410D03*
Y130670D03*
Y123583D03*
X252189Y130670D03*
X257413Y137756D03*
X252184D03*
X259457Y210478D03*
Y207978D03*
Y215478D03*
Y212978D03*
X262786Y264180D03*
X263003Y293796D03*
X257226Y312081D03*
X265011Y403307D03*
X255000Y427017D03*
X254692Y431029D03*
X253758Y435029D03*
X254512Y438323D03*
X254678Y449873D03*
X261605Y465492D03*
Y472579D03*
X259105D03*
X254305D03*
X249125Y465874D03*
X261605Y486752D03*
X254305D03*
X259105Y479666D03*
X261605D03*
X254305D03*
X259105Y486752D03*
X254305Y493839D03*
X259105D03*
X261605Y516713D03*
X259105D03*
Y523800D03*
X261605D03*
X254305D03*
Y516713D03*
X261605Y509626D03*
Y530886D03*
X259105D03*
Y537973D03*
X254305Y530886D03*
Y537973D03*
Y566752D03*
X261605Y559665D03*
Y566752D03*
X259105D03*
X261605Y588012D03*
X259105Y588013D03*
X254305Y573839D03*
X261605D03*
X259105D03*
X261605Y580926D03*
X259105D03*
X254305D03*
Y588013D03*
X259105Y602186D03*
X254305D03*
Y595099D03*
X259105D03*
X261605D03*
Y602185D03*
X254305Y609272D03*
X259105D03*
X261605D03*
X259105Y616359D03*
X254305D03*
X248984Y638125D03*
X258867Y680499D03*
X251802Y824128D03*
X255289Y824340D03*
X255909Y1542043D03*
X279156Y5374D03*
X278469Y24773D03*
Y44773D03*
X277834Y98551D03*
X268822Y116496D03*
Y109410D03*
X278233Y115401D03*
Y110445D03*
X268822Y130670D03*
Y123583D03*
X278233Y129574D03*
Y124618D03*
X268822Y137756D03*
X276146Y147540D03*
Y151540D03*
X277299Y181426D03*
X280124Y184012D03*
X277507Y184221D03*
X269913Y210713D03*
X273985Y208695D03*
X276785D03*
X273985Y211695D03*
X276485D03*
X269913Y208213D03*
Y213213D03*
Y215713D03*
X265286Y264180D03*
X276980Y267526D03*
Y270026D03*
X271680Y267526D03*
X274480D03*
Y270026D03*
X271680D03*
X276317Y288190D03*
X273517Y285690D03*
X271017Y288190D03*
X273517D03*
X271017Y285690D03*
X265503Y293796D03*
X276317Y285690D03*
X274425Y390500D03*
X265011Y410394D03*
X265945Y440098D03*
Y437598D03*
Y435098D03*
Y432598D03*
Y430098D03*
X266405Y451319D03*
Y458406D03*
X274205Y466027D03*
X266405Y465492D03*
X266229Y462264D03*
X274347Y475262D03*
X266405Y472579D03*
X274347Y489435D03*
Y482666D03*
X266405Y479665D03*
Y486752D03*
Y493839D03*
X274163Y495088D03*
X266405Y523799D03*
Y516713D03*
Y509626D03*
X274205D03*
X274820Y522134D03*
X274898Y514608D03*
X266405Y530886D03*
Y537973D03*
X275463Y529136D03*
X275302Y535677D03*
X266405Y566752D03*
Y559665D03*
X274586Y565574D03*
X274205Y559665D03*
X266405Y580926D03*
Y588012D03*
Y573839D03*
X274233Y574338D03*
X266405Y602185D03*
Y595099D03*
Y609272D03*
Y616358D03*
X274332D03*
X269700Y884600D03*
X269900Y914200D03*
X270100Y946500D03*
X272000Y1644980D03*
X288635Y117557D03*
X283225Y115401D03*
Y110445D03*
X293627Y117557D03*
X281384Y103783D03*
X288319Y106186D03*
X288635Y131731D03*
Y122513D03*
X283225Y129574D03*
Y124618D03*
X293627Y122513D03*
Y131731D03*
X291726Y146461D03*
X293627Y136687D03*
X288635D03*
X290628Y152367D03*
X292328Y180572D03*
X280510Y181366D03*
X283305Y181009D03*
X288480Y168697D03*
X292328Y185165D03*
X291577Y206767D03*
X294077D03*
X296577D03*
X285246Y213132D03*
X281543Y211359D03*
Y213859D03*
X296707Y221708D03*
X292822Y228221D03*
Y231021D03*
X294207Y221708D03*
X291122Y224421D03*
X291707Y221708D03*
X285246Y215632D03*
X293373Y236189D03*
X295873D03*
X293314Y248765D03*
X295814D03*
X296011Y270695D03*
X293511D03*
Y268195D03*
X296011D03*
X296614Y293645D03*
Y290845D03*
Y288345D03*
X284543Y290755D03*
X280543D03*
X288543D03*
X284075Y381500D03*
X292500Y410394D03*
Y403307D03*
X284295Y430760D03*
X284316Y433570D03*
X284132Y437072D03*
X284173Y439963D03*
X284417Y443180D03*
X284437Y454744D03*
X284379Y452018D03*
X292316Y458406D03*
X284482Y460250D03*
X284516Y465492D03*
X282247Y470136D03*
X292316Y465492D03*
X284516Y472579D03*
X292316D03*
X284516Y479665D03*
Y486752D03*
X292316Y479665D03*
Y486752D03*
Y493839D03*
X284516D03*
X292316Y523799D03*
Y516713D03*
Y509626D03*
X284516Y516713D03*
Y509626D03*
X292316Y537973D03*
Y530886D03*
X283377Y532756D03*
X283456Y525483D03*
X280976Y537973D03*
X284516Y559665D03*
Y566752D03*
X292316Y559665D03*
Y566752D03*
X284366Y579978D03*
X292316Y573839D03*
Y588012D03*
Y580925D03*
X284516Y573839D03*
X292316Y595099D03*
Y602185D03*
X284580Y608117D03*
X292316Y616358D03*
Y609272D03*
X292000Y1644980D03*
X298059Y3000D03*
X305610Y55513D03*
X301835Y68581D03*
X301848Y80581D03*
X304557Y117261D03*
X297011Y180527D03*
X299759Y190285D03*
X296966Y185121D03*
X301057Y221642D03*
X298373Y236189D03*
X298314Y248765D03*
X302471Y265897D03*
X304971D03*
X298811Y270695D03*
Y268195D03*
X299114Y290845D03*
Y288345D03*
Y293645D03*
X302966Y324139D03*
X310013Y316731D03*
X306812Y342319D03*
X301943Y332017D03*
X301158Y380307D03*
X309258Y389912D03*
Y393924D03*
Y385912D03*
X301308Y395346D03*
X301393Y400039D03*
X309258Y409924D03*
Y405924D03*
Y401924D03*
X306673Y418838D03*
X298507Y445908D03*
X302457Y445787D03*
X312000Y1644980D03*
X318059Y3000D03*
X324057Y116594D03*
Y119594D03*
X314053Y248371D03*
X323882Y303839D03*
X319857Y321649D03*
X315904Y336324D03*
X320483Y353506D03*
X321549Y445315D03*
Y448115D03*
X320993Y467306D03*
Y470706D03*
Y481479D03*
Y484879D03*
Y514839D03*
Y511439D03*
Y525613D03*
Y529013D03*
X324291Y556775D03*
X320993Y564879D03*
Y561479D03*
Y575652D03*
Y579052D03*
Y603999D03*
Y593225D03*
Y589825D03*
Y607399D03*
X334043Y4469D03*
X335404Y24773D03*
Y44773D03*
X342725Y53597D03*
X333674Y97667D03*
X335153Y195176D03*
X332653D03*
X336671Y199248D03*
X337653Y195176D03*
X340153D03*
X339671Y199248D03*
X336671Y201748D03*
X334507Y206806D03*
X337007D03*
X335234Y210509D03*
X332734D03*
X339671Y202048D03*
X339287Y238714D03*
X345050Y458334D03*
X331395Y474418D03*
Y488591D03*
Y477818D03*
Y491991D03*
Y518552D03*
Y521952D03*
Y536125D03*
Y532725D03*
X338358Y554861D03*
X331395Y568591D03*
Y571991D03*
Y586165D03*
Y582765D03*
Y600338D03*
Y596938D03*
Y611111D03*
Y614511D03*
X332000Y1644980D03*
X354551Y130670D03*
X359525Y137756D03*
X354546D03*
X356423Y301288D03*
X348375Y322284D03*
X348968Y333138D03*
X348737Y375386D03*
X354486Y377173D03*
X357173Y392183D03*
X357218Y396866D03*
X361234Y402867D03*
X358042Y442518D03*
Y439718D03*
X347450Y447486D03*
X353670Y488618D03*
Y491118D03*
X359278Y491870D03*
X356778D03*
X358096Y867459D03*
X358086Y884616D03*
X357962Y898800D03*
X358024Y912085D03*
X358085Y923327D03*
X352000Y1644980D03*
X362725Y53597D03*
X363184Y116496D03*
Y109410D03*
X371184Y116496D03*
Y109410D03*
X363184Y130670D03*
Y123583D03*
X371184Y130670D03*
Y123583D03*
Y137756D03*
X372275Y208213D03*
X379147Y208695D03*
X376347D03*
Y211695D03*
X372275Y210713D03*
Y213213D03*
X361819Y207978D03*
Y212978D03*
Y215478D03*
Y210478D03*
X372275Y215713D03*
X367648Y264180D03*
X365148D03*
X374042Y270026D03*
X376842D03*
X374042Y267526D03*
X376842D03*
X365365Y293796D03*
X367865D03*
X373379Y288190D03*
X375879Y285690D03*
X373379D03*
X375879Y288190D03*
X368057Y354184D03*
X364933Y374232D03*
X373264Y370010D03*
X361767Y392228D03*
X376992Y395248D03*
X368587Y409016D03*
X364551Y409032D03*
X361811Y396866D03*
X375919Y449118D03*
Y446318D03*
X364954Y450091D03*
X367919Y449118D03*
Y446318D03*
X376099Y458309D03*
Y454309D03*
X367564Y452740D03*
X376099Y462309D03*
X369282Y468088D03*
Y465288D03*
X366443Y472189D03*
X365332Y490070D03*
Y487570D03*
X361887Y493758D03*
Y496258D03*
X373504Y517954D03*
X370415Y766108D03*
X377020Y782535D03*
X373101Y779608D03*
X376300Y779800D03*
X368491Y815092D03*
X368273Y928100D03*
X375040Y932959D03*
X371424Y937185D03*
X367944Y946082D03*
X370214Y959812D03*
Y967812D03*
X372000Y1644980D03*
X388059Y3000D03*
X381518Y5374D03*
X380831Y24773D03*
X383612Y33768D03*
X380831Y44773D03*
X380196Y98551D03*
X390997Y117557D03*
X385587Y115401D03*
X380595D03*
X385587Y110445D03*
X380595D03*
X383746Y103783D03*
X390681Y106186D03*
X390997Y131731D03*
Y122513D03*
X385587Y129574D03*
X380595D03*
X385587Y124618D03*
X380595D03*
X390997Y136687D03*
X382872Y181366D03*
X379661Y181426D03*
X385667Y181009D03*
X390842Y168697D03*
X382486Y184012D03*
X379869Y184221D03*
X393939Y206767D03*
X383905Y211359D03*
X387608Y213132D03*
X378847Y211695D03*
X383905Y213859D03*
X394069Y221708D03*
X393484Y224421D03*
X387608Y215632D03*
X379342Y270026D03*
Y267526D03*
X378679Y285690D03*
Y288190D03*
X386905Y290755D03*
X382905D03*
X390905D03*
X392387Y337599D03*
Y342555D03*
X389237Y371070D03*
X385237Y370976D03*
X396373Y407104D03*
X392444Y401949D03*
X393893Y413611D03*
X393833Y423944D03*
X385584Y450041D03*
Y452841D03*
Y455641D03*
X393837Y466409D03*
X393823Y487382D03*
X393652Y482382D03*
X393746Y478382D03*
X388593Y664232D03*
X386350Y693559D03*
X391478Y690675D03*
X379800Y778000D03*
X387692Y790056D03*
X393547D03*
X392415Y792725D03*
X389015D03*
X386614Y868286D03*
X391614Y938651D03*
X385512Y955356D03*
X390150Y955312D03*
Y959905D03*
X385467Y959950D03*
X381377Y1003008D03*
X381045Y1009444D03*
X387587Y1296675D03*
X387644Y1302089D03*
X391284Y1307238D03*
X382017Y1555700D03*
Y1547700D03*
Y1551700D03*
X392000Y1644980D03*
X408059Y3000D03*
X408680Y37530D03*
X396680Y37543D03*
X408493Y117577D03*
X395989Y117557D03*
Y131731D03*
Y122513D03*
Y136687D03*
X399373Y180527D03*
X394690Y180572D03*
X403096Y192421D03*
X394690Y185165D03*
X399328Y185121D03*
X398939Y206767D03*
X396439D03*
X395184Y228221D03*
X399069Y221708D03*
X396569D03*
X403419Y221642D03*
X395184Y231021D03*
X400735Y236189D03*
X398235D03*
X395735D03*
X400676Y248765D03*
X398176D03*
X395676D03*
X407333Y265897D03*
X404833D03*
X401173Y268195D03*
Y270695D03*
X398373Y268195D03*
X395873D03*
Y270695D03*
X398373D03*
X398976Y293645D03*
X401476D03*
Y288345D03*
Y290845D03*
X398976Y288345D03*
Y290845D03*
X409484Y314921D03*
X398951Y333711D03*
X397374Y344439D03*
X394883Y341777D03*
Y338377D03*
X407493Y354142D03*
X394237Y370899D03*
X396373Y409904D03*
X409268Y408240D03*
X406843Y399161D03*
Y401661D03*
Y396661D03*
X394944Y398949D03*
X399518Y402642D03*
X402018D03*
X396633Y423944D03*
X409386Y420393D03*
X396693Y413611D03*
X399193D03*
X401693D03*
X401633Y423944D03*
X399133D03*
X395577Y455641D03*
Y450041D03*
Y452841D03*
X397315Y479560D03*
X405603Y668060D03*
X408103D03*
X403103D03*
X400603D03*
Y678060D03*
X405603D03*
X408103D03*
X403103D03*
X409284Y741316D03*
X400900Y755400D03*
X400914Y762675D03*
X408300Y755487D03*
X400900Y770100D03*
X407965Y770196D03*
X408400Y795200D03*
Y792200D03*
X406600Y789000D03*
X402376Y842677D03*
X399876D03*
X402376Y850677D03*
X399876D03*
X406967Y878764D03*
X406415Y874840D03*
X407193Y883566D03*
X401121Y936686D03*
X409121Y939186D03*
X401121D03*
X409121Y936686D03*
X396182Y955858D03*
X402682Y948536D03*
X402815Y951750D03*
X399285Y1081599D03*
X398915Y1097278D03*
X396415D03*
X409231Y1123101D03*
X406105Y1139435D03*
X410131Y1129301D03*
X407631D03*
X409231Y1125801D03*
X406105Y1131935D03*
Y1134435D03*
Y1136935D03*
Y1141935D03*
Y1146935D03*
Y1144435D03*
X403263Y1152684D03*
X406319Y1204405D03*
X404004Y1198321D03*
Y1200821D03*
X406319Y1206905D03*
Y1211905D03*
Y1209405D03*
X397695Y1287071D03*
X399716Y1295198D03*
X408937Y1351568D03*
X395959Y1352153D03*
X403981Y1351568D03*
X403029Y1379716D03*
X403111Y1384920D03*
X408212Y1379695D03*
X403111Y1390103D03*
X408212Y1390083D03*
X410152Y1410928D03*
X398112Y1403741D03*
X401711Y1419771D03*
X406667D03*
X401990Y1446807D03*
X399731Y1442755D03*
X407469Y1495035D03*
X407854Y1492118D03*
X406377Y1499142D03*
X397245Y1511640D03*
X404053Y1513673D03*
X397220Y1521207D03*
X400911Y1537902D03*
X407048D03*
X400911Y1544424D03*
X407048Y1549936D03*
X400911D03*
X409461Y1569560D03*
X405461D03*
X426147Y147540D03*
Y151540D03*
X422873Y309966D03*
X419955Y306966D03*
X414999D03*
X411984Y314921D03*
X421231Y338523D03*
Y331255D03*
Y345776D03*
X413432Y346797D03*
X416318Y367903D03*
X424479Y367859D03*
X418876Y401661D03*
Y396661D03*
X411768Y408240D03*
X414268D03*
X418876Y399161D03*
X411847Y424240D03*
X414386Y420393D03*
X411886D03*
X411847Y426740D03*
X415453Y455039D03*
X418754Y468607D03*
X411754Y474513D03*
X424731Y508152D03*
Y513452D03*
Y515952D03*
X414275Y508217D03*
Y510717D03*
Y515717D03*
Y513217D03*
X424731Y510952D03*
X419040Y533690D03*
Y528390D03*
Y530990D03*
Y536290D03*
Y538890D03*
X423266Y631438D03*
X420266D03*
X417666D03*
X420266Y637038D03*
Y634238D03*
X417666Y637038D03*
Y634238D03*
X423266Y637038D03*
Y634238D03*
X418226Y653288D03*
X423266Y642638D03*
X420266D03*
X417666D03*
X423266Y639838D03*
X420266D03*
X418226Y646480D03*
Y648980D03*
X417666Y639838D03*
X418226Y655788D03*
X410603Y668060D03*
Y678060D03*
X415700Y755400D03*
X415696Y762466D03*
X415700Y770200D03*
X422430Y834800D03*
X424649Y842644D03*
X422149D03*
Y850644D03*
X424649D03*
X422149Y858644D03*
X424649D03*
X425759Y869921D03*
Y872721D03*
Y875521D03*
Y867121D03*
X422379Y867229D03*
X425759Y878321D03*
X411214Y892109D03*
X425121Y936686D03*
Y939186D03*
X417121Y936686D03*
Y939186D03*
X417677Y1052215D03*
X425175Y1098767D03*
X417171Y1098887D03*
X419987Y1098518D03*
X419731Y1123101D03*
X417231D03*
X422631Y1125801D03*
X425131Y1129301D03*
X422631D03*
X420131D03*
X417631D03*
X415131D03*
X412631D03*
X420131Y1125801D03*
X417631D03*
X425131D03*
X422495Y1152713D03*
Y1155213D03*
X412095Y1152713D03*
Y1155213D03*
X422934Y1200821D03*
Y1198321D03*
X420619Y1204617D03*
X417469Y1200821D03*
Y1198321D03*
X420619Y1207117D03*
Y1209617D03*
Y1212117D03*
X425702Y1257160D03*
X422702Y1260160D03*
Y1257160D03*
X425702Y1260160D03*
X419702Y1257160D03*
Y1260160D03*
X418537Y1300197D03*
X423741Y1300115D03*
X413354Y1300197D03*
X425582Y1291743D03*
X423762Y1305298D03*
X413374D03*
X418558Y1310523D03*
X413395Y1310481D03*
X423721Y1310523D03*
X414280Y1362561D03*
X413437Y1379736D03*
Y1384899D03*
X425283Y1373958D03*
X413395Y1390062D03*
X411147Y1474993D03*
X419818Y1474945D03*
X415241Y1492990D03*
X415095Y1502750D03*
X411353Y1519440D03*
X419467Y1519706D03*
X420279Y1525978D03*
X410626Y1525991D03*
X413012Y1537902D03*
Y1544098D03*
X426196Y1534087D03*
X413012Y1549936D03*
X421616Y1549885D03*
X413461Y1569560D03*
X412000Y1644980D03*
X428059Y3000D03*
X441727Y146461D03*
X440629Y152367D03*
X435703Y306966D03*
X430747D03*
X427829Y309966D03*
X428459Y331255D03*
X435793D03*
X428500Y345776D03*
X435793Y345738D03*
X430439Y358115D03*
X435702Y367813D03*
X430746D03*
X433724Y433975D03*
X432310Y436164D03*
X427782Y464026D03*
X442704Y506427D03*
X427693Y506520D03*
X438396Y511493D03*
X438353Y508685D03*
X427693Y509020D03*
X432700Y516277D03*
X435834Y509580D03*
X428740Y533690D03*
X442704Y533790D03*
X428740Y528390D03*
Y530990D03*
X442704Y528490D03*
Y531090D03*
X428740Y536290D03*
X431804Y536682D03*
X428740Y538890D03*
X431804Y539182D03*
X442704Y536390D03*
X439804Y536682D03*
X442704Y538990D03*
X439804Y539182D03*
X436369Y622883D03*
X441832Y626193D03*
X441612Y631011D03*
X429210Y784833D03*
X428759Y869921D03*
Y867121D03*
Y872721D03*
Y875521D03*
Y878321D03*
X432332Y892049D03*
Y897649D03*
Y894849D03*
Y900449D03*
X433206Y1055498D03*
X430706D03*
Y1057998D03*
X433206D03*
Y1060498D03*
Y1062998D03*
X430706D03*
Y1060498D03*
X441359Y1123101D03*
X438233Y1139435D03*
X441359Y1125801D03*
X439759Y1129301D03*
X442259D03*
X429331Y1136935D03*
Y1134435D03*
Y1139435D03*
Y1131935D03*
X435733D03*
Y1134435D03*
Y1136935D03*
Y1139435D03*
X438233Y1131935D03*
Y1134435D03*
Y1136935D03*
X429331Y1141935D03*
X435733D03*
Y1146935D03*
Y1144435D03*
X438233Y1141935D03*
Y1146935D03*
Y1144435D03*
X437231Y1154902D03*
Y1152402D03*
X429331Y1146935D03*
Y1144435D03*
X433249Y1204405D03*
X430934Y1200821D03*
Y1198321D03*
X433249Y1209405D03*
Y1211905D03*
Y1206905D03*
X440702Y1260160D03*
Y1257160D03*
X437702Y1260160D03*
Y1257160D03*
X428702D03*
X431702Y1260160D03*
Y1257160D03*
X434702Y1260160D03*
Y1257160D03*
X428702Y1260160D03*
X437991Y1286544D03*
X440896Y1311366D03*
X432485Y1325784D03*
X436002Y1382252D03*
X437675Y1550158D03*
X430657Y1563562D03*
X429784Y1548222D03*
X432000Y1644980D03*
X448059Y3000D03*
X458454Y328963D03*
Y324007D03*
Y339755D03*
Y344711D03*
X453463Y370694D03*
X448092Y375770D03*
X446179Y447101D03*
X453544Y461961D03*
X451144Y472809D03*
Y468809D03*
X443094Y491251D03*
X459645Y509486D03*
X452404Y533690D03*
Y528390D03*
Y530990D03*
X455104Y536582D03*
X452404Y536290D03*
X455104Y539082D03*
X452404Y538890D03*
X447279Y633881D03*
X448726Y653288D03*
Y646480D03*
Y648980D03*
Y655788D03*
X447836Y711199D03*
X454815Y974622D03*
X448999Y994483D03*
X456210Y1004680D03*
X452319Y1000828D03*
X449731Y1000855D03*
X453710Y1018825D03*
X443091Y1022766D03*
Y1030266D03*
X450063Y1043140D03*
X459700Y1032266D03*
X449767Y1047047D03*
X450244Y1090268D03*
X457303Y1098767D03*
X452115Y1098518D03*
X446863Y1098428D03*
X450244Y1093068D03*
X449359Y1123101D03*
X451859D03*
X457259Y1129301D03*
X449759Y1125801D03*
X452259D03*
X444759Y1129301D03*
X447259D03*
X449759D03*
X452259D03*
X454759Y1125801D03*
X457259D03*
X454759Y1129301D03*
X443223Y1155213D03*
Y1152713D03*
X452623D03*
Y1155213D03*
X447549Y1204617D03*
X449864Y1198321D03*
Y1200821D03*
X447549Y1209617D03*
Y1207117D03*
Y1212117D03*
X449702Y1260160D03*
Y1257160D03*
X443702Y1260160D03*
X446702D03*
Y1257160D03*
X443702D03*
X456213Y1286776D03*
X451889Y1301067D03*
X451304Y1293045D03*
X456832Y1299121D03*
X451889Y1306023D03*
X454125Y1471805D03*
Y1487159D03*
Y1502514D03*
Y1558813D03*
Y1574167D03*
Y1589522D03*
Y1604876D03*
X452000Y1644980D03*
X468059Y3000D03*
X474058Y116594D03*
Y119594D03*
X464054Y248371D03*
X461454Y336837D03*
Y331881D03*
Y347629D03*
Y352585D03*
X466375Y366365D03*
X470389Y389553D03*
X473658Y467215D03*
X471048Y464566D03*
X468558Y491669D03*
Y503669D03*
Y507669D03*
Y499669D03*
Y512669D03*
X463104Y536582D03*
X468850Y537507D03*
X463104Y539082D03*
X461849Y668016D03*
X459349D03*
X466849D03*
X469349D03*
X464349D03*
X469349Y678016D03*
X466849D03*
X459349D03*
X461849D03*
X464349D03*
X462242Y809792D03*
X475032Y843252D03*
X474678Y857919D03*
X463134Y859203D03*
X460455Y867050D03*
X475046Y885952D03*
X467494Y924532D03*
X469495Y1011303D03*
Y1023303D03*
Y1017303D03*
X462427Y1030218D03*
X459700Y1035716D03*
X460277Y1090268D03*
Y1093068D03*
X474818Y1123101D03*
X469192Y1131935D03*
X474818Y1125801D03*
X473218Y1129301D03*
X461459Y1136935D03*
Y1134435D03*
Y1139435D03*
Y1131935D03*
X471692Y1139435D03*
Y1136935D03*
Y1134435D03*
Y1131935D03*
X469192Y1139435D03*
Y1136935D03*
Y1134435D03*
X471692Y1146935D03*
Y1141935D03*
X469192Y1144435D03*
Y1146935D03*
Y1141935D03*
X471692Y1144435D03*
X461459D03*
X462687Y1152684D03*
X468850D03*
X461459Y1141935D03*
Y1146935D03*
X465785Y1197471D03*
X461285Y1193471D03*
Y1197471D03*
X465785Y1193471D03*
X461613Y1286776D03*
X462786Y1460782D03*
X471448Y1471805D03*
X462786Y1476136D03*
Y1491490D03*
X471448Y1487159D03*
Y1502514D03*
X462786Y1506845D03*
Y1563144D03*
X471448Y1558813D03*
X462786Y1578498D03*
X471448Y1574167D03*
X462786Y1593853D03*
X471448Y1589522D03*
X462786Y1609207D03*
X471448Y1604876D03*
X472000Y1644980D03*
X484043Y4469D03*
X485404Y24773D03*
Y44773D03*
X483675Y97667D03*
X487654Y195176D03*
X489672Y199248D03*
X485154Y195176D03*
X482654D03*
X486672Y199248D03*
X490154Y195176D03*
X485235Y210509D03*
X482735D03*
X489672Y202048D03*
X486672Y201748D03*
X484508Y206806D03*
X487008D03*
X489288Y238714D03*
X483242Y366481D03*
X483584Y375840D03*
X483736Y371266D03*
X483541Y380306D03*
X481724Y391589D03*
Y387089D03*
X488438Y425464D03*
X481485Y439900D03*
X482484Y444517D03*
X492736Y478982D03*
X482905Y531726D03*
X482737Y537215D03*
X482905Y552726D03*
Y540726D03*
X486738Y581222D03*
X489538D03*
Y591215D03*
X486738D03*
X491340Y611091D03*
X485005Y659771D03*
X491324Y667293D03*
X485303Y681841D03*
X484341Y700528D03*
Y705484D03*
X486246Y804497D03*
X485824Y819787D03*
X481593Y826387D03*
X491453Y834546D03*
X491527Y843206D03*
X488469Y857013D03*
X481943Y924633D03*
X488388Y938903D03*
X483636Y952152D03*
X490143Y989521D03*
X481495Y1011303D03*
X475495D03*
X481495Y1023303D03*
Y1017303D03*
X475495Y1023303D03*
X485678Y1039880D03*
X485633Y1036155D03*
X476148Y1057998D03*
Y1055498D03*
X478648D03*
Y1057998D03*
X476148Y1060498D03*
Y1062998D03*
X478648D03*
Y1060498D03*
X490762Y1098767D03*
X485574Y1098518D03*
X480322Y1098428D03*
X485318Y1123101D03*
X482818D03*
X490718Y1129301D03*
X483218Y1125801D03*
X485718D03*
X475718Y1129301D03*
X478218D03*
X480718D03*
X483218D03*
X485718D03*
X488218Y1125801D03*
X490718D03*
X488218Y1129301D03*
X477682Y1152713D03*
Y1155213D03*
X488082D03*
Y1152713D03*
X477206Y1198321D03*
X490671D03*
Y1200821D03*
X479521Y1204405D03*
X477206Y1200821D03*
X479521Y1206905D03*
Y1211905D03*
Y1209405D03*
X484800Y1302000D03*
X480109Y1460782D03*
Y1476136D03*
X488771Y1471805D03*
Y1487159D03*
X480109Y1491490D03*
Y1506845D03*
X488771Y1502514D03*
Y1558813D03*
X480109Y1563144D03*
Y1578498D03*
X488771Y1574167D03*
Y1589522D03*
X480109Y1593853D03*
X488771Y1604876D03*
X480109Y1609207D03*
X492725Y53597D03*
X506653Y121652D03*
X504552Y130670D03*
X504547Y137756D03*
X497424Y354559D03*
X492317Y376252D03*
X503682Y455466D03*
X497776Y448466D03*
X492736Y487982D03*
Y483982D03*
Y499982D03*
X506925Y546830D03*
X493929Y555194D03*
X496729D03*
X493929Y563194D03*
X496729D03*
X493929Y571194D03*
X496729D03*
X492338Y581222D03*
Y591215D03*
X499278Y641817D03*
X493778D03*
X494632Y654622D03*
X501618Y698355D03*
X499012Y699819D03*
X503311Y715652D03*
X500705Y705524D03*
X507546Y738539D03*
X505673Y767961D03*
X500717D03*
X504341Y812040D03*
X491655Y829173D03*
X506246Y824689D03*
X492799Y846488D03*
X503741Y846830D03*
X497467Y833027D03*
X499640Y861538D03*
X499595Y963963D03*
X493050Y976078D03*
X506566Y1000766D03*
Y1004766D03*
Y1016266D03*
Y1030766D03*
X505981Y1052487D03*
X506946Y1123101D03*
Y1125801D03*
X505346Y1129301D03*
X507846D03*
X503820Y1139435D03*
Y1136935D03*
Y1134435D03*
Y1131935D03*
X501320Y1139435D03*
Y1136935D03*
Y1134435D03*
Y1131935D03*
X494918Y1136935D03*
Y1134435D03*
Y1139435D03*
Y1131935D03*
X503820Y1144435D03*
Y1146935D03*
Y1141935D03*
X501320Y1144435D03*
Y1146935D03*
Y1141935D03*
X494918Y1146935D03*
Y1144435D03*
Y1141935D03*
X502562Y1152713D03*
Y1155213D03*
X506451Y1204405D03*
X504136Y1198321D03*
Y1200821D03*
X493821Y1204617D03*
X496136Y1200821D03*
Y1198321D03*
X506451Y1206905D03*
Y1211905D03*
Y1209405D03*
X493821Y1207117D03*
Y1209617D03*
Y1212117D03*
X497432Y1460782D03*
Y1476136D03*
X506093Y1471805D03*
X497432Y1491490D03*
X506093Y1487159D03*
X497432Y1506845D03*
X506093Y1502514D03*
X497432Y1563144D03*
X506093Y1558813D03*
X497432Y1578498D03*
X506093Y1574167D03*
Y1589522D03*
X497432Y1593853D03*
X506093Y1604876D03*
X497432Y1609207D03*
X492000Y1644980D03*
X512725Y53597D03*
X513185Y116496D03*
Y109410D03*
X521185Y116496D03*
Y109410D03*
X513185Y130670D03*
Y123583D03*
X521185Y130670D03*
Y123583D03*
X509251Y137756D03*
X521185D03*
X511820Y207978D03*
Y210478D03*
Y215478D03*
Y212978D03*
X522276Y208213D03*
Y213213D03*
Y210713D03*
Y215713D03*
X515149Y264180D03*
X517649D03*
X524043Y270026D03*
Y267526D03*
X517866Y293796D03*
X515366D03*
X523380Y285690D03*
Y288190D03*
X511342Y311124D03*
X520845Y434508D03*
X516845D03*
X512845D03*
X514608Y445874D03*
X510022Y446352D03*
X523705Y444269D03*
X523583Y447201D03*
X508729Y469905D03*
X521310Y470045D03*
X513310D03*
X523457Y482134D03*
Y484634D03*
X521636Y504699D03*
X516636D03*
X519136D03*
X516756Y500086D03*
X517319Y521804D03*
X516338Y516979D03*
X521338D03*
X518838D03*
X513626Y528578D03*
Y531378D03*
X518781Y527449D03*
X517319Y524304D03*
X521581Y527449D03*
X521494Y572975D03*
X519875Y608311D03*
X523596Y628242D03*
X512404Y629362D03*
X510215Y627948D03*
X518812Y665867D03*
X511990Y686365D03*
X518001Y694940D03*
X522410Y694881D03*
X518067Y699378D03*
X518530Y703584D03*
X522628Y703884D03*
X508237Y723585D03*
X512502Y738539D03*
X516953Y738575D03*
X521909D03*
X520159Y758832D03*
X509063Y782867D03*
X517194Y773232D03*
X522316Y793574D03*
X509316Y793224D03*
X508130Y787488D03*
X521178Y814001D03*
X521565Y820931D03*
X520720Y846133D03*
X517832Y834558D03*
X508049Y877789D03*
X523272Y880067D03*
X509428Y888390D03*
X521115Y897500D03*
X511025Y911443D03*
X509673Y900295D03*
X516256Y939157D03*
X524475Y952290D03*
X514886Y952189D03*
X509471Y981608D03*
X519792Y1031271D03*
X515831Y1090568D03*
X517702Y1098518D03*
X512450Y1098428D03*
X515831Y1093068D03*
X522890Y1098767D03*
X514946Y1123101D03*
X517446D03*
X522846Y1129301D03*
X515346Y1125801D03*
X517846D03*
X510346Y1129301D03*
X512846D03*
X515346D03*
X517846D03*
X520346Y1125801D03*
X522846D03*
X520346Y1129301D03*
X518210Y1155213D03*
Y1152713D03*
X508810D03*
Y1155213D03*
X520751Y1204617D03*
X523066Y1200821D03*
Y1198321D03*
X520751Y1207117D03*
Y1209617D03*
Y1212117D03*
X517374Y1287222D03*
X514363Y1287370D03*
X520548Y1287181D03*
X514755Y1460782D03*
Y1476136D03*
Y1491490D03*
Y1506845D03*
Y1563144D03*
Y1578498D03*
Y1593853D03*
Y1609207D03*
X512000Y1644980D03*
X531518Y5374D03*
X530831Y24773D03*
Y44773D03*
X530197Y98551D03*
X530596Y115401D03*
X535588Y110445D03*
Y115401D03*
X530596Y110445D03*
X533747Y103783D03*
X530596Y124618D03*
Y129574D03*
X535588Y124618D03*
Y129574D03*
X528509Y147540D03*
Y151540D03*
X535668Y181009D03*
X529662Y181426D03*
X532873Y181366D03*
X529870Y184221D03*
X532487Y184012D03*
X533906Y211359D03*
Y213859D03*
X528848Y211695D03*
X537609Y213132D03*
X526348Y208695D03*
X529148D03*
X526348Y211695D03*
X537609Y215632D03*
X526843Y270026D03*
X529343D03*
X526843Y267526D03*
X529343D03*
X525880Y285690D03*
X528680D03*
X525880Y288190D03*
X528680D03*
X532906Y290755D03*
X536906D03*
X540906D03*
X533027Y351836D03*
X530215Y364422D03*
X535142Y397552D03*
X535119Y483886D03*
Y481086D03*
Y478586D03*
X526902Y478446D03*
Y475946D03*
X531412Y480705D03*
X535119Y476086D03*
X528612Y480705D03*
X525288Y522129D03*
X527936Y519544D03*
X525436D03*
X530436D03*
X525288Y524629D03*
Y527129D03*
Y529929D03*
X529481Y532849D03*
X532281D03*
X524708Y572842D03*
X532863Y585507D03*
X528270D03*
X528816Y579475D03*
X532908Y590190D03*
X528314Y590145D03*
X532770Y605443D03*
X538826Y633450D03*
X526756Y636005D03*
Y633205D03*
X538826Y636250D03*
Y639050D03*
X526756Y638805D03*
X524653Y643595D03*
X533486Y664052D03*
X538442D03*
X524941Y661387D03*
X530796D03*
X534940Y684489D03*
X539111Y681459D03*
X526956Y694959D03*
X526951Y699443D03*
X535387Y712617D03*
X526933Y703820D03*
X532628Y720776D03*
X526276Y721339D03*
X539763Y734097D03*
X534807D03*
X531763Y739097D03*
X526807D03*
X532450Y767474D03*
X542275Y760782D03*
X532278Y762736D03*
X532449Y782389D03*
X534672Y785037D03*
X531501Y792331D03*
X531260Y794934D03*
X531666Y815724D03*
X531313Y822693D03*
X527733Y847026D03*
X536641Y838649D03*
X537300Y842900D03*
X528868Y873683D03*
X533468Y878533D03*
X527346Y911458D03*
X528975Y898346D03*
X537279Y897943D03*
X528674Y964851D03*
X527046Y1131935D03*
Y1139435D03*
Y1134435D03*
Y1136935D03*
X528274Y1152684D03*
X527046Y1146935D03*
Y1144435D03*
Y1141935D03*
X532000Y1644980D03*
X550421Y3000D03*
X554198Y68581D03*
X554211Y80581D03*
X540998Y117557D03*
X545990D03*
X540682Y106186D03*
X545990Y122513D03*
Y131731D03*
X540998Y122513D03*
Y131731D03*
X544089Y146461D03*
X545990Y136687D03*
X540998D03*
X542991Y152367D03*
X549374Y180527D03*
X544691Y180572D03*
X540843Y168697D03*
X553097Y192421D03*
X549329Y185121D03*
X544691Y185165D03*
X548940Y206767D03*
X546440D03*
X543940D03*
X549070Y221708D03*
X546570D03*
X553420Y221642D03*
X545185Y231021D03*
Y228221D03*
X544070Y221708D03*
X543485Y224421D03*
X550736Y236189D03*
X548236D03*
X545736D03*
X550677Y248765D03*
X548177D03*
X545677D03*
X545874Y268195D03*
X548374D03*
X551174Y270695D03*
X554834Y265897D03*
X551174Y268195D03*
X548374Y270695D03*
X545874D03*
X551477Y288345D03*
Y290845D03*
X548977Y288345D03*
Y290845D03*
Y293645D03*
X551477D03*
X541644Y389047D03*
X553731Y388487D03*
X541706Y381723D03*
X552905Y430829D03*
X540770Y605443D03*
X550274Y658676D03*
X556574Y684031D03*
Y700031D03*
Y688987D03*
Y716031D03*
Y704987D03*
Y720987D03*
X552384Y762892D03*
X552188Y766577D03*
X542599Y782389D03*
X549168Y781600D03*
X545768D03*
X542546Y784911D03*
X554357Y784889D03*
X551524D03*
X553871Y811298D03*
X545741Y804149D03*
X548464Y823156D03*
X540807Y816556D03*
X541129Y828335D03*
Y838865D03*
X545981Y846389D03*
X549241Y841388D03*
X545237Y850319D03*
X548521Y877859D03*
Y874859D03*
X540968Y878360D03*
X545144Y909025D03*
X544793Y899220D03*
X552238Y959102D03*
X548215Y1006560D03*
X552923Y997860D03*
X541766Y1018368D03*
X554696Y1018469D03*
X557681Y1035088D03*
X557584Y1543411D03*
X552000Y1644980D03*
X570421Y3000D03*
X557973Y55513D03*
X556920Y117261D03*
X566416Y248371D03*
X557334Y265897D03*
X570634Y375453D03*
X559074Y696987D03*
Y692031D03*
Y712987D03*
Y708031D03*
X561886Y728138D03*
X559625Y739609D03*
X557813Y747814D03*
X570578Y749800D03*
X570695Y767052D03*
X564276Y776701D03*
X558241Y796389D03*
X562231Y784911D03*
X558294D03*
X569186Y787332D03*
X561401Y811242D03*
X567559Y812850D03*
X567316Y806224D03*
X561061Y803606D03*
X563099Y829943D03*
X560263Y829989D03*
X567316Y827724D03*
X559741Y822149D03*
X572171Y842346D03*
X559196Y846296D03*
X569577Y886913D03*
X560814Y901022D03*
X568503Y936807D03*
X565003D03*
X564923Y997860D03*
X560923D03*
X568923D03*
X556923D03*
X568362Y1008262D03*
X571857Y1009354D03*
X568362Y1011762D03*
X565451Y1035102D03*
X569520Y1102091D03*
X560211D03*
X566020D03*
X566058Y1109564D03*
X560211D03*
X566058Y1122164D03*
X560211D03*
X566058Y1134764D03*
X560211D03*
X566058Y1147364D03*
X560211D03*
X566058Y1159964D03*
X560211D03*
X566058Y1172564D03*
X560211D03*
Y1185164D03*
X570796Y1530309D03*
X565400Y1535100D03*
X563968Y1541445D03*
X568279Y1538438D03*
X572507Y1541375D03*
X586405Y4469D03*
X587766Y24773D03*
Y44773D03*
X586037Y97667D03*
X576420Y116594D03*
Y119594D03*
X587516Y195176D03*
X585016D03*
X589034Y199248D03*
X587597Y210509D03*
X585097D03*
X589034Y201748D03*
X586870Y206806D03*
X581487Y336676D03*
X573805Y728301D03*
X578271Y763556D03*
X583102Y767137D03*
X574620Y772724D03*
X584624Y781850D03*
X585912Y778470D03*
X588659Y790336D03*
X581001Y814123D03*
X583501Y800831D03*
X579758Y817753D03*
X579827Y884000D03*
X579251Y903364D03*
X582706Y908959D03*
X577903Y940907D03*
X581703D03*
X576003Y935107D03*
X581903Y954507D03*
X577303D03*
X577249Y965445D03*
X580923Y997860D03*
X576923D03*
X588923D03*
X577666Y1009354D03*
X581166D03*
X572923Y997860D03*
X584923D03*
X581166Y1021954D03*
X577666D03*
X581803Y1493687D03*
X578859Y1497758D03*
X582027Y1502800D03*
X581803Y1509687D03*
X577931Y1505687D03*
X575332Y1523740D03*
X583800Y1518000D03*
X583740Y1520640D03*
X575809Y1532912D03*
X583809Y1533025D03*
X579809Y1528163D03*
X587809Y1545854D03*
X583809Y1541607D03*
X577571Y1544013D03*
X595087Y53597D03*
X590016Y195176D03*
X592516D03*
X592034Y199248D03*
Y202048D03*
X589370Y206806D03*
X591650Y238714D03*
X590178Y309760D03*
X605147Y378600D03*
X597776Y401513D03*
Y398113D03*
X595376Y412287D03*
Y426460D03*
Y415687D03*
Y440633D03*
Y429860D03*
X593690Y450750D03*
X605262Y458711D03*
X595376Y444033D03*
X602462Y458711D03*
X595376Y469387D03*
Y472787D03*
Y483560D03*
Y486960D03*
Y513521D03*
Y516921D03*
Y531094D03*
Y527694D03*
X592238Y880612D03*
X597129Y913386D03*
X602385Y940920D03*
X589603Y952907D03*
X606142Y965665D03*
X596923Y997860D03*
X592923D03*
X604923D03*
X600923D03*
X602603Y1012354D03*
Y1024954D03*
X604405Y1034870D03*
X591898Y1035011D03*
X590957Y1105091D03*
Y1117691D03*
Y1130291D03*
Y1155491D03*
Y1142891D03*
Y1168091D03*
X595809Y1546214D03*
X591809Y1542407D03*
X615087Y53597D03*
X615547Y116496D03*
Y109410D03*
Y130670D03*
Y123583D03*
X606914Y130670D03*
X606909Y137756D03*
X612138D03*
X614182Y210478D03*
Y215478D03*
Y212978D03*
Y207978D03*
X617511Y264180D03*
X620011D03*
X617728Y293796D03*
X620228D03*
X605778Y391001D03*
Y405174D03*
Y394401D03*
Y408574D03*
Y422747D03*
Y419347D03*
Y433521D03*
Y436921D03*
Y479899D03*
Y490673D03*
Y476499D03*
Y494073D03*
Y520633D03*
Y524033D03*
Y534806D03*
Y538206D03*
X614461Y555234D03*
X612489Y941024D03*
X616923Y997860D03*
X608923D03*
X620151Y1040363D03*
X619086Y1056453D03*
X620715Y1046785D03*
X613738Y1546507D03*
X612000Y1644980D03*
X633248Y44884D03*
X632559Y98551D03*
X632958Y110445D03*
X623547Y109410D03*
Y116496D03*
X632958Y115401D03*
X636109Y103783D03*
X632958Y124618D03*
X623547Y123583D03*
Y130670D03*
X632958Y129574D03*
X623547Y137756D03*
X630871Y147540D03*
Y151540D03*
X632024Y181426D03*
X635235Y181366D03*
X632232Y184221D03*
X634849Y184012D03*
X628710Y211695D03*
Y208695D03*
X631510D03*
X624638Y208213D03*
X636268Y211359D03*
Y213859D03*
X631210Y211695D03*
X624638Y213213D03*
Y210713D03*
Y215713D03*
X629205Y267526D03*
X626405D03*
X631705D03*
X629205Y270026D03*
X626405D03*
X631705D03*
X631042Y288190D03*
Y285690D03*
X625742Y288190D03*
X628242Y285690D03*
X625742D03*
X628242Y288190D03*
X635268Y290755D03*
X634455Y389154D03*
Y396240D03*
Y403327D03*
Y410413D03*
Y417500D03*
Y424587D03*
Y431673D03*
Y438760D03*
Y445847D03*
Y467539D03*
Y474626D03*
Y488799D03*
Y481713D03*
Y495886D03*
Y511673D03*
Y518760D03*
Y525847D03*
Y532933D03*
Y540020D03*
Y547106D03*
X633736Y602197D03*
X634200Y595108D03*
X622270Y864781D03*
X621727Y1556800D03*
X632000Y1644980D03*
X643360Y117557D03*
X637950Y110445D03*
Y115401D03*
X648352Y117557D03*
X643044Y106186D03*
X643360Y122513D03*
Y131731D03*
X637950Y124618D03*
Y129574D03*
X648352Y122513D03*
Y131731D03*
X646451Y146461D03*
X643360Y136687D03*
X648352D03*
X645353Y152367D03*
X647053Y180572D03*
X651736Y180527D03*
X638030Y181009D03*
X643205Y168697D03*
X651691Y185121D03*
X647053Y185165D03*
X646302Y206767D03*
X651302D03*
X648802D03*
X639971Y213132D03*
X648932Y221708D03*
X647547Y228221D03*
X645847Y224421D03*
X647547Y231021D03*
X646432Y221708D03*
X651432D03*
X639971Y215632D03*
X650598Y236189D03*
X648098D03*
X653098D03*
X653039Y248765D03*
X650539D03*
X648039D03*
X650736Y268195D03*
X653536Y270695D03*
Y268195D03*
X650736Y270695D03*
X648236D03*
Y268195D03*
X651339Y290845D03*
Y293645D03*
X653839D03*
X639268Y290755D03*
X643268D03*
X653839Y288345D03*
Y290845D03*
X651339Y288345D03*
X642255Y389154D03*
X649074D03*
X642255Y396240D03*
X643534Y404911D03*
X647604Y396240D03*
X642488Y412571D03*
X652381Y414823D03*
X651689Y422864D03*
X643675Y426299D03*
X651759Y429832D03*
X651364Y436447D03*
X653399Y447953D03*
X643986Y445847D03*
X642255Y467539D03*
X652566D03*
X642255Y474626D03*
X651308Y472772D03*
X652042Y487711D03*
X652155Y479104D03*
X642516Y480828D03*
X644466Y498834D03*
X652566Y495886D03*
X647915Y516841D03*
X651166Y510565D03*
X642255Y518760D03*
Y511673D03*
Y525847D03*
X642862Y550123D03*
X642740Y552872D03*
X644494Y572334D03*
X642185Y562443D03*
X643953Y560675D03*
X642726Y574102D03*
X648211Y602400D03*
Y598400D03*
Y594400D03*
Y606400D03*
Y614400D03*
X647361Y653161D03*
X648352Y645467D03*
X650958Y677843D03*
X652000Y1644980D03*
X657507Y58013D03*
X656560Y68581D03*
X656573Y80581D03*
X659282Y117261D03*
X655459Y192421D03*
X655782Y221642D03*
X668886Y248371D03*
X657196Y265897D03*
X659696D03*
X660366Y389154D03*
X667666Y389153D03*
X661761Y382109D03*
X660366Y403327D03*
Y410413D03*
X665166Y396240D03*
X667666D03*
X665166Y403327D03*
X667666Y403326D03*
X665166Y410413D03*
X667666D03*
X660366Y396240D03*
X667666Y417499D03*
X665166Y424586D03*
X667666D03*
X660366Y417500D03*
Y424586D03*
X665166Y417500D03*
Y431673D03*
Y438760D03*
X667666D03*
Y431673D03*
X660366D03*
Y438760D03*
X665166Y445847D03*
X660366D03*
X667666Y467539D03*
X660366D03*
X665166Y474626D03*
X667666D03*
X660366D03*
Y488799D03*
X665166D03*
X667666D03*
Y481712D03*
X665166D03*
X660366Y481713D03*
X665166Y495886D03*
X660366D03*
X667666Y518760D03*
X665166D03*
X667666Y511673D03*
X660366D03*
Y518760D03*
X667666Y532933D03*
X665166D03*
Y540020D03*
Y525846D03*
X667666D03*
X660366Y525847D03*
Y532933D03*
Y540020D03*
Y554193D03*
Y547106D03*
X660826Y570414D03*
Y567914D03*
Y565414D03*
X669546Y560500D03*
X661760Y561420D03*
Y558917D03*
X660826Y575414D03*
Y572914D03*
X657581Y577937D03*
X660366Y602205D03*
Y595118D03*
X655752Y668885D03*
X661776Y662981D03*
X656157Y691851D03*
X661768Y705043D03*
X688399Y97667D03*
X678782Y116594D03*
Y119594D03*
X686012Y339795D03*
X685353Y392718D03*
X672466Y389153D03*
Y410413D03*
X685353Y408718D03*
Y400718D03*
Y404718D03*
X672466Y396240D03*
Y403326D03*
Y424586D03*
Y417499D03*
X685353Y412718D03*
X672466Y438760D03*
Y431673D03*
X678461Y455981D03*
X672466Y467539D03*
Y474626D03*
Y488799D03*
Y481712D03*
Y518760D03*
Y511673D03*
Y525846D03*
Y532933D03*
X682586Y530000D03*
X681586Y555000D03*
X681011Y543925D03*
X682086Y540500D03*
X672000Y1644980D03*
X690073Y44662D03*
X697387Y53619D03*
X691396Y199248D03*
X687378Y195176D03*
X689878D03*
X694396Y199248D03*
X694878Y195176D03*
X692378D03*
X691396Y201748D03*
X689232Y206806D03*
X687459Y210509D03*
X689959D03*
X694396Y202048D03*
X691732Y206806D03*
X694012Y238714D03*
X702448Y546712D03*
X700164Y636842D03*
X698936Y678462D03*
X692478Y730641D03*
X702691Y766471D03*
Y753471D03*
X702677Y771159D03*
Y784659D03*
X692000Y1644980D03*
X717387Y53619D03*
X717909Y116496D03*
Y109410D03*
Y130670D03*
Y123583D03*
X709276Y130670D03*
X714500Y137756D03*
X709271D03*
X716544Y215478D03*
Y210478D03*
Y207978D03*
Y212978D03*
X713162Y434493D03*
X711598Y438323D03*
X711764Y449873D03*
X706211Y465874D03*
X718691Y465492D03*
Y472579D03*
X716191D03*
X711391D03*
X716191Y479666D03*
X718691D03*
X711391D03*
Y486752D03*
X716191D03*
X718691D03*
X711391Y493839D03*
X716191D03*
Y516713D03*
Y523800D03*
X718691D03*
X711391D03*
Y516713D03*
X718691D03*
Y509626D03*
Y530886D03*
X716191D03*
Y537973D03*
X711391Y530886D03*
Y537973D03*
Y566752D03*
X718691Y559665D03*
Y566752D03*
X716191D03*
X711391Y573839D03*
X718691D03*
X716191D03*
X711391Y588013D03*
X718691Y588012D03*
X716191Y588013D03*
X718691Y580926D03*
X716191D03*
X711391D03*
X716191Y602186D03*
X711391D03*
X718691Y602185D03*
Y595099D03*
X711391D03*
X716191D03*
X711391Y609272D03*
X716191D03*
X718691D03*
X716191Y616359D03*
X711391D03*
X706070Y638125D03*
X716656Y646429D03*
X703669Y665140D03*
X705390Y655789D03*
X716350Y699477D03*
X703604Y699653D03*
X704446Y760611D03*
X713425Y786029D03*
X712000Y1644980D03*
X734921Y98551D03*
X725909Y116496D03*
Y109410D03*
Y130670D03*
Y123583D03*
Y137756D03*
X733233Y147540D03*
Y151540D03*
X734386Y181426D03*
X734594Y184221D03*
X727000Y213213D03*
Y208213D03*
X733872Y208695D03*
X731072D03*
X733572Y211695D03*
X731072D03*
X727000Y210713D03*
Y215713D03*
X722373Y264180D03*
X719873D03*
X731567Y267526D03*
X728767D03*
X734067D03*
Y270026D03*
X731567D03*
X728767D03*
X733404Y285690D03*
X720090Y293796D03*
X722590D03*
X728104Y288190D03*
X730604Y285690D03*
X728104D03*
X730604Y288190D03*
X733404D03*
X731511Y390500D03*
X734606Y379562D03*
X722097Y410394D03*
Y403307D03*
X723031Y440098D03*
Y437598D03*
Y435098D03*
Y432598D03*
Y430098D03*
X723491Y458406D03*
Y451319D03*
Y465492D03*
X731291Y466027D03*
X723315Y462264D03*
X723491Y472579D03*
X731433Y475262D03*
Y489435D03*
Y482666D03*
X723491Y479665D03*
Y486752D03*
Y493839D03*
X731249Y495088D03*
X723491Y523799D03*
Y516713D03*
Y509626D03*
X731984Y514608D03*
X731906Y522134D03*
X731291Y509626D03*
X723491Y530886D03*
Y537973D03*
X732549Y529136D03*
X732388Y535677D03*
X723491Y566752D03*
Y559665D03*
X731291D03*
X731672Y565574D03*
X723491Y573839D03*
Y588012D03*
Y580926D03*
X731319Y574338D03*
X723491Y595099D03*
Y602185D03*
Y609272D03*
Y616358D03*
X731418D03*
X734819Y646429D03*
X721218Y742131D03*
X720271Y782481D03*
X728503Y891692D03*
X728692Y886653D03*
X724707Y893143D03*
X720373Y940310D03*
X732000Y1644980D03*
X736242Y5374D03*
X735555Y24773D03*
Y44773D03*
X750714Y117557D03*
X745722D03*
X740312Y115401D03*
Y110445D03*
X735320D03*
Y115401D03*
X745406Y106186D03*
X738471Y103783D03*
X745722Y131731D03*
Y122513D03*
X740312Y129574D03*
Y124618D03*
X735320D03*
Y129574D03*
X750714Y131731D03*
Y122513D03*
Y136687D03*
X745722D03*
X748813Y146461D03*
X747715Y152367D03*
X749415Y180572D03*
X740392Y181009D03*
X737597Y181366D03*
X745567Y168697D03*
X749415Y185165D03*
X737211Y184012D03*
X751164Y206767D03*
X748664D03*
X738630Y213859D03*
Y211359D03*
X742333Y213132D03*
X749909Y228221D03*
Y231021D03*
X751294Y221708D03*
X748209Y224421D03*
X748794Y221708D03*
X742333Y215632D03*
X750460Y236189D03*
X750401Y248765D03*
X750598Y268195D03*
Y270695D03*
X741630Y290755D03*
X737630D03*
X745630D03*
X741161Y381500D03*
X749586Y410394D03*
Y403307D03*
X741259Y439963D03*
X741381Y430760D03*
X741402Y433570D03*
X741218Y437072D03*
X741503Y443180D03*
X741523Y454744D03*
X741465Y452018D03*
X749402Y458406D03*
X741602Y465492D03*
X741568Y460250D03*
X739333Y470136D03*
X749402Y465492D03*
X741602Y472579D03*
X749402D03*
X741072Y478958D03*
X741602Y486752D03*
X749402Y479665D03*
Y486752D03*
Y493839D03*
X741602D03*
X749402Y523799D03*
Y516713D03*
Y509626D03*
X741602D03*
Y516713D03*
X749402Y537973D03*
Y530886D03*
X738062Y537973D03*
X740542Y525483D03*
X740463Y532756D03*
X749402Y559665D03*
Y566752D03*
X741602Y559665D03*
Y566752D03*
X749402Y573839D03*
Y588012D03*
Y580925D03*
X741452Y579978D03*
X741602Y573839D03*
X749402Y602185D03*
Y595099D03*
Y609272D03*
Y616358D03*
X741666Y608117D03*
X744069Y746617D03*
X741000Y771100D03*
X738707Y987952D03*
X745673Y1007009D03*
X747140Y1581335D03*
X744924Y1617709D03*
X743331Y1627871D03*
X755145Y3000D03*
X762697Y55513D03*
X758922Y68581D03*
X758935Y80581D03*
X762065Y117040D03*
X754098Y180527D03*
X757821Y192421D03*
X754053Y185121D03*
X753664Y206767D03*
X753794Y221708D03*
X758144Y221642D03*
X752960Y236189D03*
X755460D03*
X755401Y248765D03*
X752901D03*
X753098Y268195D03*
X755898D03*
X753098Y270695D03*
X755898D03*
X759558Y265897D03*
X762058D03*
X756201Y288345D03*
Y290845D03*
X753701Y288345D03*
Y290845D03*
Y293645D03*
X756201D03*
X760407Y324494D03*
X767099Y316731D03*
X763898Y342319D03*
X759029Y332017D03*
X766344Y393924D03*
Y389912D03*
Y385912D03*
X758038Y381143D03*
X766344Y409924D03*
Y405924D03*
Y401924D03*
X752341Y407148D03*
X756800Y403824D03*
X758381Y395391D03*
X759543Y445787D03*
X755593Y445908D03*
X755187Y1580821D03*
X752000Y1644980D03*
X775145Y3000D03*
X781144Y116594D03*
Y119594D03*
X771140Y248371D03*
X780968Y303839D03*
X776943Y321649D03*
X772990Y336324D03*
X777569Y353506D03*
X778985Y442498D03*
X778881Y446510D03*
X779029Y450510D03*
X778079Y467306D03*
Y470706D03*
Y481479D03*
Y484879D03*
Y514839D03*
Y511439D03*
Y529013D03*
Y525613D03*
Y561479D03*
Y564879D03*
Y575652D03*
Y579052D03*
Y589825D03*
Y593225D03*
Y603999D03*
Y607399D03*
X771557Y1446818D03*
X777725Y1450193D03*
X778045Y1619395D03*
X772000Y1644980D03*
X791129Y4469D03*
X792490Y24773D03*
Y44773D03*
X799811Y53597D03*
X790761Y97667D03*
X796758Y199248D03*
X797240Y195176D03*
X794740D03*
X789740D03*
X792240D03*
X793758Y199248D03*
X794094Y206806D03*
X791594D03*
X789821Y210509D03*
X792321D03*
X793758Y201748D03*
X796758Y202048D03*
X796374Y238714D03*
X788522Y290304D03*
X799937Y347340D03*
X792564Y406410D03*
X784586Y421000D03*
Y418500D03*
Y413500D03*
Y416000D03*
X802136Y448334D03*
X788481Y474418D03*
Y477818D03*
Y488591D03*
Y491991D03*
Y518552D03*
Y521952D03*
Y532725D03*
Y536125D03*
Y571991D03*
Y568591D03*
Y586165D03*
Y582765D03*
Y600338D03*
Y596938D03*
Y614511D03*
Y611111D03*
X794716Y1186071D03*
X792183Y1334030D03*
Y1331230D03*
X789383Y1334030D03*
Y1331230D03*
X794506Y1411307D03*
X793564Y1642682D03*
X811638Y130670D03*
X811633Y137756D03*
X804536Y441486D03*
X802136Y452334D03*
X810756Y491118D03*
Y488618D03*
Y483618D03*
X816364Y486870D03*
X810756Y486118D03*
X813864Y486870D03*
X815492Y732917D03*
X818000Y797000D03*
X812661Y810032D03*
X812980Y824166D03*
X813182Y852800D03*
X814731Y889365D03*
X812811Y908162D03*
X806787Y1148000D03*
X815034Y1159455D03*
X809623Y1160168D03*
X809393Y1187252D03*
X807487Y1193019D03*
X815487D03*
X811487D03*
X817446Y1210089D03*
X800627Y1392748D03*
X806318Y1401661D03*
X812901Y1432804D03*
X815901D03*
X810059Y1432778D03*
X809986Y1438785D03*
X812986D03*
X815986D03*
X809986Y1441485D03*
X812986D03*
X815986D03*
X812901Y1435504D03*
X815901D03*
X810001D03*
X806874Y1447457D03*
X812474D03*
X806874Y1452587D03*
Y1457717D03*
X812474D03*
X815096Y1464387D03*
X812009Y1473432D03*
Y1470432D03*
X815096Y1467387D03*
X812096Y1479587D03*
Y1476587D03*
X815096Y1473387D03*
Y1479587D03*
Y1476587D03*
Y1470387D03*
X811457Y1639797D03*
X819811Y53597D03*
X820271Y116496D03*
Y109410D03*
X828271Y116496D03*
Y109410D03*
X820271Y130670D03*
Y123583D03*
X828271Y130670D03*
Y123583D03*
X816637Y137756D03*
X828271D03*
X829362Y213213D03*
X818906Y207978D03*
Y212978D03*
Y215478D03*
Y210478D03*
X829362Y208213D03*
Y210713D03*
Y215713D03*
X822235Y264180D03*
X824735D03*
X831129Y267526D03*
Y270026D03*
X824952Y293796D03*
X822452D03*
X830466Y285690D03*
Y288190D03*
X825792Y305225D03*
X829381Y348036D03*
X824650Y446740D03*
X822040Y444091D03*
X826262Y462326D03*
Y459326D03*
X823529Y467189D03*
X818973Y491258D03*
Y488758D03*
X822418Y485070D03*
Y482570D03*
X823790Y713375D03*
X829784Y713939D03*
X823843Y732109D03*
X832284Y731216D03*
X830484Y746701D03*
X819890Y736924D03*
X819993Y754109D03*
X824500Y760500D03*
X830075Y769000D03*
X824500Y778500D03*
X830075Y787000D03*
X824500Y796500D03*
X830075Y805000D03*
X824500Y814500D03*
X830075Y823000D03*
X826797Y883756D03*
X825774Y895553D03*
X830063Y898500D03*
X825508Y913869D03*
X822462Y915095D03*
X818347Y939610D03*
X828193Y949324D03*
X828423Y964731D03*
X832432Y977982D03*
X832711Y993268D03*
X825335Y1137129D03*
X825744Y1146937D03*
Y1150087D03*
X823220Y1162817D03*
X823487Y1193019D03*
X819487D03*
X826612Y1219254D03*
X819522Y1212164D03*
X821816Y1214458D03*
X816648Y1377608D03*
X824901Y1427404D03*
X827901D03*
X821901D03*
X818901Y1430104D03*
X821901D03*
X830901D03*
X827901D03*
X824901D03*
Y1432804D03*
X827901D03*
X830901D03*
X821901D03*
X818901D03*
X824901Y1435504D03*
X827901D03*
X821901D03*
X818901D03*
X821986Y1441485D03*
X818986D03*
Y1438785D03*
X821986D03*
X817974Y1447457D03*
Y1452587D03*
Y1457717D03*
X818096Y1464387D03*
X821096D03*
X818096Y1473387D03*
X821096D03*
X824096D03*
X818096Y1479587D03*
X821096D03*
X824096D03*
X818096Y1476587D03*
X821096D03*
X824096D03*
X818096Y1467387D03*
Y1470387D03*
X821096D03*
Y1467387D03*
X824096D03*
Y1470387D03*
X831457Y1639797D03*
X838606Y5374D03*
X837919Y24773D03*
Y44773D03*
X837283Y98551D03*
X837682Y110445D03*
Y115401D03*
X848084Y117557D03*
X842674Y115401D03*
Y110445D03*
X840833Y103783D03*
X847768Y106186D03*
X842674Y129574D03*
Y124618D03*
X837682D03*
Y129574D03*
X848084Y131731D03*
Y122513D03*
Y136687D03*
X842754Y181009D03*
X839959Y181366D03*
X836748Y181426D03*
X847929Y168697D03*
X839573Y184012D03*
X836956Y184221D03*
X836234Y208695D03*
X833434D03*
X835934Y211695D03*
X840992Y213859D03*
Y211359D03*
X833434Y211695D03*
X844695Y213132D03*
Y215632D03*
X836429Y267526D03*
X833929D03*
Y270026D03*
X836429D03*
X832966Y288190D03*
Y285690D03*
X835766Y288190D03*
Y285690D03*
X843992Y290755D03*
X839992D03*
X847992D03*
X839573Y325327D03*
X833185Y456309D03*
Y452309D03*
Y448309D03*
X844227Y479882D03*
X842476Y482382D03*
X835236Y533174D03*
X845729Y661263D03*
X836503Y667845D03*
X845784Y713939D03*
X848284Y731181D03*
X846484Y746701D03*
X841500Y758161D03*
Y776161D03*
Y794161D03*
X838189Y847490D03*
X837183Y855459D03*
X840234Y851459D03*
X836999Y867413D03*
X845654Y895437D03*
X833870Y881860D03*
X839381Y915839D03*
X839122Y939655D03*
X848045Y1019310D03*
X848070Y1022190D03*
X835474Y1457397D03*
X850145Y3000D03*
X865059Y55513D03*
X861284Y68581D03*
X861297Y80581D03*
X864006Y117261D03*
X853076Y117557D03*
Y131731D03*
Y122513D03*
Y136687D03*
X851777Y180572D03*
X856460Y180527D03*
X860183Y192421D03*
X851777Y185165D03*
X856415Y185121D03*
X853526Y206767D03*
X856026D03*
X851026D03*
X860506Y221642D03*
X852271Y228221D03*
Y231021D03*
X853656Y221708D03*
X856156D03*
X850571Y224421D03*
X851156Y221708D03*
X852822Y236189D03*
X855322D03*
X857822D03*
X852763Y248765D03*
X855263D03*
X857763D03*
X852960Y268195D03*
Y270695D03*
X855460D03*
X864420Y265897D03*
X858260Y268195D03*
Y270695D03*
X861920Y265897D03*
X855460Y268195D03*
X858563Y293645D03*
Y290845D03*
X856063Y293645D03*
Y290845D03*
X858563Y288345D03*
X856063D03*
X864920Y343168D03*
X854622Y359004D03*
X854086Y385000D03*
X858586D03*
X864086Y384000D03*
X857973Y404867D03*
X862522Y400229D03*
X862566Y404867D03*
X857928Y400184D03*
X862020Y410899D03*
X862882Y468791D03*
Y465991D03*
X854882D03*
Y468791D03*
X850733Y461382D03*
X850832Y473382D03*
X861468Y491303D03*
X850738Y477382D03*
X850909Y482382D03*
X867093Y570703D03*
Y582828D03*
X858202Y646330D03*
X851111Y656635D03*
X856145Y677887D03*
X855646Y685230D03*
X858186Y713170D03*
X867227Y722060D03*
X849500Y761000D03*
X863443Y753254D03*
X864575Y770500D03*
X849500Y779000D03*
X861425Y770500D03*
X864575Y788500D03*
X849500Y797000D03*
X861425Y788500D03*
X864575Y806500D03*
X861425D03*
Y824500D03*
X851184Y863459D03*
Y867459D03*
X855524Y898505D03*
X856628Y915242D03*
X849600Y915266D03*
X855867Y935540D03*
X867096Y935963D03*
X849088Y951081D03*
X863334Y1009393D03*
X863342Y1120636D03*
X855542D03*
X858142D03*
X860842D03*
X863442Y1130336D03*
X858242D03*
X855642D03*
X860942D03*
Y1139336D03*
X863442D03*
X861119Y1148080D03*
X863619D03*
X863944Y1432359D03*
Y1429359D03*
X860944Y1432359D03*
X857944Y1429359D03*
X860944D03*
Y1426359D03*
X857944D03*
X863944D03*
X857944Y1432359D03*
X863944Y1435359D03*
Y1441359D03*
Y1438359D03*
X860944Y1441359D03*
X857944Y1435359D03*
X860944D03*
X857944Y1441359D03*
Y1438359D03*
X860944D03*
X859071Y1447459D03*
X864671D03*
X859071Y1452589D03*
Y1457719D03*
X864671D03*
X864644Y1464759D03*
X861644D03*
X855644D03*
X858644D03*
Y1467759D03*
X855644Y1470759D03*
X858644D03*
X864644Y1467759D03*
Y1470759D03*
X861644Y1467759D03*
Y1470759D03*
X855644Y1467759D03*
Y1473759D03*
X858644D03*
X864644D03*
X861644D03*
X855644Y1476759D03*
X858644D03*
X864644D03*
X861644D03*
X851457Y1639797D03*
X873373Y60922D03*
X876246Y302754D03*
X873733Y357844D03*
X868086Y373750D03*
X872736Y383125D03*
X867586Y385000D03*
X872318Y408589D03*
X866128Y417532D03*
X869342Y417399D03*
X880910Y471982D03*
Y469182D03*
Y466382D03*
X870882Y465991D03*
Y468791D03*
X875907Y486256D03*
X867093Y558703D03*
Y562703D03*
Y566703D03*
Y578703D03*
X870137Y669461D03*
X869313Y688486D03*
X872069Y700894D03*
X876286Y686970D03*
X873021Y715729D03*
X877616Y749484D03*
X878610Y747171D03*
X873318Y744597D03*
X871294Y771809D03*
X867000Y774000D03*
X873250Y798750D03*
X880040Y792851D03*
X867000Y792000D03*
X875916Y808965D03*
X867000Y810000D03*
X872628Y918042D03*
X876628Y915242D03*
X872126Y934766D03*
X867199Y949372D03*
X869390Y978003D03*
X871624Y1213314D03*
X874624D03*
X871624Y1221714D03*
Y1218914D03*
Y1216114D03*
X874624Y1221714D03*
Y1218914D03*
Y1216114D03*
X872440Y1230083D03*
Y1227583D03*
X871624Y1224514D03*
X874624D03*
X872440Y1234483D03*
Y1236983D03*
X878004Y1224406D03*
X872440Y1243883D03*
Y1241383D03*
Y1248283D03*
Y1250783D03*
X883142Y1259935D03*
X875700Y1299700D03*
X872944Y1432359D03*
Y1429359D03*
Y1426359D03*
X869944Y1432359D03*
Y1429359D03*
Y1426359D03*
X866944Y1432359D03*
Y1429359D03*
Y1426359D03*
X872944Y1435359D03*
Y1441359D03*
Y1438359D03*
X869944Y1435359D03*
X866944D03*
X869944Y1441359D03*
Y1438359D03*
X866944Y1441359D03*
Y1438359D03*
X870171Y1447459D03*
Y1452589D03*
Y1457719D03*
X867644Y1464759D03*
X870644D03*
X881244Y1456859D03*
X867644Y1467759D03*
X870644D03*
X867644Y1470759D03*
X870644D03*
X867644Y1473759D03*
X870644D03*
X867644Y1476759D03*
X870644D03*
X871457Y1639797D03*
X883233Y147540D03*
X886011Y154100D03*
X895780Y237517D03*
Y232634D03*
X886261Y252090D03*
X885741Y261150D03*
X886026Y346584D03*
X883552Y357276D03*
X884736Y383125D03*
X893736D03*
X888736D03*
X891251Y387484D03*
X894844Y418983D03*
X889219Y426952D03*
X887770Y415290D03*
X891699Y420445D03*
X890270Y415290D03*
X891699Y423245D03*
X897344Y418983D03*
X894519Y426952D03*
X889596Y437264D03*
X896388Y437614D03*
X887096Y437264D03*
X892019Y426952D03*
X897019D03*
X890903Y469182D03*
Y471982D03*
Y466382D03*
X882907Y480350D03*
X896431Y534093D03*
X882891Y536122D03*
X896449Y550863D03*
X893949Y550363D03*
X892023Y570176D03*
X882949Y557363D03*
X890959Y579788D03*
X890956Y588325D03*
X894015Y588253D03*
X895933Y618143D03*
X887949Y608863D03*
X894449Y606363D03*
X883309Y666608D03*
X892461Y666671D03*
X886304Y666650D03*
X884903Y694119D03*
X889436Y715970D03*
X886836Y729778D03*
X889083Y780371D03*
X888545Y785528D03*
X888514Y797602D03*
X898737Y792289D03*
X889516Y792851D03*
X891916Y808965D03*
X884628Y915242D03*
X897056Y1091391D03*
X891055Y1095407D03*
X897056Y1095984D03*
X884906Y1102760D03*
X884890Y1098724D03*
X888650Y1199622D03*
X893190Y1208069D03*
X893328Y1212887D03*
X894887Y1227209D03*
X891003Y1292765D03*
X886926Y1298712D03*
X889729Y1295516D03*
X890738Y1311132D03*
X891457Y1639797D03*
X898813Y146461D03*
X897715Y152367D03*
X898851Y231496D03*
Y238583D03*
Y245669D03*
X910977Y238583D03*
X898851Y259843D03*
X898576Y253056D03*
X910977Y252756D03*
Y257480D03*
X898851Y274016D03*
X910977Y266929D03*
X898851D03*
X912786Y306697D03*
X901848Y307782D03*
Y312738D03*
X910076Y304843D03*
X905120D03*
X909417Y323302D03*
X912278Y343881D03*
X913206Y336489D03*
X912085Y332335D03*
X910040Y353532D03*
X898869Y351114D03*
X902169Y413002D03*
Y418002D03*
Y415502D03*
X905094Y424581D03*
X902594D03*
X907594D03*
X905212Y436734D03*
X902712D03*
X907712D03*
X907173Y440581D03*
X898888Y437614D03*
X907173Y443081D03*
X910779Y471380D03*
X903431Y534093D03*
X906996Y530707D03*
X902459Y530755D03*
X911630Y543998D03*
X910578Y550186D03*
X909362Y555614D03*
X898156Y554812D03*
X913853Y561487D03*
X904393Y570176D03*
X908517D03*
X898815D03*
X909024Y578394D03*
X898232Y588320D03*
X909024Y586768D03*
X902635Y588305D03*
X906999Y588274D03*
X909024Y574394D03*
X908730Y619120D03*
X913686D03*
X899898Y619040D03*
X904854D03*
X900753Y656925D03*
X912462Y695770D03*
X910036Y702285D03*
X905313Y709259D03*
X910753Y715864D03*
X905050Y720268D03*
X913716Y800815D03*
X899916D03*
X911053Y800510D03*
X913716Y811954D03*
X907884Y829866D03*
X899693Y895207D03*
X900628Y918042D03*
X903759Y951358D03*
X908422Y1023103D03*
X908856Y1017677D03*
X901739Y1091346D03*
X901694Y1095940D03*
X911071Y1123803D03*
X905771D03*
X903171D03*
X908371D03*
X910971Y1114103D03*
X908271D03*
X903071D03*
X905671D03*
X911699Y1129488D03*
X909041Y1126328D03*
X911641D03*
X901428Y1136426D03*
X903908Y1132870D03*
X904063Y1135946D03*
X904897Y1145169D03*
X902397D03*
X901940Y1236799D03*
Y1229899D03*
Y1232399D03*
Y1246199D03*
Y1243699D03*
Y1239299D03*
X908700Y1316300D03*
X911135Y1345560D03*
X899944Y1432359D03*
X908944Y1426359D03*
Y1429359D03*
Y1432359D03*
X911944Y1426359D03*
Y1429359D03*
Y1432359D03*
X905944Y1426359D03*
X899944D03*
X902944D03*
Y1429359D03*
X899944D03*
X902944Y1432359D03*
X905944Y1429359D03*
Y1432359D03*
X902944Y1438359D03*
X899944D03*
Y1441359D03*
X902944Y1435359D03*
X899944D03*
X908944Y1438359D03*
Y1441359D03*
X911944Y1438359D03*
Y1441359D03*
X902944D03*
X905944Y1438359D03*
Y1441359D03*
X908944Y1435359D03*
X911944D03*
X905944D03*
X912171Y1447459D03*
X906671D03*
X901071D03*
X912171Y1457719D03*
Y1452589D03*
X906671Y1457719D03*
X901071D03*
Y1452589D03*
X908370Y1464583D03*
X905370D03*
X899370D03*
X902370D03*
X911370D03*
X905370Y1476583D03*
X908370D03*
X902370D03*
X899370D03*
X905370Y1473583D03*
X908370D03*
X902370D03*
X899370D03*
X902370Y1467583D03*
X899370Y1470583D03*
X902370D03*
X908370Y1467583D03*
Y1470583D03*
X905370Y1467583D03*
Y1470583D03*
X899370Y1467583D03*
X911370Y1476583D03*
Y1473583D03*
Y1467583D03*
Y1470583D03*
X911457Y1639797D03*
X930145Y3000D03*
X920142Y308501D03*
X926801Y323302D03*
X917906Y321670D03*
X922629Y336609D03*
X922198Y342051D03*
X917858Y331453D03*
X923902Y332411D03*
X915395Y357267D03*
X921847Y346622D03*
X915395Y363212D03*
X927309Y363239D03*
Y369210D03*
X921468D03*
X915395D03*
X927072Y386992D03*
X919072D03*
X923072D03*
X914202Y418002D03*
Y413002D03*
Y415502D03*
X927636Y452505D03*
X929050Y450316D03*
X924600Y533706D03*
X920961Y550075D03*
X915949Y563363D03*
X915712Y613792D03*
X915194Y666671D03*
X928043Y677795D03*
X917286Y679625D03*
X924932Y701051D03*
X916590Y800636D03*
X917803Y811365D03*
X924864Y1026762D03*
Y1023208D03*
X925024Y1018909D03*
X927861Y1024768D03*
X916749Y1092664D03*
X916875Y1098643D03*
X916749Y1104659D03*
X927598Y1120636D03*
X924898D03*
X914661Y1132612D03*
X914299Y1129488D03*
X914241Y1126328D03*
X924919Y1130336D03*
X927619D03*
X924919Y1139336D03*
X927419D03*
X925097Y1147708D03*
X927597D03*
X924650Y1327819D03*
Y1324419D03*
X914033Y1345613D03*
X931159Y1406027D03*
X914944Y1426359D03*
Y1429359D03*
Y1432359D03*
Y1438359D03*
Y1441359D03*
Y1435359D03*
X914370Y1464583D03*
Y1476583D03*
Y1473583D03*
Y1467583D03*
Y1470583D03*
X926044Y1545370D03*
Y1542370D03*
X929094Y1542353D03*
Y1545353D03*
X926041Y1554503D03*
Y1551503D03*
Y1548503D03*
Y1557503D03*
Y1560503D03*
X941129Y4469D03*
X942490Y24773D03*
Y44773D03*
X940761Y97667D03*
X931144Y116594D03*
Y119594D03*
X945406Y180347D03*
X940406D03*
X942906D03*
X947424Y184419D03*
X944424Y186919D03*
X944760Y191977D03*
X942260D03*
X940487Y195680D03*
X942987D03*
X944424Y184419D03*
X933403Y245507D03*
X941845Y278968D03*
X939606Y310521D03*
X939653Y317474D03*
X940924Y328959D03*
X936608Y326058D03*
X945120Y326441D03*
X942731Y324044D03*
X939331D03*
X932388Y330517D03*
X930398Y342050D03*
X936453Y345336D03*
X945599Y345383D03*
X940972Y338238D03*
X932622Y336817D03*
X943663Y355674D03*
X944694Y352192D03*
X942700Y346363D03*
X939300D03*
X944900Y363700D03*
X938499Y362202D03*
X940600Y370600D03*
X941872Y440942D03*
X941505Y463442D03*
X939827Y531104D03*
X939992Y536726D03*
Y540726D03*
X931627Y561578D03*
Y565578D03*
X943825Y581222D03*
X931620Y584417D03*
X931594Y599420D03*
X931647Y593271D03*
X931578Y590669D03*
X935281Y677795D03*
X939314Y707847D03*
X931244Y720471D03*
X936026Y730600D03*
X945626Y789761D03*
X941916Y808965D03*
X935124Y831382D03*
X940716Y840074D03*
X944297Y839975D03*
X942634Y886520D03*
X933700Y887508D03*
X944839Y902400D03*
X938188Y900853D03*
X940015Y1020176D03*
X934911Y1023579D03*
X945864Y1023208D03*
X930864Y1026762D03*
X936864D03*
X942864D03*
X939864Y1023208D03*
X930864D03*
X930883Y1018751D03*
X936822Y1018988D03*
X942760Y1018751D03*
X943093Y1021769D03*
X935601Y1221714D03*
Y1218914D03*
Y1216114D03*
Y1213314D03*
X938601Y1221714D03*
Y1218914D03*
Y1216114D03*
Y1213314D03*
X936417Y1234483D03*
Y1236983D03*
Y1230083D03*
Y1227583D03*
X935601Y1224514D03*
X938601D03*
X941981Y1224406D03*
X936417Y1243883D03*
Y1241383D03*
Y1248283D03*
Y1250783D03*
X947119Y1259935D03*
X933254Y1308273D03*
X940848Y1310181D03*
X943891Y1306608D03*
X944207Y1320739D03*
X947308Y1325035D03*
X931159Y1398427D03*
X943725Y1430744D03*
Y1427744D03*
X934725Y1430744D03*
X940725Y1427744D03*
Y1430744D03*
X934725Y1427744D03*
X937725D03*
Y1430744D03*
X943725Y1433744D03*
Y1439744D03*
Y1436744D03*
X940725Y1433744D03*
Y1439744D03*
Y1436744D03*
X934725Y1433744D03*
X937725D03*
X934725Y1439744D03*
X937725D03*
X934725Y1436744D03*
X937725D03*
X930441Y1455039D03*
Y1458039D03*
Y1464039D03*
Y1461039D03*
Y1467039D03*
X938670Y1510528D03*
X941270D03*
Y1505328D03*
X938670D03*
X940170Y1507928D03*
X943870Y1510528D03*
Y1505328D03*
X945370Y1507928D03*
X942770D03*
X935094Y1542353D03*
X932094D03*
X935094Y1545353D03*
X932094D03*
X938094Y1542353D03*
Y1545353D03*
X941094Y1542353D03*
X944094D03*
X941094Y1545353D03*
X944094D03*
X931457Y1639797D03*
X949811Y53597D03*
X961638Y130670D03*
X961633Y137756D03*
X947906Y180347D03*
X947424Y187219D03*
X947040Y223885D03*
X949579Y330517D03*
X949813Y336817D03*
X956348Y356371D03*
X952170Y356131D03*
X958823Y362802D03*
X954888Y369513D03*
X948400Y370045D03*
X950315Y464851D03*
X949823Y487982D03*
X949876Y478486D03*
X949823Y483982D03*
Y499982D03*
X953816Y555194D03*
X951016D03*
X953816Y571194D03*
X951016D03*
X953816Y563194D03*
X951016D03*
X946625Y581222D03*
X949425D03*
Y591215D03*
X946625D03*
X948427Y611091D03*
X956365Y641817D03*
X950865D03*
X957551Y698251D03*
X954023Y725336D03*
X951195Y727165D03*
X952681Y735256D03*
X956323Y748412D03*
X957474Y764426D03*
X955086Y779798D03*
X956051Y793937D03*
X951461Y812223D03*
X951791Y808121D03*
X951708Y818894D03*
X950300Y877800D03*
X952738Y886624D03*
X953587Y902814D03*
X954567Y927654D03*
X961671Y991564D03*
X953671D03*
X954937Y1021998D03*
X948864Y1026762D03*
X954864D03*
X951864Y1023208D03*
X957864D03*
X957678Y1018555D03*
X961208Y1018592D03*
X960636Y1021917D03*
X959371Y1026985D03*
X948975Y1021325D03*
X952627Y1199622D03*
X957305Y1212887D03*
X957167Y1208069D03*
X958864Y1227209D03*
X948259Y1295965D03*
X949970Y1321749D03*
X952070Y1367717D03*
X949070D03*
X946725Y1427744D03*
Y1430744D03*
X949725D03*
Y1427744D03*
X960883Y1427997D03*
Y1430997D03*
X946725Y1433744D03*
X949725D03*
X946725Y1439744D03*
X949725D03*
X946725Y1436744D03*
X949725D03*
X960883Y1433997D03*
Y1436997D03*
Y1439997D03*
X956238Y1455139D03*
Y1458139D03*
Y1461139D03*
Y1464139D03*
X952676Y1461039D03*
Y1464039D03*
Y1458039D03*
Y1455039D03*
X956238Y1467139D03*
Y1469902D03*
X952676Y1467039D03*
X946470Y1510528D03*
Y1505328D03*
X956035Y1545333D03*
X959035D03*
X953035D03*
X950035D03*
X959035Y1542333D03*
X956035D03*
X953035D03*
X950035D03*
X947094Y1545353D03*
Y1542353D03*
X951457Y1639797D03*
X969811Y53597D03*
X978271Y109410D03*
X970271Y116496D03*
Y109410D03*
X978271Y116496D03*
X970271Y130670D03*
Y123583D03*
X978271Y130670D03*
Y123583D03*
X963360Y121459D03*
X966347Y137756D03*
X978271D03*
X968906Y207978D03*
Y212978D03*
Y215478D03*
Y210478D03*
X970865Y264068D03*
X973365D03*
X974952Y293796D03*
X972452D03*
X976763Y307303D03*
X972147Y323681D03*
X977150Y328472D03*
X973338Y345018D03*
X977150Y335472D03*
X975631Y343112D03*
Y346612D03*
X969623Y405614D03*
X963577Y426391D03*
X975932Y437508D03*
X971932D03*
X973695Y448874D03*
X969109Y449352D03*
X967816Y472905D03*
X972397Y472954D03*
X973843Y500086D03*
X978723Y504699D03*
X976223D03*
X973723D03*
X978425Y516979D03*
X973425D03*
X974406Y521804D03*
X975925Y516979D03*
X978668Y527449D03*
X974406Y524304D03*
X970713Y531378D03*
Y528878D03*
X975868Y527449D03*
X964012Y546830D03*
X978581Y572975D03*
X977857Y605443D03*
X973857D03*
X980683Y628242D03*
X967302Y627948D03*
X969491Y629362D03*
X963187Y667620D03*
X973138Y667621D03*
X978059Y747438D03*
X976764Y786563D03*
X971144Y908972D03*
X968507Y937615D03*
X965671Y991564D03*
X963864Y1026762D03*
Y1023208D03*
X967148Y1123803D03*
X969748D03*
X969648Y1114103D03*
X967048D03*
X972348Y1123803D03*
X975048D03*
X972248Y1114103D03*
X974948D03*
X965405Y1136426D03*
X970485Y1132870D03*
X967885D03*
X968874Y1145169D03*
X966374D03*
X978614Y1210568D03*
Y1214838D03*
X965917Y1236799D03*
Y1229899D03*
Y1232399D03*
Y1246199D03*
Y1243699D03*
Y1239299D03*
X978727Y1284908D03*
X978857Y1360945D03*
X963883Y1430997D03*
Y1427997D03*
X966883Y1430997D03*
Y1427997D03*
X969883D03*
Y1430997D03*
X975883Y1427997D03*
Y1430997D03*
X972883D03*
Y1427997D03*
X963883Y1433997D03*
X966883D03*
X969883D03*
X963883Y1436997D03*
Y1439997D03*
X966883Y1436997D03*
Y1439997D03*
X969883Y1436997D03*
Y1439997D03*
X975883Y1433997D03*
X972883D03*
X975883Y1436997D03*
X972883D03*
X975883Y1439997D03*
X972883D03*
X971467Y1509515D03*
X974067D03*
X972567Y1512115D03*
X969967D03*
X976667Y1509515D03*
X977767Y1506915D03*
X975167D03*
X969967D03*
X972567D03*
X975167Y1512115D03*
X977767D03*
X971140Y1514693D03*
X968540D03*
X973740D03*
X976340D03*
X977547Y1546081D03*
X974547D03*
X971547D03*
X971457Y1639797D03*
X988606Y5374D03*
X987919Y24773D03*
Y44773D03*
X987283Y98551D03*
X987682Y115401D03*
X992674D03*
Y110445D03*
X987682D03*
X990833Y103783D03*
X992674Y124618D03*
X987682D03*
Y129574D03*
X992674D03*
X985595Y147540D03*
Y151540D03*
X989959Y181366D03*
X986748Y181426D03*
X992754Y181009D03*
X986956Y184221D03*
X989573Y184012D03*
X994695Y213132D03*
X979362Y208213D03*
Y210713D03*
Y213213D03*
X986234Y208695D03*
X983434D03*
X985934Y211695D03*
X990992Y213859D03*
Y211359D03*
X983434Y211695D03*
X979362Y215713D03*
X994695Y215632D03*
X986429Y270026D03*
X983929D03*
X981129D03*
X983929Y267526D03*
X986429D03*
X981129D03*
X985766Y288190D03*
X982966D03*
X985766Y285690D03*
X982966D03*
X980466Y288190D03*
Y285690D03*
X993992Y290755D03*
X989992D03*
X993132Y310942D03*
X993243Y321325D03*
X987055Y320273D03*
X993920Y335454D03*
X993420Y337954D03*
X992045Y366559D03*
X984045D03*
X988045D03*
X979932Y437508D03*
X982792Y447269D03*
X982670Y450201D03*
X980397Y473045D03*
X992206Y478586D03*
Y481086D03*
Y483886D03*
X985699Y480705D03*
X980544Y482134D03*
Y484634D03*
X992206Y476086D03*
X988499Y480705D03*
X983989Y475946D03*
Y478446D03*
X982375Y522129D03*
X987436Y519531D03*
X982436D03*
X984936D03*
X982375Y527129D03*
Y524629D03*
Y529929D03*
X989068Y532949D03*
X986268D03*
X981795Y572842D03*
X985903Y579475D03*
X985357Y585507D03*
X989950D03*
X985401Y590145D03*
X989995Y590190D03*
X989857Y605443D03*
X981857Y605637D03*
X983843Y633205D03*
Y636005D03*
Y638805D03*
X983712Y722064D03*
X984307Y748432D03*
X985030Y781204D03*
X988329Y781445D03*
X991990Y773974D03*
X984963Y785387D03*
X989700Y846500D03*
X987202Y846395D03*
X987319Y843589D03*
X979203Y833159D03*
X989800Y843900D03*
X987200Y848940D03*
X979592Y902849D03*
X980852Y1098643D03*
X980726Y1104659D03*
Y1092664D03*
X995009Y1131223D03*
X991763Y1140378D03*
Y1128378D03*
Y1134378D03*
X984558Y1140774D03*
X988112Y1137774D03*
X984558Y1128774D03*
Y1134774D03*
X987804Y1131619D03*
X988389Y1302558D03*
X981857Y1360945D03*
X980501Y1369685D03*
X983501D03*
X986949Y1430997D03*
Y1427997D03*
X983949D03*
X989949Y1430997D03*
Y1427997D03*
X983949Y1430997D03*
X992949Y1427997D03*
Y1430997D03*
X986949Y1433997D03*
X983949D03*
X989949D03*
X992949D03*
X986949Y1436997D03*
X983949D03*
X986949Y1439997D03*
X983949D03*
X989949Y1436997D03*
Y1439997D03*
X992949Y1436997D03*
Y1439997D03*
X979538Y1464039D03*
Y1461039D03*
Y1458039D03*
Y1455039D03*
Y1467039D03*
Y1469802D03*
X979267Y1509515D03*
X984467D03*
X981867D03*
X985567Y1512115D03*
Y1506915D03*
X980367D03*
X982967D03*
Y1512115D03*
X980367D03*
X989667Y1509515D03*
X992267D03*
X987067D03*
X988167Y1512115D03*
X990767D03*
Y1506915D03*
X988167D03*
X984140Y1514693D03*
X981540D03*
X978940D03*
X986740D03*
X989340D03*
X986773Y1546081D03*
X983773D03*
X980773D03*
X991457Y1639797D03*
X1007508Y3000D03*
X1011284Y68581D03*
X1011297Y80581D03*
X1003076Y117557D03*
X998084D03*
X997768Y106186D03*
X1003076Y122513D03*
Y131731D03*
X998084Y122513D03*
Y131731D03*
X1001175Y146461D03*
X1003076Y136687D03*
X998084D03*
X1000077Y152367D03*
X1001777Y180572D03*
X1006460Y180527D03*
X997929Y168697D03*
X1010183Y192421D03*
X1001777Y185165D03*
X1006415Y185121D03*
X1003526Y206767D03*
X1006026D03*
X1001026D03*
X1002271Y228221D03*
Y231021D03*
X1010506Y221642D03*
X1003656Y221708D03*
X1006156D03*
X1000571Y224421D03*
X1001156Y221708D03*
X1002822Y236189D03*
X1005322D03*
X1007822D03*
X1002763Y248765D03*
X1005263D03*
X1007763D03*
X1008260Y268195D03*
X1005460D03*
X1002960D03*
X1008260Y270695D03*
X1002960D03*
X1005460D03*
X1000698Y300276D03*
X1010499Y309062D03*
X998667Y322239D03*
X1004544Y318050D03*
X1004933Y314535D03*
X997921Y333654D03*
X1000420Y348954D03*
X997857Y605443D03*
X995913Y633450D03*
Y636250D03*
Y639050D03*
X1011185Y724519D03*
X1009562Y722438D03*
X1002930Y906785D03*
X1010119Y933822D03*
X1006619D03*
X1010009Y998100D03*
X995317Y1137378D03*
X1008312Y1363533D03*
X1008452Y1376752D03*
X1008483Y1372734D03*
X1006211Y1397662D03*
X1009338Y1391597D03*
Y1388597D03*
X998643Y1398271D03*
X1008138Y1407186D03*
Y1409986D03*
X1005338Y1407186D03*
Y1409986D03*
X1008138Y1415586D03*
Y1412786D03*
X1005338Y1415586D03*
Y1412786D03*
X1008138Y1418386D03*
X1005338D03*
X998949Y1427997D03*
Y1430997D03*
X995949D03*
Y1427997D03*
X1009981Y1431097D03*
Y1428097D03*
X1006981D03*
Y1431097D03*
X998949Y1433997D03*
X995949D03*
X998949Y1436997D03*
X995949D03*
X998949Y1439997D03*
X995949D03*
X1009981Y1434097D03*
X1006981D03*
X1009981Y1437097D03*
X1006981D03*
X1009981Y1440097D03*
X1006981D03*
X1002538Y1463939D03*
Y1460939D03*
Y1457939D03*
Y1454939D03*
Y1466939D03*
Y1469702D03*
X1008549Y1509815D03*
X1007049Y1507215D03*
X1011149Y1509815D03*
X1009649Y1507215D03*
Y1512415D03*
X1007049D03*
X1008222Y1514993D03*
X1005622D03*
X1010822D03*
X1010606Y1547824D03*
X1007611Y1561247D03*
Y1558247D03*
Y1555247D03*
Y1552247D03*
X1004611Y1561247D03*
Y1558247D03*
Y1555247D03*
Y1552247D03*
X1010659Y1568771D03*
Y1565771D03*
X1010653Y1571669D03*
X1027508Y3000D03*
X1015059Y55513D03*
X1014006Y117261D03*
X1023502Y248371D03*
X1014420Y265897D03*
X1011920D03*
X1016635Y300276D03*
X1012635D03*
X1025749D03*
X1020635D03*
X1013354Y323362D03*
X1021451Y322879D03*
X1026032Y322906D03*
X1013327Y327453D03*
X1013318Y333190D03*
X1022845Y340944D03*
X1013313Y339909D03*
X1015195Y428305D03*
X1018155Y684132D03*
X1024932Y717856D03*
X1014641Y724436D03*
X1012851Y722417D03*
X1026090Y770943D03*
X1021895Y771974D03*
X1025859Y802275D03*
X1021221Y848712D03*
X1025219Y842155D03*
X1025239Y845070D03*
X1016973Y877196D03*
X1016574Y874537D03*
X1016798Y890299D03*
X1026340Y917761D03*
X1019519Y937922D03*
X1023319D03*
X1017619Y932122D03*
X1023519Y951522D03*
X1018919D03*
X1022009Y997860D03*
X1018009D03*
X1026009D03*
X1014009D03*
X1017297Y1165091D03*
X1023106D03*
X1026606D03*
X1017297Y1177691D03*
X1023106D03*
X1026606D03*
X1020434Y1205579D03*
X1022420Y1203204D03*
X1026968Y1223749D03*
X1025434Y1320606D03*
X1011829Y1347471D03*
Y1342515D03*
X1015286Y1344924D03*
X1023358Y1363921D03*
X1013991Y1360842D03*
X1021623Y1373216D03*
X1012338Y1388597D03*
Y1391597D03*
X1015338D03*
Y1388597D03*
X1021338D03*
Y1391597D03*
X1018338D03*
Y1388597D03*
X1027338D03*
Y1391597D03*
X1024338D03*
Y1388597D03*
X1012981Y1431097D03*
Y1428097D03*
X1015981D03*
Y1431097D03*
X1021981Y1428097D03*
Y1431097D03*
X1018981D03*
Y1428097D03*
X1012981Y1434097D03*
X1015981D03*
X1012981Y1437097D03*
Y1440097D03*
X1015981Y1437097D03*
Y1440097D03*
X1021981Y1434097D03*
X1018981D03*
X1021981Y1437097D03*
X1018981D03*
X1021981Y1440097D03*
X1018981D03*
X1025138Y1463839D03*
Y1460839D03*
Y1457839D03*
Y1454839D03*
Y1466839D03*
Y1469602D03*
X1020023Y1489637D03*
X1016769Y1489832D03*
X1013749Y1509815D03*
X1016349D03*
X1021549D03*
X1018949D03*
X1024149D03*
X1022649Y1507215D03*
X1025249D03*
X1017449D03*
X1020049D03*
X1014849D03*
X1012249D03*
X1026749Y1509815D03*
X1012249Y1512415D03*
X1014849D03*
X1025249D03*
X1022649D03*
X1020049D03*
X1017449D03*
X1013422Y1514993D03*
X1023822D03*
X1021222D03*
X1018622D03*
X1016022D03*
X1026422D03*
X1013606Y1547824D03*
X1016606D03*
X1019606D03*
X1013659Y1568771D03*
X1016659D03*
X1019659D03*
X1013659Y1565771D03*
X1016659D03*
X1019659D03*
X1013653Y1571669D03*
X1016653D03*
X1019653D03*
X1011457Y1639797D03*
X1043492Y4469D03*
X1043123Y97667D03*
X1033506Y116594D03*
Y119594D03*
X1042102Y195176D03*
X1042183Y210509D03*
X1045650Y300093D03*
X1029639Y300141D03*
X1031354Y325901D03*
Y322905D03*
X1031382Y340947D03*
X1031310Y337888D03*
X1031377Y333671D03*
X1031362Y329268D03*
X1030753Y732213D03*
X1038796Y763272D03*
X1042880Y794924D03*
X1028155Y879413D03*
X1030300Y881400D03*
X1043252Y902501D03*
X1031219Y949922D03*
X1030009Y997860D03*
X1034009D03*
X1042009D03*
X1038009D03*
X1040600Y1210600D03*
X1035384Y1215195D03*
X1034513Y1333665D03*
X1042586Y1345824D03*
X1030338Y1391597D03*
Y1388597D03*
X1032867Y1431213D03*
Y1428213D03*
X1029867D03*
X1035867Y1431213D03*
Y1428213D03*
X1029867Y1431213D03*
X1038867Y1428213D03*
Y1431213D03*
X1041867D03*
Y1428213D03*
X1032867Y1434213D03*
X1029867D03*
X1035867D03*
X1038867D03*
X1032867Y1437213D03*
X1029867D03*
X1032867Y1440213D03*
X1029867D03*
X1035867Y1437213D03*
Y1440213D03*
X1038867Y1437213D03*
Y1440213D03*
X1041867Y1434213D03*
Y1437213D03*
Y1440213D03*
X1029349Y1509815D03*
X1027849Y1507215D03*
Y1512415D03*
X1031457Y1639797D03*
X1044853Y24773D03*
Y44773D03*
X1052174Y53597D03*
X1047102Y195176D03*
X1046120Y199248D03*
X1044602Y195176D03*
X1049120Y199248D03*
X1049602Y195176D03*
X1046120Y201748D03*
X1049120Y202048D03*
X1044683Y210509D03*
X1046456Y206806D03*
X1043956D03*
X1048736Y238714D03*
X1050164Y302748D03*
X1050076Y305512D03*
X1046674Y340031D03*
X1045966Y346808D03*
X1054863Y401513D03*
Y398113D03*
X1052463Y412287D03*
Y415687D03*
Y426460D03*
Y440633D03*
Y429860D03*
X1050777Y450750D03*
X1052463Y444033D03*
X1059549Y458711D03*
X1052463Y469387D03*
Y472787D03*
Y486960D03*
Y483560D03*
Y513521D03*
Y516921D03*
Y531094D03*
Y527694D03*
X1044112Y778835D03*
X1045744Y800835D03*
X1048328Y808166D03*
X1057961Y931919D03*
X1046009Y997860D03*
X1054009D03*
X1050009D03*
X1058009D03*
X1048043Y1168091D03*
Y1180691D03*
X1051249Y1290288D03*
X1052221Y1336984D03*
X1044867Y1428213D03*
Y1431213D03*
Y1434213D03*
Y1437213D03*
Y1440213D03*
X1051457Y1639797D03*
X1072174Y53597D03*
X1072633Y116496D03*
Y109410D03*
Y130670D03*
Y123583D03*
X1064000Y130670D03*
X1069224Y137756D03*
X1063995D03*
X1071268Y207978D03*
Y212978D03*
Y215478D03*
Y210478D03*
X1074597Y264180D03*
X1061325Y339509D03*
X1060679Y360151D03*
Y364276D03*
X1062865Y391001D03*
X1062234Y378600D03*
X1062865Y408574D03*
Y405174D03*
Y394401D03*
Y422747D03*
Y419347D03*
Y436921D03*
Y433521D03*
X1062349Y458711D03*
X1062865Y476499D03*
Y479899D03*
Y490673D03*
Y494073D03*
Y520633D03*
Y524033D03*
Y534806D03*
Y538206D03*
X1071548Y555234D03*
X1066009Y997860D03*
X1062009D03*
X1074009D03*
X1069642Y1445541D03*
X1068861Y1451311D03*
X1071457Y1639797D03*
X1090280Y44773D03*
X1089645Y98551D03*
X1090044Y110445D03*
Y115401D03*
X1080633Y116496D03*
Y109410D03*
Y130670D03*
Y123583D03*
X1090044Y124618D03*
Y129574D03*
X1080633Y137756D03*
X1087957Y147540D03*
Y151540D03*
X1092321Y181366D03*
X1089110Y181426D03*
X1091935Y184012D03*
X1089318Y184221D03*
X1081724Y208213D03*
X1085796Y208695D03*
Y211695D03*
X1081724Y210713D03*
Y213213D03*
X1088596Y208695D03*
X1088296Y211695D03*
X1081724Y215713D03*
X1077097Y264180D03*
X1083491Y267526D03*
X1088791D03*
X1086291D03*
X1083491Y270026D03*
X1086291D03*
X1088791D03*
X1077855Y327478D03*
X1077602Y314060D03*
X1079748Y322743D03*
Y319343D03*
X1077855Y332434D03*
X1082297Y340770D03*
X1092554Y340318D03*
X1085615Y339815D03*
X1079863Y345660D03*
X1082787Y348501D03*
X1091031Y374810D03*
X1091542Y389154D03*
Y410413D03*
Y396240D03*
Y403327D03*
Y417500D03*
Y424587D03*
Y431673D03*
Y438760D03*
Y445847D03*
Y467539D03*
Y474626D03*
Y488799D03*
Y481713D03*
Y495886D03*
Y511673D03*
Y518760D03*
Y525847D03*
Y532933D03*
Y540020D03*
Y547106D03*
X1090823Y602197D03*
X1091287Y595108D03*
X1083283Y1526583D03*
X1084000Y1529600D03*
X1091529Y1528718D03*
X1091525Y1546300D03*
X1090469Y1588435D03*
X1083900Y1593206D03*
X1090747Y1617415D03*
X1092000Y1644980D03*
X1100446Y117557D03*
X1095036Y115401D03*
Y110445D03*
X1105438Y117557D03*
X1100130Y106186D03*
X1093195Y103783D03*
X1095036Y129574D03*
Y124618D03*
X1105438Y131731D03*
Y122513D03*
X1100446Y131731D03*
Y122513D03*
X1103537Y146461D03*
X1100446Y136687D03*
X1105438D03*
X1102439Y152367D03*
X1104139Y180572D03*
X1108822Y180527D03*
X1095116Y181009D03*
X1100291Y168697D03*
X1104139Y185165D03*
X1108777Y185121D03*
X1105888Y206767D03*
X1108388D03*
X1103388D03*
X1093354Y213859D03*
Y211359D03*
X1097057Y213132D03*
X1104633Y228221D03*
X1106018Y221708D03*
X1108518D03*
X1102933Y224421D03*
X1103518Y221708D03*
X1104633Y231021D03*
X1097057Y215632D03*
X1105184Y236189D03*
X1107684D03*
X1105125Y248765D03*
X1107625D03*
X1107822Y268195D03*
X1105322D03*
Y270695D03*
X1107822D03*
X1108779Y327705D03*
X1100703Y340560D03*
X1105012Y353504D03*
X1098845Y353404D03*
X1093994Y374003D03*
X1093841Y371335D03*
X1099342Y389154D03*
X1106161D03*
X1099342Y396240D03*
X1100621Y404911D03*
X1104691Y396240D03*
X1099575Y412571D03*
X1108776Y422864D03*
X1100762Y426299D03*
X1108846Y429832D03*
X1108451Y436447D03*
X1101073Y445847D03*
X1099342Y467539D03*
Y474626D03*
X1108395Y472772D03*
X1099603Y480828D03*
X1101553Y498834D03*
X1105002Y516841D03*
X1108253Y510565D03*
X1099342Y518760D03*
Y511673D03*
Y525847D03*
X1099949Y550123D03*
X1099827Y552872D03*
X1101581Y572334D03*
X1099272Y562443D03*
X1101040Y560675D03*
X1099813Y574102D03*
X1105298Y598400D03*
Y602400D03*
Y594400D03*
Y614400D03*
Y606400D03*
X1104448Y653161D03*
X1108045Y677843D03*
X1095080Y1513398D03*
X1096780Y1526700D03*
X1095250Y1531600D03*
X1098617Y1546183D03*
X1096264Y1562285D03*
X1093713Y1585583D03*
X1107620Y1606752D03*
X1114781Y58013D03*
X1113646Y68581D03*
X1113659Y80581D03*
X1116368Y117261D03*
X1112545Y192421D03*
X1112868Y221642D03*
X1110184Y236189D03*
X1110125Y248765D03*
X1116782Y265897D03*
X1114282D03*
X1110622Y268195D03*
Y270695D03*
X1123500Y329000D03*
Y339000D03*
Y334000D03*
X1117453Y389154D03*
X1124753Y389153D03*
X1118848Y382109D03*
X1122253Y396240D03*
X1124753D03*
X1122253Y403327D03*
X1124753Y403326D03*
X1122253Y410413D03*
X1124753D03*
X1117453Y396240D03*
Y403327D03*
Y410413D03*
X1109468Y414823D03*
X1122253Y424586D03*
X1124753D03*
X1117453Y417500D03*
Y424586D03*
X1122253Y417500D03*
X1124753Y417499D03*
X1122253Y438760D03*
X1124753D03*
Y431673D03*
X1117453D03*
Y438760D03*
X1122253Y431673D03*
X1110486Y447953D03*
X1122253Y445847D03*
X1117453D03*
X1109653Y467539D03*
X1124753D03*
X1117453D03*
X1122253Y474626D03*
X1124753D03*
X1117453D03*
X1122253Y488799D03*
X1124753D03*
X1117453D03*
X1109129Y487711D03*
X1109242Y479104D03*
X1124753Y481712D03*
X1122253D03*
X1117453Y481713D03*
X1122253Y495886D03*
X1117453D03*
X1109653D03*
X1124753Y518760D03*
X1122253D03*
X1124753Y511673D03*
X1117453D03*
Y518760D03*
X1124753Y532933D03*
X1122253D03*
Y540020D03*
Y525846D03*
X1124753D03*
X1117453Y525847D03*
Y532933D03*
Y540020D03*
Y554193D03*
Y547106D03*
X1117913Y565414D03*
Y567914D03*
Y570414D03*
Y572914D03*
Y575414D03*
X1114668Y577937D03*
X1117453Y602205D03*
Y595118D03*
X1122718Y598857D03*
X1121191Y612555D03*
X1120512Y617332D03*
X1121022Y607750D03*
X1118863Y662981D03*
X1112839Y668885D03*
X1113244Y691851D03*
X1111785Y686971D03*
X1118855Y705043D03*
X1112000Y1644980D03*
X1135868Y116594D03*
Y119594D03*
X1125864Y248371D03*
X1129553Y389153D03*
Y396240D03*
Y403326D03*
Y410413D03*
X1142440Y404718D03*
X1129553Y424586D03*
Y417499D03*
X1142440Y412718D03*
X1129553Y431673D03*
Y438760D03*
X1126931Y453564D03*
X1130355Y453483D03*
X1135548Y455804D03*
X1129553Y467539D03*
X1125178Y459792D03*
X1129553Y474626D03*
Y488799D03*
Y481712D03*
Y518760D03*
Y511673D03*
Y532933D03*
Y525846D03*
X1138166Y534759D03*
X1139673Y530000D03*
X1138098Y543925D03*
X1138673Y555000D03*
X1139173Y540500D03*
X1126633Y560500D03*
X1125287Y592897D03*
X1129637Y1465913D03*
Y1461182D03*
Y1456451D03*
X1138298Y1465513D03*
Y1460782D03*
X1129637Y1476536D03*
Y1481267D03*
X1138298Y1476136D03*
Y1470244D03*
Y1480867D03*
X1129637Y1471805D03*
Y1496621D03*
X1138298Y1491490D03*
Y1485598D03*
Y1496221D03*
X1129637Y1491890D03*
Y1487159D03*
X1138298Y1500952D03*
Y1511576D03*
X1129637Y1507245D03*
Y1502514D03*
Y1511976D03*
X1138298Y1506845D03*
Y1516307D03*
X1129637Y1563544D03*
Y1558813D03*
X1138298Y1563144D03*
Y1572606D03*
X1129637Y1568275D03*
Y1578898D03*
Y1574167D03*
X1138298Y1567875D03*
Y1578498D03*
X1129637Y1583629D03*
Y1594253D03*
Y1589522D03*
X1138298Y1583229D03*
Y1593853D03*
Y1587960D03*
Y1598584D03*
Y1603315D03*
X1129637Y1609607D03*
Y1598984D03*
Y1604876D03*
X1138298Y1609207D03*
X1129637Y1614338D03*
X1138298Y1613938D03*
Y1618669D03*
X1132000Y1644980D03*
X1147214Y44773D03*
X1154535Y53597D03*
X1145485Y97667D03*
X1149464Y195176D03*
X1148482Y199248D03*
X1151482D03*
X1144464Y195176D03*
X1146964D03*
X1151964D03*
X1151482Y202048D03*
X1146318Y206806D03*
X1144545Y210509D03*
X1147045D03*
X1148818Y206806D03*
X1148482Y201748D03*
X1151098Y238714D03*
X1145761Y324148D03*
X1142440Y392718D03*
Y400718D03*
Y408718D03*
X1157451Y618288D03*
X1157251Y636842D03*
X1156023Y678462D03*
X1149437Y728541D03*
X1152512Y728543D03*
X1152316Y746625D03*
X1149345Y771517D03*
X1145910Y794217D03*
X1151277Y790996D03*
X1149627Y813323D03*
X1146985Y812642D03*
X1152510Y844642D03*
X1146960Y1465913D03*
Y1461182D03*
X1155621Y1465513D03*
Y1460782D03*
X1146960Y1456451D03*
X1155621Y1480867D03*
X1146960Y1471805D03*
Y1476536D03*
Y1481267D03*
X1155621Y1476136D03*
Y1470244D03*
Y1491490D03*
Y1485598D03*
Y1496221D03*
X1146960Y1487159D03*
Y1491890D03*
Y1496621D03*
Y1507245D03*
Y1502514D03*
X1155621Y1506845D03*
Y1500952D03*
Y1511576D03*
X1146960Y1511976D03*
X1155621Y1516307D03*
X1146960Y1563544D03*
X1155621Y1563144D03*
X1146960Y1558813D03*
X1155621Y1572606D03*
X1146960Y1568275D03*
X1155621Y1567875D03*
X1146960Y1574167D03*
Y1578898D03*
X1155621Y1578498D03*
X1146960Y1594253D03*
X1155621Y1593853D03*
Y1587960D03*
X1146960Y1583629D03*
X1155621Y1583229D03*
X1146960Y1589522D03*
Y1609607D03*
Y1604876D03*
Y1598984D03*
X1155621Y1609207D03*
Y1598584D03*
Y1603315D03*
X1146960Y1614338D03*
X1155621Y1613938D03*
Y1618669D03*
X1152000Y1644980D03*
X1166362Y130670D03*
X1171586Y137756D03*
X1166357D03*
X1173630Y207978D03*
Y210478D03*
Y212978D03*
Y215478D03*
X1168902Y431029D03*
X1167931Y435029D03*
X1169173Y427017D03*
X1168685Y438323D03*
X1168851Y449873D03*
X1171255Y456287D03*
X1173278Y472579D03*
X1168478D03*
X1163298Y465874D03*
X1173278Y479666D03*
X1168478D03*
Y486752D03*
X1173278D03*
X1168478Y493839D03*
X1173278D03*
X1168478Y523800D03*
Y516713D03*
X1173278D03*
Y523800D03*
Y537973D03*
X1168478D03*
X1173278Y530886D03*
X1168478D03*
X1161274Y550462D03*
X1159535Y546712D03*
X1173278Y566752D03*
X1168478D03*
Y580926D03*
X1173278D03*
Y588013D03*
X1168478D03*
X1173278Y573839D03*
X1168478D03*
Y602186D03*
X1173278D03*
Y595099D03*
X1168478D03*
X1173278Y609272D03*
X1168478D03*
Y616359D03*
X1173278D03*
X1163157Y638125D03*
X1160756Y665140D03*
X1160275Y656321D03*
X1164275D03*
X1170603Y715281D03*
X1163751Y719498D03*
X1168577Y733812D03*
X1171934Y733857D03*
X1157985Y791142D03*
X1161291Y791662D03*
X1173697Y791911D03*
X1160516Y800900D03*
X1169266Y800799D03*
X1164283Y1465913D03*
Y1456451D03*
Y1461182D03*
X1172944Y1465513D03*
Y1460782D03*
Y1470244D03*
Y1480867D03*
X1164283Y1471805D03*
Y1476536D03*
Y1481267D03*
X1172944Y1476136D03*
X1164283Y1487159D03*
Y1491890D03*
Y1496621D03*
X1172944Y1491490D03*
Y1485598D03*
Y1496221D03*
X1164283Y1507245D03*
Y1502514D03*
X1172944Y1506845D03*
Y1500952D03*
Y1511576D03*
X1164283Y1511976D03*
X1172944Y1516307D03*
X1164283Y1558813D03*
Y1563544D03*
X1172944Y1563144D03*
Y1567875D03*
X1164283Y1574167D03*
Y1578898D03*
X1172944Y1578498D03*
Y1572606D03*
X1164283Y1568275D03*
Y1583629D03*
X1172944Y1583229D03*
X1164283Y1589522D03*
Y1594253D03*
X1172944Y1593853D03*
Y1587960D03*
Y1598584D03*
Y1603315D03*
X1164283Y1609607D03*
Y1604876D03*
Y1598984D03*
X1172944Y1609207D03*
X1164283Y1614338D03*
X1172944Y1613938D03*
Y1618669D03*
X1172000Y1644980D03*
X1174535Y53597D03*
X1174995Y116496D03*
Y109410D03*
X1182995Y116496D03*
Y109410D03*
X1174995Y130670D03*
Y123583D03*
X1182995Y130670D03*
Y123583D03*
Y137756D03*
X1188158Y211695D03*
X1184086Y210713D03*
Y213213D03*
Y208213D03*
X1190958Y208695D03*
X1188158D03*
X1184086Y215713D03*
X1176959Y264180D03*
X1179459D03*
X1185853Y267526D03*
X1188653D03*
X1185853Y270026D03*
X1188653D03*
X1181706Y310131D03*
X1178045Y312193D03*
X1174929Y319167D03*
X1182911Y336516D03*
X1177036Y334148D03*
X1188598Y390500D03*
X1179184Y410394D03*
Y403307D03*
X1180118Y430098D03*
Y440098D03*
Y437598D03*
Y435098D03*
Y432598D03*
X1180578Y458406D03*
Y451319D03*
X1188378Y466027D03*
X1180402Y462264D03*
X1175778Y465492D03*
X1180578D03*
X1188520Y475262D03*
X1175778Y472579D03*
X1180578D03*
X1188520Y489435D03*
Y482666D03*
X1175778Y479666D03*
X1180578Y479665D03*
Y486752D03*
X1175778D03*
X1180578Y493839D03*
X1188336Y495088D03*
X1175778Y509626D03*
X1180578Y523799D03*
Y516713D03*
Y509626D03*
X1175778Y516713D03*
Y523800D03*
X1189071Y514608D03*
X1188993Y522134D03*
X1188378Y509626D03*
X1180578Y537973D03*
X1175778Y530886D03*
X1180578D03*
X1189475Y535677D03*
X1189636Y529136D03*
X1180578Y559665D03*
Y566752D03*
X1175778D03*
Y559665D03*
X1188378D03*
X1188759Y565574D03*
X1175778Y580926D03*
X1180578D03*
Y588012D03*
X1175778D03*
X1180578Y573839D03*
X1175778D03*
X1188406Y574338D03*
X1175778Y602185D03*
X1180578D03*
X1175778Y595099D03*
X1180578D03*
X1175778Y609272D03*
X1180578Y616358D03*
Y609272D03*
X1188505Y616358D03*
X1177745Y771744D03*
X1177566Y778539D03*
X1190062Y844378D03*
X1187703Y849734D03*
X1186742Y855466D03*
X1183431Y868340D03*
X1177775Y894053D03*
X1176577Y885974D03*
X1178480Y915220D03*
X1178000Y936500D03*
X1188431Y936568D03*
X1187200Y963400D03*
X1181605Y1465913D03*
Y1456451D03*
Y1461182D03*
Y1471805D03*
Y1476536D03*
Y1481267D03*
Y1487159D03*
Y1491890D03*
Y1496621D03*
Y1507245D03*
Y1502514D03*
Y1511976D03*
Y1558813D03*
Y1563544D03*
Y1568275D03*
Y1574167D03*
Y1578898D03*
Y1583629D03*
Y1589522D03*
Y1594253D03*
Y1598984D03*
Y1609607D03*
Y1604876D03*
Y1614338D03*
X1193330Y5374D03*
X1192643Y24773D03*
Y44773D03*
X1192007Y98551D03*
X1202808Y117557D03*
X1197398Y110445D03*
Y115401D03*
X1192406Y110445D03*
Y115401D03*
X1195557Y103783D03*
X1202492Y106186D03*
X1197398Y129574D03*
Y124618D03*
X1192406D03*
Y129574D03*
X1202808Y122513D03*
Y131731D03*
X1205899Y146461D03*
X1202808Y136687D03*
X1190319Y147540D03*
X1204801Y152367D03*
X1190319Y151540D03*
X1194683Y181366D03*
X1191472Y181426D03*
X1197478Y181009D03*
X1202653Y168697D03*
X1194297Y184012D03*
X1191680Y184221D03*
X1205750Y206767D03*
X1195716Y211359D03*
Y213859D03*
X1199419Y213132D03*
X1190658Y211695D03*
X1205295Y224421D03*
X1205880Y221708D03*
X1199419Y215632D03*
X1191153Y267526D03*
Y270026D03*
X1192500Y322400D03*
X1198248Y381500D03*
X1198468Y430760D03*
X1198489Y433570D03*
X1198305Y437072D03*
X1198346Y439963D03*
X1198552Y452018D03*
X1198590Y443180D03*
X1198610Y454744D03*
X1198689Y465492D03*
X1198655Y460250D03*
X1196420Y470136D03*
X1198689Y472579D03*
Y486752D03*
Y479665D03*
Y493839D03*
Y509626D03*
Y516713D03*
X1195149Y537973D03*
X1197629Y525483D03*
X1197550Y532756D03*
X1198689Y559665D03*
Y566752D03*
X1198539Y579978D03*
X1198689Y573839D03*
X1198753Y608117D03*
X1195118Y936296D03*
X1201794Y985289D03*
X1195757Y988131D03*
X1198845Y998504D03*
X1204919Y1021860D03*
X1202268Y1013551D03*
X1190267Y1465513D03*
Y1460782D03*
X1198928Y1465914D03*
Y1456452D03*
Y1461183D03*
Y1481268D03*
X1190267Y1476136D03*
Y1470244D03*
Y1480867D03*
X1198928Y1476537D03*
Y1471806D03*
X1190267Y1485598D03*
Y1496221D03*
X1198928Y1491891D03*
Y1487160D03*
Y1496622D03*
X1190267Y1491490D03*
Y1506845D03*
Y1500952D03*
Y1511576D03*
X1198928Y1507246D03*
Y1502515D03*
Y1511977D03*
X1190267Y1516307D03*
X1198928Y1558813D03*
X1190267Y1563144D03*
X1198928Y1563544D03*
X1190267Y1567875D03*
X1198928Y1568275D03*
X1190267Y1578498D03*
Y1572606D03*
X1198928Y1578898D03*
Y1574167D03*
X1190267Y1583229D03*
X1198928Y1583629D03*
X1190267Y1593853D03*
Y1587960D03*
X1198928Y1594253D03*
Y1589522D03*
X1190267Y1609207D03*
Y1598584D03*
Y1603315D03*
X1198928Y1609607D03*
Y1598984D03*
Y1604876D03*
X1190267Y1613938D03*
Y1618669D03*
X1198928Y1614338D03*
X1192000Y1644980D03*
X1212232Y3000D03*
X1219783Y55513D03*
X1216008Y68581D03*
X1216021Y80581D03*
X1218730Y117261D03*
X1207800Y117557D03*
Y122513D03*
Y131731D03*
Y136687D03*
X1206501Y180572D03*
X1211184Y180527D03*
X1214907Y192421D03*
X1206501Y185165D03*
X1211139Y185121D03*
X1208250Y206767D03*
X1210750D03*
X1215230Y221642D03*
X1206995Y228221D03*
X1208380Y221708D03*
X1210880D03*
X1206995Y231021D03*
X1207546Y236189D03*
X1210046D03*
X1212546D03*
X1207487Y248765D03*
X1209987D03*
X1212487D03*
X1219144Y265897D03*
X1216644D03*
X1212984Y268195D03*
X1210184D03*
X1207684D03*
X1212984Y270695D03*
X1207684D03*
X1210184D03*
X1217139Y324139D03*
X1220723Y324466D03*
X1221337Y332017D03*
X1220985Y342319D03*
X1217177Y369925D03*
X1206673Y410394D03*
Y403307D03*
X1206489Y458406D03*
X1212680Y445908D03*
X1216630Y445787D03*
X1206489Y465492D03*
Y472579D03*
Y479665D03*
Y486752D03*
Y493839D03*
Y523799D03*
Y516713D03*
Y509626D03*
Y537973D03*
Y530886D03*
Y566752D03*
Y559665D03*
Y580925D03*
Y588012D03*
Y573839D03*
Y602185D03*
Y595099D03*
Y616358D03*
Y609272D03*
X1212000Y1644980D03*
X1232232Y3000D03*
X1238230Y116594D03*
Y119594D03*
X1228226Y248371D03*
X1229922Y324550D03*
X1232197Y316964D03*
X1238293Y317296D03*
X1230077Y336324D03*
X1234656Y353506D03*
X1225755Y369391D03*
X1229122Y369355D03*
X1222601Y369251D03*
X1223431Y393924D03*
Y389912D03*
Y385912D03*
Y409924D03*
Y405924D03*
Y401924D03*
X1235166Y470706D03*
Y467306D03*
Y484879D03*
Y481479D03*
Y514839D03*
Y511439D03*
Y529013D03*
Y525613D03*
Y564879D03*
Y561479D03*
Y575652D03*
Y579052D03*
Y593225D03*
Y603999D03*
Y589825D03*
Y607399D03*
X1232000Y1644980D03*
X1248216Y4469D03*
X1249577Y24773D03*
Y44773D03*
X1247847Y97667D03*
X1251826Y195176D03*
X1254326D03*
X1253844Y199248D03*
X1249326Y195176D03*
X1250844Y199248D03*
X1246826Y195176D03*
X1249407Y210509D03*
X1253844Y202048D03*
X1250844Y201748D03*
X1251180Y206806D03*
X1248680D03*
X1246907Y210509D03*
X1253460Y238714D03*
X1245568Y474418D03*
Y488591D03*
Y477818D03*
Y491991D03*
Y521952D03*
Y518552D03*
Y536125D03*
Y532725D03*
Y568591D03*
Y571991D03*
Y582765D03*
Y586165D03*
Y596938D03*
Y600338D03*
Y611111D03*
Y614511D03*
X1245900Y1528000D03*
X1254275Y1531334D03*
X1249894Y1527805D03*
X1254275Y1539334D03*
X1250434Y1535334D03*
X1256898Y53597D03*
X1268724Y130670D03*
X1268719Y137756D03*
X1263328Y309003D03*
X1266219Y374300D03*
X1268659Y377173D03*
X1261623Y447486D03*
X1259223Y458334D03*
X1267843Y488618D03*
Y491118D03*
X1270951Y491870D03*
X1269876Y1132319D03*
X1263873Y1148000D03*
X1266709Y1160168D03*
X1258736Y1188223D03*
X1268573Y1193019D03*
X1264573D03*
X1263242Y1523458D03*
X1262985Y1519459D03*
X1267333Y1531334D03*
X1262891Y1527334D03*
X1260260Y1546500D03*
X1267183Y1539334D03*
X1262891Y1535334D03*
X1276898Y53597D03*
X1277357Y116496D03*
Y109410D03*
X1285357Y116496D03*
Y109410D03*
Y123583D03*
X1277357Y130670D03*
Y123583D03*
X1285357Y130670D03*
X1273555Y137756D03*
X1285357D03*
X1275992Y215478D03*
Y212978D03*
Y210478D03*
Y207978D03*
X1286448Y213213D03*
Y210713D03*
Y208213D03*
Y215713D03*
X1281821Y264180D03*
X1279321D03*
X1281834Y374839D03*
X1287437Y370010D03*
X1275940Y392228D03*
X1271346Y392183D03*
X1275407Y402867D03*
X1271391Y396866D03*
X1275984D03*
X1282760Y409016D03*
X1278724Y409032D03*
X1272215Y442518D03*
Y439718D03*
X1279127Y450091D03*
X1282092Y449118D03*
Y446318D03*
X1281737Y452740D03*
X1283455Y468088D03*
Y465288D03*
X1280616Y472189D03*
X1279505Y487570D03*
Y490070D03*
X1276060Y496258D03*
X1273451Y491870D03*
X1276060Y493758D03*
X1283400Y715500D03*
Y719700D03*
X1285500Y827500D03*
X1281388Y827388D03*
X1285500Y843500D03*
X1281331Y843331D03*
X1281269Y835492D03*
X1285500Y835500D03*
Y863500D03*
Y859500D03*
Y855500D03*
Y867500D03*
X1274264Y898591D03*
X1283494Y907176D03*
X1273865Y1132497D03*
X1272120Y1159455D03*
X1280306Y1162817D03*
X1276573Y1193019D03*
X1280573D03*
X1272573D03*
X1277108Y1211664D03*
X1279402Y1213958D03*
X1275032Y1209589D03*
X1284198Y1218754D03*
X1302232Y3000D03*
X1295692Y5374D03*
X1295005Y24773D03*
X1297785Y33768D03*
X1295005Y44773D03*
X1294369Y98551D03*
X1299760Y110445D03*
Y115401D03*
X1294768Y110445D03*
Y115401D03*
X1297919Y103783D03*
X1294768Y129574D03*
X1299760D03*
Y124618D03*
X1294768D03*
X1299840Y181009D03*
X1293834Y181426D03*
X1297045Y181366D03*
X1294042Y184221D03*
X1296659Y184012D03*
X1301781Y213132D03*
X1298078Y211359D03*
Y213859D03*
X1290520Y211695D03*
X1293020D03*
X1290520Y208695D03*
X1293320D03*
X1301781Y215632D03*
X1293515Y270026D03*
X1291015D03*
X1288215D03*
Y267526D03*
X1293515D03*
X1291015D03*
X1294000Y324000D03*
X1293000Y338500D03*
X1295410Y371076D03*
X1291165Y395248D03*
X1290092Y449118D03*
Y446318D03*
X1299757Y450041D03*
Y452841D03*
Y455641D03*
X1290272Y458309D03*
Y454309D03*
Y462309D03*
X1296783Y511956D03*
X1298966Y899610D03*
X1296466D03*
X1302000Y917000D03*
X1302500Y939500D03*
X1296500Y961500D03*
X1290792Y961363D03*
X1300500Y970187D03*
X1297852Y1014475D03*
X1302866Y1491890D03*
Y1487159D03*
Y1496621D03*
Y1507245D03*
Y1502514D03*
Y1511976D03*
Y1578898D03*
Y1574167D03*
Y1594253D03*
Y1589522D03*
Y1583629D03*
Y1609607D03*
Y1598984D03*
Y1604876D03*
Y1614338D03*
X1292000Y1644980D03*
X1310853Y37543D03*
X1310162Y117557D03*
X1305170D03*
X1304854Y106186D03*
X1310162Y122513D03*
Y131731D03*
X1305170Y122513D03*
Y131731D03*
X1310162Y136687D03*
X1305170D03*
X1313546Y180527D03*
X1308863Y180572D03*
X1305015Y168697D03*
X1308863Y185165D03*
X1317269Y192421D03*
X1313501Y185121D03*
X1308112Y206767D03*
X1313112D03*
X1310612D03*
X1313242Y221708D03*
X1310742D03*
X1309357Y231021D03*
Y228221D03*
X1317592Y221642D03*
X1308242Y221708D03*
X1307657Y224421D03*
X1309908Y236189D03*
X1314908D03*
X1312408D03*
X1312349Y248765D03*
X1309849D03*
X1314849D03*
X1310046Y268195D03*
X1312546D03*
X1315346D03*
X1319006Y265897D03*
X1312546Y270695D03*
X1310046D03*
X1315346D03*
X1305928Y318250D03*
X1308428D03*
X1315397Y333709D03*
X1310172Y367956D03*
X1313691Y402642D03*
X1316191D03*
X1310546Y409904D03*
Y407104D03*
X1309117Y398949D03*
X1306617Y401949D03*
X1308066Y413611D03*
X1310866D03*
X1313366D03*
X1315866D03*
X1315806Y423944D03*
X1313306D03*
X1310806D03*
X1308006D03*
X1309750Y455641D03*
Y450041D03*
Y452841D03*
X1308010Y466409D03*
X1307996Y487382D03*
X1311488Y479560D03*
X1307919Y478382D03*
X1307825Y482382D03*
X1319000Y566500D03*
Y582500D03*
X1319323Y598454D03*
X1313979Y677726D03*
X1305412Y799061D03*
X1305134Y812065D03*
X1315000Y811620D03*
X1319000D03*
X1310971Y842319D03*
X1319500Y905000D03*
X1319554Y925585D03*
X1309103Y936559D03*
X1306500Y936500D03*
X1315779Y943743D03*
X1311000Y961500D03*
X1307000Y970000D03*
X1311000Y970124D03*
X1307707Y979870D03*
X1307561Y986951D03*
X1312873Y1036543D03*
X1306385Y1036646D03*
X1313459Y1081599D03*
X1310589Y1097278D03*
X1313089D03*
X1317437Y1152684D03*
X1318178Y1198321D03*
Y1200821D03*
X1307167Y1245696D03*
X1308276Y1276446D03*
X1310773Y1282411D03*
X1311527Y1491490D03*
Y1496221D03*
Y1506845D03*
Y1500952D03*
Y1511576D03*
Y1516307D03*
Y1578498D03*
Y1583229D03*
Y1593853D03*
Y1587960D03*
Y1609207D03*
Y1598584D03*
Y1603315D03*
Y1613938D03*
Y1618669D03*
X1312000Y1644980D03*
X1322232Y3000D03*
X1334223Y33425D03*
X1322853Y37530D03*
X1321092Y117261D03*
X1321506Y265897D03*
X1332359Y322685D03*
X1325007Y370951D03*
X1333049Y399268D03*
Y401768D03*
Y396768D03*
X1321016Y399161D03*
Y401661D03*
Y396661D03*
X1325941Y408240D03*
X1328441D03*
X1323441D03*
X1326059Y420393D03*
X1326020Y424240D03*
X1323559Y420393D03*
X1328559D03*
X1326020Y426740D03*
X1329626Y455039D03*
X1332927Y468607D03*
X1325927Y474513D03*
X1326912Y493153D03*
X1325630Y513238D03*
X1331096Y549931D03*
X1326946Y567906D03*
X1335000Y590500D03*
Y586500D03*
X1327000Y583826D03*
X1333224Y615484D03*
X1327000Y613000D03*
Y629000D03*
Y657500D03*
X1331000Y811620D03*
X1327000D03*
X1325000Y804000D03*
X1333000D03*
X1323000Y811620D03*
X1335000D03*
X1331056Y904557D03*
X1336096Y905042D03*
X1336000Y900500D03*
X1330500Y925500D03*
X1333425Y930925D03*
X1324000D03*
X1335343Y961727D03*
X1321028Y961749D03*
X1325550Y960445D03*
X1332000Y969500D03*
X1327000D03*
X1320549Y1037876D03*
X1322773Y1040599D03*
X1331890Y1051919D03*
X1331359Y1098898D03*
X1334161Y1098518D03*
X1333905Y1123101D03*
X1331405D03*
X1323405D03*
X1320279Y1131935D03*
Y1134435D03*
Y1136935D03*
Y1139435D03*
X1334305Y1129301D03*
X1331805D03*
X1329305D03*
X1326805D03*
X1324305D03*
X1321805D03*
X1334305Y1125801D03*
X1331805D03*
X1323405D03*
X1320279Y1141935D03*
Y1146935D03*
Y1144435D03*
X1326269Y1152713D03*
Y1155213D03*
X1320493Y1204405D03*
X1334793Y1204617D03*
X1331643Y1200821D03*
Y1198321D03*
X1320493Y1206905D03*
Y1211905D03*
Y1209405D03*
X1334793Y1207117D03*
Y1209617D03*
Y1212117D03*
X1335470Y1297498D03*
X1328850Y1491490D03*
X1320189Y1496621D03*
X1328850Y1496221D03*
X1320189Y1487159D03*
Y1491890D03*
Y1502514D03*
X1328850Y1506845D03*
Y1500952D03*
Y1511576D03*
X1320189Y1511976D03*
Y1507245D03*
X1328850Y1516307D03*
X1320189Y1574167D03*
Y1578898D03*
X1328850Y1578498D03*
Y1583229D03*
X1320189Y1589522D03*
Y1594253D03*
X1328850Y1593853D03*
Y1587960D03*
X1320189Y1583629D03*
X1328850Y1603315D03*
X1320189Y1609607D03*
Y1604876D03*
Y1598984D03*
X1328850Y1609207D03*
Y1598584D03*
Y1613938D03*
Y1618669D03*
X1320189Y1614338D03*
X1332000Y1644980D03*
X1342232Y3000D03*
X1340320Y147540D03*
Y151540D03*
X1344007Y279054D03*
X1347990Y322539D03*
X1341169Y325926D03*
X1349763Y371908D03*
X1347897Y433975D03*
X1346483Y436164D03*
X1343846Y461607D03*
X1344129Y606914D03*
X1344433Y601201D03*
X1344680Y619085D03*
X1346378Y623734D03*
X1351000Y811620D03*
X1347000D03*
X1343000D03*
X1341000Y804000D03*
X1351511Y900000D03*
X1347380Y1057998D03*
Y1055498D03*
X1344880D03*
Y1057998D03*
X1347380Y1060498D03*
Y1062998D03*
X1344880D03*
Y1060498D03*
X1339349Y1098767D03*
X1339305Y1129301D03*
X1336805D03*
X1339305Y1125801D03*
X1336805D03*
X1343505Y1136935D03*
Y1134435D03*
Y1139435D03*
Y1131935D03*
X1349907D03*
Y1134435D03*
Y1136935D03*
Y1139435D03*
X1352407Y1131935D03*
Y1134435D03*
Y1136935D03*
Y1139435D03*
X1343505Y1146935D03*
Y1144435D03*
Y1141935D03*
X1349907D03*
Y1146935D03*
Y1144435D03*
X1352407Y1141935D03*
Y1146935D03*
Y1144435D03*
X1336669Y1152713D03*
Y1155213D03*
X1351405Y1154902D03*
Y1152402D03*
X1347423Y1204405D03*
X1337108Y1200821D03*
Y1198321D03*
X1345108Y1200821D03*
Y1198321D03*
X1347423Y1209405D03*
Y1211905D03*
Y1206905D03*
X1340870Y1297498D03*
X1346270D03*
X1351670D03*
X1346173Y1491490D03*
X1337512Y1487159D03*
Y1491890D03*
Y1496621D03*
X1346173Y1496221D03*
X1337512Y1507245D03*
Y1502514D03*
X1346173Y1506845D03*
Y1500952D03*
Y1511576D03*
X1337512Y1511976D03*
X1346173Y1516307D03*
X1337512Y1574167D03*
Y1578898D03*
X1346173Y1578498D03*
X1337512Y1583629D03*
X1346173Y1583229D03*
X1337512Y1589522D03*
Y1594253D03*
X1346173Y1593853D03*
Y1587960D03*
X1337512Y1609607D03*
Y1604876D03*
Y1598984D03*
X1346173Y1609207D03*
Y1598584D03*
Y1603315D03*
X1337512Y1614338D03*
X1346173Y1613938D03*
Y1618669D03*
X1352000Y1644980D03*
X1362232Y3000D03*
X1355900Y146461D03*
X1354802Y152367D03*
X1361039Y327099D03*
Y332055D03*
X1364039Y334973D03*
Y339929D03*
X1361039Y342847D03*
X1364039Y350721D03*
X1361039Y347803D03*
X1364039Y355677D03*
X1360352Y447101D03*
X1363173Y994483D03*
X1363905Y1000855D03*
X1366493Y1000828D03*
X1367884Y1018825D03*
X1357265Y1022766D03*
X1364237Y1043140D03*
X1357265Y1030266D03*
X1363941Y1047047D03*
X1364418Y1090568D03*
Y1093068D03*
X1366289Y1098518D03*
X1361037Y1098428D03*
X1355533Y1123101D03*
X1363533D03*
X1366033D03*
X1366433Y1129301D03*
X1355533Y1125801D03*
X1363933D03*
X1366433D03*
X1353933Y1129301D03*
X1356433D03*
X1358933D03*
X1361433D03*
X1363933D03*
X1357397Y1155213D03*
Y1152713D03*
X1366797D03*
Y1155213D03*
X1361723Y1204617D03*
X1364038Y1198321D03*
Y1200821D03*
X1361723Y1212117D03*
Y1209617D03*
Y1207117D03*
X1357070Y1297498D03*
X1354834Y1487159D03*
Y1496621D03*
X1363496Y1491490D03*
Y1496221D03*
X1354834Y1491890D03*
Y1502514D03*
Y1511976D03*
X1363496Y1511576D03*
Y1506845D03*
Y1500952D03*
X1354834Y1507245D03*
X1363496Y1516307D03*
X1354834Y1574167D03*
Y1578898D03*
X1363496Y1578498D03*
X1354834Y1583629D03*
Y1589522D03*
Y1594253D03*
X1363496Y1583229D03*
Y1593853D03*
Y1587960D03*
X1354834Y1609607D03*
Y1604876D03*
Y1598984D03*
X1363496Y1609207D03*
Y1598584D03*
Y1603315D03*
X1354834Y1614338D03*
X1363496Y1613938D03*
Y1618669D03*
X1382232Y3000D03*
X1378227Y248371D03*
X1384253Y346826D03*
X1384447Y356871D03*
X1384174Y362641D03*
X1383963Y366675D03*
X1375400Y435192D03*
X1375360Y432234D03*
X1378957Y584457D03*
X1383000Y584500D03*
X1378957Y630957D03*
X1384657Y631620D03*
X1378957Y675457D03*
X1383000Y675500D03*
X1378957Y722457D03*
X1385290Y722400D03*
X1385360Y811757D03*
X1371379Y986717D03*
X1370384Y1004680D03*
X1383669Y1011303D03*
Y1017303D03*
Y1023303D03*
X1376601Y1030218D03*
X1373874Y1032266D03*
Y1035716D03*
X1374451Y1090568D03*
Y1093068D03*
X1371477Y1098767D03*
X1375633Y1136935D03*
Y1134435D03*
Y1139435D03*
Y1131935D03*
X1383366D03*
Y1134435D03*
Y1136935D03*
Y1139435D03*
X1368933Y1125801D03*
X1371433D03*
X1368933Y1129301D03*
X1371433D03*
X1383024Y1152684D03*
X1376861D03*
X1375633Y1146935D03*
Y1144435D03*
Y1141935D03*
X1383366D03*
Y1146935D03*
Y1144435D03*
X1375459Y1197471D03*
Y1193471D03*
X1379959Y1197471D03*
Y1193471D03*
X1377390Y1244055D03*
Y1250760D03*
Y1254164D03*
X1372157Y1487160D03*
Y1491891D03*
Y1496622D03*
Y1502515D03*
Y1507246D03*
Y1511977D03*
Y1574167D03*
Y1578898D03*
Y1583629D03*
Y1589522D03*
Y1594253D03*
Y1604876D03*
Y1598984D03*
Y1609607D03*
Y1614338D03*
X1372000Y1644980D03*
X1398216Y4469D03*
X1399577Y24773D03*
Y44773D03*
X1397848Y97667D03*
X1388231Y116594D03*
Y119594D03*
X1399327Y195176D03*
X1396827D03*
X1400845Y199248D03*
Y201748D03*
X1398681Y206806D03*
X1401181D03*
X1399408Y210509D03*
X1396908D03*
X1385943Y323222D03*
X1385971Y327688D03*
X1386143Y331982D03*
X1386057Y341200D03*
X1385971Y336791D03*
X1386286Y350218D03*
X1397550Y390484D03*
X1387814Y397136D03*
X1389295Y408443D03*
X1389557Y424678D03*
X1389431Y421593D03*
X1390271Y417578D03*
X1397079Y531726D03*
Y536726D03*
Y552726D03*
Y540726D03*
X1391086Y577192D03*
X1400912Y581222D03*
Y591215D03*
X1391587Y627817D03*
X1391040Y812027D03*
X1386335Y803704D03*
X1390537Y803679D03*
X1400069Y827515D03*
X1395955Y832697D03*
X1402000Y840000D03*
Y848000D03*
Y864000D03*
X1390182Y873460D03*
X1387582Y873487D03*
X1388980Y921075D03*
X1395669Y1011303D03*
X1389669D03*
X1395669Y1017303D03*
Y1023303D03*
X1389669D03*
X1399807Y1036155D03*
X1399852Y1039779D03*
X1390322Y1057998D03*
Y1055498D03*
X1392822D03*
Y1057998D03*
X1390322Y1060498D03*
Y1062998D03*
X1392822D03*
Y1060498D03*
X1399748Y1098518D03*
X1394496Y1098428D03*
X1388992Y1123101D03*
X1396992D03*
X1399492D03*
X1385866Y1131935D03*
Y1134435D03*
Y1136935D03*
Y1139435D03*
X1388992Y1125801D03*
X1397392D03*
X1399892D03*
X1387392Y1129301D03*
X1389892D03*
X1392392D03*
X1394892D03*
X1397392D03*
X1399892D03*
X1391856Y1155213D03*
Y1152713D03*
X1385866Y1141935D03*
Y1146935D03*
Y1144435D03*
X1393695Y1204405D03*
X1391380Y1200821D03*
Y1198321D03*
X1393695Y1206905D03*
Y1211905D03*
Y1209405D03*
X1385992Y1285466D03*
X1390492D03*
X1392000Y1644980D03*
X1406898Y53597D03*
X1403845Y199248D03*
X1401827Y195176D03*
X1404327D03*
X1403845Y202048D03*
X1403461Y238714D03*
X1408666Y324733D03*
X1409830Y347649D03*
X1416347Y384373D03*
X1416830Y407134D03*
X1411400Y398032D03*
X1413889Y415642D03*
X1411950Y448466D03*
X1406910Y487982D03*
Y478982D03*
Y483982D03*
Y499982D03*
X1408103Y555194D03*
X1410903D03*
X1408103Y563194D03*
X1410903D03*
X1408103Y571194D03*
X1410903D03*
X1406512Y581222D03*
X1403712D03*
Y591215D03*
X1406512D03*
X1405514Y611091D03*
X1413452Y641817D03*
X1407952D03*
X1405000Y656000D03*
Y699000D03*
X1410000Y689000D03*
Y705000D03*
Y733000D03*
X1418000Y740000D03*
X1405500Y844000D03*
Y836000D03*
Y860000D03*
Y868000D03*
X1413733Y911137D03*
X1412376Y907848D03*
X1414876D03*
X1417376D03*
X1409876D03*
X1405214Y965074D03*
X1404317Y989436D03*
X1411038Y985379D03*
X1404936Y1098767D03*
X1415494Y1139435D03*
Y1136935D03*
Y1134435D03*
Y1131935D03*
X1409092Y1136935D03*
Y1134435D03*
Y1139435D03*
Y1131935D03*
X1402392Y1125801D03*
X1404892D03*
X1402392Y1129301D03*
X1404892D03*
X1409092Y1141935D03*
X1416736Y1152713D03*
Y1155213D03*
X1402256D03*
Y1152713D03*
X1415494Y1144435D03*
Y1146935D03*
Y1141935D03*
X1409092Y1146935D03*
Y1144435D03*
X1407995Y1204617D03*
X1410310Y1200821D03*
Y1198321D03*
X1404845D03*
Y1200821D03*
X1407995Y1207117D03*
Y1209617D03*
Y1212117D03*
X1415903Y1282590D03*
X1404019Y1285290D03*
X1417711Y1301729D03*
X1410817Y1305417D03*
X1404239Y1547755D03*
X1403747Y1570433D03*
X1412000Y1644980D03*
X1426898Y53597D03*
X1427358Y116496D03*
Y109410D03*
X1421700Y122900D03*
X1427358Y130670D03*
Y123583D03*
X1418725Y130670D03*
X1423515Y137756D03*
X1418720D03*
X1425993Y212978D03*
Y207978D03*
Y210478D03*
Y215478D03*
X1429322Y264180D03*
X1431822D03*
X1429539Y293796D03*
X1432039D03*
X1431019Y434508D03*
X1427019D03*
X1424196Y446352D03*
X1428782Y445874D03*
X1417856Y455466D03*
X1427484Y470045D03*
X1422903Y469905D03*
X1430930Y500086D03*
X1433310Y504699D03*
X1430810D03*
X1433012Y516979D03*
X1430512D03*
X1431493Y521804D03*
X1427800Y528578D03*
X1432955Y527449D03*
X1431493Y524304D03*
X1427800Y531378D03*
X1421099Y546830D03*
X1427233Y628183D03*
X1424389Y627948D03*
X1430481Y658153D03*
X1426615Y674112D03*
X1425909Y691120D03*
X1426000Y753000D03*
Y761000D03*
X1420740Y1004766D03*
Y1000766D03*
X1428864Y996766D03*
X1420740Y1016266D03*
X1428823Y1020266D03*
X1420740Y1030766D03*
X1420107Y1052514D03*
X1430005Y1090568D03*
Y1093068D03*
X1431876Y1098518D03*
X1426624Y1098428D03*
X1421120Y1123101D03*
X1429120D03*
X1431620D03*
X1422020Y1129301D03*
X1424520D03*
X1427020D03*
X1429520D03*
X1432020D03*
X1417994Y1139435D03*
Y1136935D03*
Y1134435D03*
Y1131935D03*
X1421120Y1125801D03*
X1429520D03*
X1432020D03*
X1419520Y1129301D03*
X1432384Y1155213D03*
Y1152713D03*
X1422984D03*
Y1155213D03*
X1417994Y1144435D03*
Y1146935D03*
Y1141935D03*
X1420625Y1204405D03*
X1418310Y1198321D03*
Y1200821D03*
X1420625Y1206905D03*
Y1209405D03*
X1425652Y1297411D03*
X1431080Y1301702D03*
X1421238Y1301712D03*
X1428009Y1301760D03*
X1424732Y1301603D03*
X1428840Y1407740D03*
X1432258Y1414600D03*
X1422176Y1491198D03*
X1423065Y1508327D03*
X1432499Y1512175D03*
X1423806Y1524252D03*
X1424245Y1543338D03*
X1425558Y1537432D03*
X1425260Y1558072D03*
X1433558Y1555366D03*
X1423701Y1563978D03*
X1432000Y1644980D03*
X1445692Y5374D03*
X1445005Y24773D03*
Y44773D03*
X1444370Y98551D03*
X1435358Y116496D03*
Y109410D03*
X1449761Y115401D03*
Y110445D03*
X1444769D03*
Y115401D03*
X1447920Y103783D03*
X1449761Y124618D03*
X1444769D03*
Y129574D03*
X1435358Y130670D03*
Y123583D03*
X1449761Y129574D03*
X1435358Y137756D03*
X1442682Y147540D03*
Y151540D03*
X1449841Y181009D03*
X1447046Y181366D03*
X1443835Y181426D03*
X1444043Y184221D03*
X1446660Y184012D03*
X1448079Y211359D03*
Y213859D03*
X1436449Y213213D03*
Y210713D03*
X1440521Y211695D03*
X1443021D03*
X1440521Y208695D03*
X1443321D03*
X1436449Y208213D03*
Y215713D03*
X1441016Y267526D03*
Y270026D03*
X1443516D03*
X1438216D03*
X1443516Y267526D03*
X1438216D03*
X1440053Y285690D03*
X1437553D03*
X1440053Y288190D03*
X1442853D03*
Y285690D03*
X1447079Y290755D03*
X1437553Y288190D03*
X1443041Y363648D03*
X1440568Y369566D03*
X1449619Y363290D03*
X1437758Y362584D03*
X1445906Y366030D03*
X1438588Y380589D03*
X1435019Y434508D03*
X1437757Y447201D03*
X1437879Y444269D03*
X1435484Y470045D03*
X1442786Y480705D03*
X1437631Y482134D03*
Y484634D03*
X1449293Y476086D03*
X1445586Y480705D03*
X1441076Y475946D03*
Y478446D03*
X1449293Y478586D03*
Y481086D03*
Y483886D03*
X1435810Y504699D03*
X1435512Y516979D03*
X1439462Y522129D03*
X1444536Y519518D03*
X1439536D03*
X1442036D03*
X1439462Y529929D03*
X1435755Y527449D03*
X1439462Y527129D03*
Y524629D03*
X1443555Y532949D03*
X1446355D03*
X1438882Y572842D03*
X1447037Y585507D03*
X1442444D03*
X1442990Y579475D03*
X1435668Y572975D03*
X1442488Y590145D03*
X1447082Y590190D03*
X1435241Y593796D03*
X1434049Y608311D03*
X1446944Y605443D03*
X1437770Y628242D03*
X1440930Y636005D03*
Y633205D03*
Y638805D03*
X1437784Y683532D03*
X1436567Y727532D03*
X1443000Y802500D03*
Y846500D03*
X1435745Y901500D03*
X1440610Y1021567D03*
X1435266Y1031522D03*
X1435197Y1028372D03*
X1437064Y1098767D03*
X1441220Y1131935D03*
Y1139435D03*
Y1134435D03*
Y1136935D03*
X1434520Y1125801D03*
X1437020D03*
X1434520Y1129301D03*
X1437020D03*
X1441220Y1141935D03*
Y1144435D03*
Y1146935D03*
X1442448Y1152684D03*
X1434925Y1204617D03*
X1437240Y1200821D03*
Y1198321D03*
X1434925Y1207117D03*
Y1209617D03*
Y1212117D03*
X1436408Y1303462D03*
X1444438Y1308312D03*
X1439482D03*
X1441200Y1338700D03*
X1435900Y1340800D03*
X1439258Y1414600D03*
X1437293Y1546125D03*
X1436801Y1568803D03*
X1464594Y3000D03*
X1460163Y117557D03*
X1455171D03*
X1454855Y106186D03*
X1455171Y122513D03*
X1460163Y131731D03*
Y122513D03*
X1455171Y131731D03*
X1458262Y146461D03*
X1460163Y136687D03*
X1455171D03*
X1457164Y152367D03*
X1463547Y180527D03*
X1458864Y180572D03*
X1455016Y168697D03*
X1458864Y185165D03*
X1463502Y185121D03*
X1458113Y206767D03*
X1463113D03*
X1460613D03*
X1451782Y213132D03*
X1463243Y221708D03*
X1460743D03*
X1458243D03*
X1457658Y224421D03*
X1459358Y231021D03*
Y228221D03*
X1451782Y215632D03*
X1459909Y236189D03*
X1464909D03*
X1462409D03*
X1459850Y248765D03*
X1464850D03*
X1462350D03*
X1457056Y279208D03*
X1461160Y281307D03*
X1460047Y270695D03*
Y268195D03*
X1462547Y270695D03*
Y268195D03*
X1465347Y270695D03*
Y268195D03*
X1465650Y293645D03*
X1455079Y290755D03*
X1451079D03*
X1465650Y288345D03*
Y290845D03*
X1463150Y288345D03*
Y290845D03*
Y293645D03*
X1451215Y323193D03*
X1451330Y327588D03*
X1451272Y340971D03*
X1451344Y336620D03*
X1451300Y332225D03*
X1451387Y345609D03*
X1451186Y350447D03*
X1458982Y356861D03*
X1455979Y391756D03*
X1458212Y403374D03*
X1454944Y605443D03*
X1453000Y633450D03*
Y636250D03*
Y639050D03*
X1460816Y727964D03*
X1453775Y813032D03*
X1456966Y998507D03*
X1465846Y1023900D03*
X1452000Y1644980D03*
X1472146Y55513D03*
X1468371Y68581D03*
X1468384Y80581D03*
X1471093Y117261D03*
X1467270Y192421D03*
X1467593Y221642D03*
X1480589Y248371D03*
X1471507Y265897D03*
X1469007D03*
X1473364Y410724D03*
X1472403Y417338D03*
X1469293Y428815D03*
X1479500Y706500D03*
X1469957Y706957D03*
X1474000Y707000D03*
X1479962Y727500D03*
X1471415Y748629D03*
X1479500Y750500D03*
X1469957Y750957D03*
X1474425Y760075D03*
X1474000Y753093D03*
X1473634Y864337D03*
X1474060Y877196D03*
X1473468Y874267D03*
X1482387Y872940D03*
X1473433Y891043D03*
X1479441Y961941D03*
X1476500Y974000D03*
X1475096Y980330D03*
X1471096D03*
X1475062Y1008300D03*
Y1002453D03*
X1476230Y1030672D03*
X1473230D03*
X1474384Y1109564D03*
X1480231D03*
X1474384Y1122164D03*
X1480231D03*
X1474384Y1134764D03*
X1480231D03*
X1474384Y1147364D03*
X1480231D03*
X1474384Y1172564D03*
X1480231D03*
X1474384Y1159964D03*
X1480231D03*
X1474384Y1185164D03*
X1476094Y1465913D03*
Y1461182D03*
Y1456451D03*
Y1471805D03*
Y1481267D03*
Y1476536D03*
Y1491890D03*
Y1487159D03*
Y1496621D03*
Y1502514D03*
Y1511976D03*
Y1507245D03*
Y1563544D03*
Y1558813D03*
Y1568275D03*
Y1578898D03*
Y1574167D03*
Y1583629D03*
Y1594253D03*
Y1589522D03*
Y1609607D03*
Y1598984D03*
Y1604876D03*
Y1614338D03*
X1472000Y1644980D03*
X1484594Y3000D03*
X1500210Y97667D03*
X1490593Y116594D03*
Y119594D03*
X1484796Y320359D03*
X1484968Y325025D03*
X1484876Y329377D03*
X1488255Y342921D03*
X1484682Y338394D03*
X1497760Y336543D03*
X1487926Y347387D03*
X1486360Y358700D03*
Y354200D03*
X1483813Y368516D03*
X1496473Y769000D03*
X1496500Y792000D03*
X1486957Y792457D03*
X1495170Y796670D03*
X1491425Y801575D03*
X1496845Y813000D03*
X1491425Y845575D03*
X1496500Y836000D03*
X1486957Y836457D03*
X1492625Y837324D03*
X1489805Y866386D03*
X1497488Y873839D03*
X1498084Y894825D03*
X1482566Y882154D03*
X1498446Y912370D03*
X1496383Y898023D03*
X1497208Y909740D03*
X1496500Y919000D03*
X1496000Y922000D03*
X1496425Y943075D03*
X1496072Y950044D03*
X1486030Y1016827D03*
X1491877D03*
X1486030Y1029427D03*
X1491877D03*
X1484755Y1465513D03*
Y1460782D03*
X1493417Y1465913D03*
Y1456451D03*
Y1461182D03*
Y1471805D03*
Y1476536D03*
Y1481267D03*
X1484755Y1476136D03*
Y1470244D03*
Y1480867D03*
Y1496221D03*
X1493417Y1487159D03*
Y1491890D03*
Y1496621D03*
X1484755Y1491490D03*
Y1485598D03*
Y1506845D03*
Y1500952D03*
Y1511576D03*
X1493417Y1507245D03*
Y1502514D03*
Y1511976D03*
X1484755Y1516307D03*
Y1563144D03*
X1493417Y1558813D03*
Y1563544D03*
Y1578898D03*
X1484755Y1567875D03*
Y1578498D03*
Y1572606D03*
X1493417Y1568275D03*
Y1574167D03*
X1484755Y1583229D03*
Y1593853D03*
Y1587960D03*
X1493417Y1583629D03*
Y1589522D03*
Y1594253D03*
X1484755Y1609207D03*
Y1598584D03*
Y1603315D03*
X1493417Y1609607D03*
Y1604876D03*
Y1598984D03*
X1484755Y1613938D03*
Y1618669D03*
X1493417Y1614338D03*
X1492000Y1644980D03*
X1500578Y4469D03*
X1501939Y24773D03*
Y44773D03*
X1509260Y53597D03*
X1506689Y195176D03*
X1506207Y199248D03*
X1501689Y195176D03*
X1503207Y199248D03*
X1499189Y195176D03*
X1504189D03*
X1506207Y202048D03*
X1503207Y201748D03*
X1499270Y210509D03*
X1501043Y206806D03*
X1501770Y210509D03*
X1503543Y206806D03*
X1505823Y238714D03*
X1500480Y295727D03*
X1501807Y323766D03*
X1511950Y401513D03*
Y398113D03*
X1509550Y412287D03*
Y415687D03*
Y426460D03*
Y440633D03*
Y429860D03*
Y444033D03*
X1516636Y458711D03*
X1509550Y472787D03*
Y469387D03*
Y483560D03*
Y486960D03*
Y516921D03*
Y513521D03*
Y527694D03*
Y531094D03*
X1507034Y888133D03*
X1507358Y909740D03*
X1507305Y912262D03*
X1510280Y899732D03*
X1514354Y938811D03*
X1510500Y931500D03*
X1513955Y950396D03*
X1511000Y970500D03*
X1502078Y1465513D03*
Y1460782D03*
X1510740Y1465913D03*
Y1456451D03*
Y1461182D03*
X1502078Y1470244D03*
Y1480867D03*
X1510740Y1471805D03*
Y1476536D03*
Y1481267D03*
X1502078Y1476136D03*
Y1491490D03*
Y1485598D03*
Y1496221D03*
X1510740Y1487159D03*
Y1491890D03*
Y1496621D03*
Y1507245D03*
Y1502514D03*
Y1511976D03*
X1502078Y1506845D03*
Y1500952D03*
Y1511576D03*
Y1516307D03*
X1510740Y1563544D03*
X1502078Y1563144D03*
X1510740Y1558813D03*
Y1578898D03*
X1502078Y1567875D03*
Y1578498D03*
Y1572606D03*
X1510740Y1568275D03*
Y1574167D03*
X1502078Y1583229D03*
Y1593853D03*
Y1587960D03*
X1510740Y1583629D03*
Y1589522D03*
Y1594253D03*
X1502078Y1609207D03*
Y1598584D03*
Y1603315D03*
X1510740Y1609607D03*
Y1604876D03*
Y1598984D03*
X1502078Y1613938D03*
Y1618669D03*
X1510740Y1614338D03*
X1512000Y1644980D03*
X1529260Y53597D03*
X1529720Y116496D03*
Y109410D03*
Y130670D03*
Y123583D03*
X1521087Y130670D03*
X1526311Y137756D03*
X1521082D03*
X1528355Y210478D03*
Y215478D03*
Y212978D03*
Y207978D03*
X1515779Y351594D03*
X1519321Y378600D03*
X1519952Y391001D03*
Y394401D03*
Y408574D03*
Y405174D03*
Y422747D03*
Y419347D03*
Y436921D03*
Y433521D03*
X1519436Y458711D03*
X1519952Y479899D03*
Y476499D03*
Y490673D03*
Y494073D03*
Y520633D03*
Y524033D03*
Y534806D03*
Y538206D03*
X1528635Y555234D03*
X1519063Y876339D03*
X1517344Y896999D03*
X1515743Y888133D03*
X1517344Y903179D03*
X1517153Y908367D03*
X1516283Y912240D03*
X1519116D03*
X1523053Y912262D03*
X1523000Y923740D03*
X1526611Y921442D03*
X1525740Y928740D03*
X1527876Y939439D03*
X1528087Y936394D03*
X1524500Y949500D03*
X1525022Y957340D03*
X1530174Y956986D03*
X1530767Y972981D03*
X1522904Y1021256D03*
X1519401Y1465513D03*
Y1460782D03*
X1528062Y1465913D03*
Y1456451D03*
Y1461182D03*
Y1481267D03*
X1519401Y1476136D03*
Y1470244D03*
Y1480867D03*
X1528062Y1471805D03*
Y1476536D03*
X1519401Y1491490D03*
Y1485598D03*
Y1496221D03*
X1528062Y1487159D03*
Y1491890D03*
Y1496621D03*
X1519401Y1506845D03*
Y1500952D03*
Y1511576D03*
X1528062Y1507245D03*
Y1502514D03*
Y1511976D03*
X1519401Y1516307D03*
Y1563144D03*
X1528062Y1558813D03*
Y1563544D03*
Y1578898D03*
X1519401Y1567875D03*
Y1578498D03*
Y1572606D03*
X1528062Y1568275D03*
Y1574167D03*
X1519401Y1587960D03*
X1528062Y1583629D03*
Y1589522D03*
Y1594253D03*
X1519401Y1583229D03*
Y1593853D03*
Y1609207D03*
Y1598584D03*
Y1603315D03*
X1528062Y1609607D03*
Y1604876D03*
Y1598984D03*
X1519401Y1613938D03*
Y1618669D03*
X1528062Y1614338D03*
X1547367Y44773D03*
X1546732Y98551D03*
X1547131Y110445D03*
Y115401D03*
X1537720Y116496D03*
Y109410D03*
X1547131Y129574D03*
X1537720Y130670D03*
Y123583D03*
X1547131Y124618D03*
X1537720Y137756D03*
X1545044Y147540D03*
Y151540D03*
X1546197Y181426D03*
X1546405Y184221D03*
X1538811Y213213D03*
Y210713D03*
X1542883Y211695D03*
X1545383D03*
X1542883Y208695D03*
X1545683D03*
X1538811Y208213D03*
Y215713D03*
X1534184Y264180D03*
X1531684D03*
X1545878Y270026D03*
X1543378D03*
X1540578D03*
X1543378Y267526D03*
X1540578D03*
X1545878D03*
X1531901Y293796D03*
X1539915Y288190D03*
X1542415Y285690D03*
X1539915D03*
X1542415Y288190D03*
X1545215D03*
Y285690D03*
X1534401Y293796D03*
X1541534Y322850D03*
X1541283Y354553D03*
X1545385Y1461183D03*
X1536724Y1465513D03*
Y1460782D03*
X1545385Y1465914D03*
Y1456452D03*
X1536724Y1476136D03*
Y1470244D03*
Y1480867D03*
X1545385Y1476537D03*
Y1471806D03*
Y1481268D03*
X1536724Y1491490D03*
Y1485598D03*
Y1496221D03*
X1545385Y1491891D03*
Y1487160D03*
Y1496622D03*
X1536724Y1506845D03*
Y1500952D03*
Y1511576D03*
X1545385Y1507246D03*
Y1502515D03*
Y1511977D03*
X1536724Y1516307D03*
Y1563144D03*
Y1567875D03*
Y1578498D03*
Y1572606D03*
Y1583229D03*
Y1593853D03*
Y1587960D03*
Y1609207D03*
Y1598584D03*
Y1603315D03*
Y1613938D03*
Y1618669D03*
X1532000Y1644980D03*
X1562525Y117557D03*
X1557533D03*
X1552123Y115401D03*
Y110445D03*
X1557217Y106186D03*
X1550282Y103783D03*
X1562525Y122513D03*
X1552123Y129574D03*
Y124618D03*
X1557533Y131731D03*
Y122513D03*
X1562525Y131731D03*
X1560624Y146461D03*
X1557533Y136687D03*
X1562525D03*
X1559526Y152367D03*
X1561226Y180572D03*
X1552203Y181009D03*
X1549408Y181366D03*
X1557378Y168697D03*
X1561226Y185165D03*
X1549022Y184012D03*
X1560475Y206767D03*
X1562975D03*
X1554144Y213132D03*
X1550441Y211359D03*
Y213859D03*
X1560605Y221708D03*
X1560020Y224421D03*
X1563105Y221708D03*
X1561720Y231021D03*
Y228221D03*
X1554144Y215632D03*
X1562271Y236189D03*
X1562212Y248765D03*
X1559418Y279208D03*
X1563522Y281307D03*
X1562409Y268195D03*
Y270695D03*
X1549441Y290755D03*
X1553441D03*
X1557441D03*
X1547972Y304906D03*
X1556151Y318596D03*
X1556294Y327814D03*
X1556437Y332022D03*
X1556380Y336917D03*
X1556498Y340958D03*
X1556353Y345636D03*
X1554403Y352363D03*
X1556429Y389154D03*
X1563248D03*
X1548629D03*
Y403327D03*
Y410413D03*
X1556429Y396240D03*
X1557708Y404911D03*
X1561778Y396240D03*
X1548629D03*
X1556662Y412571D03*
X1557849Y426299D03*
X1548629Y417500D03*
Y424587D03*
Y438760D03*
Y431673D03*
X1558160Y445847D03*
X1548629D03*
X1556429Y467539D03*
X1548629D03*
X1556429Y474626D03*
X1548629D03*
Y488799D03*
X1556690Y480828D03*
X1548629Y481713D03*
Y495886D03*
X1558640Y498834D03*
X1548629Y511673D03*
Y518760D03*
X1562089Y516841D03*
X1556429Y518760D03*
Y511673D03*
X1548629Y540020D03*
Y525847D03*
Y532933D03*
X1556429Y525847D03*
X1548629Y547106D03*
X1556914Y552872D03*
X1557036Y550123D03*
X1556359Y562443D03*
X1558668Y572334D03*
X1558127Y560675D03*
X1556900Y574102D03*
X1547910Y602197D03*
X1562385Y598400D03*
Y602400D03*
Y594400D03*
X1548374Y595108D03*
X1562385Y614400D03*
Y606400D03*
X1561535Y653161D03*
X1561552Y665455D03*
X1565132Y677843D03*
X1547813Y906581D03*
X1551099Y959096D03*
X1552000Y1644980D03*
X1571895Y58013D03*
X1570733Y68581D03*
X1570746Y80581D03*
X1573455Y117261D03*
X1565909Y180527D03*
X1569632Y192421D03*
X1565864Y185121D03*
X1565475Y206767D03*
X1565605Y221708D03*
X1569955Y221642D03*
X1564771Y236189D03*
X1567271D03*
X1564712Y248765D03*
X1567212D03*
X1567709Y270695D03*
X1573869Y265897D03*
X1571369D03*
X1567709Y268195D03*
X1564909Y270695D03*
Y268195D03*
X1565512Y288345D03*
X1568012Y293645D03*
Y290845D03*
Y288345D03*
X1565512Y293645D03*
Y290845D03*
X1574845Y338843D03*
X1571625Y333549D03*
X1574540Y389154D03*
X1575935Y382109D03*
X1579340Y396240D03*
Y403327D03*
Y410413D03*
X1574540Y396240D03*
Y403327D03*
Y410413D03*
X1566555Y414823D03*
X1565863Y422864D03*
X1579340Y417500D03*
Y424586D03*
X1574540Y417500D03*
Y424586D03*
X1565933Y429832D03*
X1565538Y436447D03*
X1574540Y438760D03*
X1579340Y431673D03*
Y438760D03*
X1574540Y431673D03*
X1567573Y447953D03*
X1579340Y445847D03*
X1574540D03*
X1566740Y467539D03*
X1574540D03*
X1565482Y472772D03*
X1574540Y474626D03*
X1579340D03*
Y488799D03*
X1574540D03*
X1566216Y487711D03*
X1566329Y479104D03*
X1574540Y481713D03*
X1579340Y481712D03*
Y495886D03*
X1574540D03*
X1566740D03*
X1579340Y518760D03*
X1574540Y511673D03*
Y518760D03*
X1565050Y511673D03*
X1574540Y540020D03*
X1579340D03*
Y532933D03*
Y525846D03*
X1574540Y525847D03*
Y532933D03*
Y547106D03*
Y554193D03*
X1575000Y565414D03*
Y567914D03*
Y570414D03*
X1575934Y561420D03*
Y558917D03*
X1575000Y572914D03*
Y575414D03*
X1571755Y577937D03*
X1574540Y602205D03*
Y595118D03*
X1579753Y599100D03*
X1578679Y613047D03*
X1578114Y607563D03*
X1574222Y629872D03*
X1576297Y627600D03*
X1577077Y631712D03*
X1569926Y668885D03*
X1575950Y662981D03*
X1569434Y677111D03*
X1570331Y691851D03*
X1575942Y705043D03*
X1572000Y1644980D03*
X1592187Y-69306D03*
Y-72706D03*
X1582187Y-33786D03*
Y-30386D03*
X1592955Y116594D03*
Y119594D03*
X1582951Y248371D03*
X1586640Y389153D03*
X1581840D03*
Y403326D03*
Y410413D03*
X1586640D03*
X1581840Y396240D03*
X1586640D03*
Y403326D03*
Y417499D03*
X1581840D03*
Y424586D03*
X1586640D03*
X1581840Y438760D03*
X1586640D03*
Y431673D03*
X1581840D03*
X1592635Y455911D03*
X1586640Y467539D03*
X1581840D03*
Y474626D03*
X1586640D03*
X1581840Y488799D03*
X1586640D03*
X1581840Y481712D03*
X1586640D03*
X1581840Y518760D03*
Y511673D03*
X1586640D03*
Y518760D03*
Y525846D03*
Y532933D03*
X1581840D03*
Y525846D03*
X1595185Y543925D03*
X1595760Y555000D03*
X1583720Y560500D03*
X1590748Y1523377D03*
X1604301Y44773D03*
X1611622Y53597D03*
X1602572Y97667D03*
X1604051Y195176D03*
X1605569Y199248D03*
X1601551Y195176D03*
X1606551D03*
X1609051D03*
X1608569Y199248D03*
X1603405Y206806D03*
X1605905D03*
X1601632Y210509D03*
X1604132D03*
X1608569Y202048D03*
X1605569Y201748D03*
X1608185Y238714D03*
X1597006Y290417D03*
X1599527Y396718D03*
X1596760Y530000D03*
X1596260Y540500D03*
X1614338Y636842D03*
X1611316Y685800D03*
X1597039Y1475100D03*
X1599726Y1474990D03*
X1601500Y1514500D03*
X1613790Y1531334D03*
X1609348Y1527334D03*
X1613790Y1523334D03*
X1604000Y1519000D03*
X1609348Y1535334D03*
X1598574Y1543373D03*
X1623449Y130670D03*
X1623444Y137756D03*
X1625772Y438323D03*
X1625938Y445873D03*
X1620385Y465874D03*
X1625565Y479666D03*
Y486752D03*
Y493839D03*
Y523800D03*
Y516713D03*
Y537973D03*
Y530886D03*
X1616622Y546712D03*
X1625565Y566752D03*
Y588013D03*
Y573839D03*
Y580926D03*
Y602186D03*
Y595099D03*
Y609272D03*
Y616359D03*
X1614538Y618288D03*
X1620244Y638125D03*
X1617843Y665140D03*
X1621362Y656321D03*
X1617362D03*
X1613110Y678462D03*
X1624148Y708258D03*
X1627455Y759489D03*
X1619612Y783152D03*
X1620359Y774830D03*
X1619569Y796035D03*
X1620755Y787530D03*
X1613235Y808466D03*
X1620479Y815730D03*
X1620072Y801630D03*
X1616255Y824405D03*
X1619859Y839519D03*
X1631622Y53597D03*
X1632082Y116496D03*
Y109410D03*
X1640082Y116496D03*
Y109410D03*
X1632082Y130670D03*
Y123583D03*
X1640082Y130670D03*
Y123583D03*
X1628673Y137756D03*
X1640082D03*
X1641173Y213213D03*
Y210713D03*
Y208213D03*
X1630717Y210478D03*
Y215478D03*
Y212978D03*
Y207978D03*
X1641173Y215713D03*
X1634046Y264180D03*
X1636546D03*
X1642940Y267526D03*
Y270026D03*
X1644777Y288190D03*
X1642277Y285690D03*
X1644777D03*
X1642277Y288190D03*
X1636763Y293796D03*
X1634263D03*
X1630365Y486752D03*
X1632865D03*
X1630365Y493839D03*
X1637665D03*
X1632865Y509626D03*
Y516713D03*
X1630365D03*
Y523800D03*
X1632865D03*
X1637665Y523799D03*
Y516713D03*
Y509626D03*
X1630365Y530886D03*
X1637665D03*
X1632865D03*
X1637665Y537973D03*
X1630365D03*
X1637665Y559665D03*
Y566752D03*
X1630365D03*
X1632865D03*
Y559665D03*
Y573839D03*
X1630365Y580926D03*
X1632865D03*
X1637665D03*
Y588012D03*
X1630365Y588013D03*
X1632865Y588012D03*
X1637665Y573839D03*
X1630365D03*
X1632865Y602185D03*
X1630365Y602186D03*
X1637665Y602185D03*
Y595099D03*
X1632865D03*
X1630365D03*
Y616359D03*
X1632865Y609272D03*
X1630365D03*
X1637665Y616358D03*
Y609272D03*
X1637526Y699930D03*
X1637472Y717830D03*
X1631031Y732430D03*
X1628813Y727045D03*
X1631187Y750630D03*
X1629969Y740826D03*
X1644304Y891353D03*
X1640581Y1551907D03*
X1650417Y5374D03*
X1649730Y24773D03*
Y44773D03*
X1649094Y98551D03*
X1659895Y117557D03*
X1654485Y110445D03*
Y115401D03*
X1649493Y110445D03*
Y115401D03*
X1652644Y103783D03*
X1659579Y106186D03*
X1659895Y122513D03*
Y131731D03*
X1654485Y124618D03*
Y129574D03*
X1649493Y124618D03*
Y129574D03*
X1659895Y136687D03*
X1647406Y147540D03*
Y151540D03*
X1654565Y181009D03*
X1648559Y181426D03*
X1651770Y181366D03*
X1659740Y168697D03*
X1651384Y184012D03*
X1648767Y184221D03*
X1647745Y211695D03*
X1645245Y208695D03*
X1648045D03*
X1656506Y213132D03*
X1652803Y211359D03*
Y213859D03*
X1645245Y211695D03*
X1656506Y215632D03*
X1648240Y267526D03*
X1645740D03*
Y270026D03*
X1648240D03*
X1647577Y285690D03*
Y288190D03*
X1655803Y290755D03*
X1651803D03*
X1659803D03*
X1646209Y442606D03*
X1645826Y446606D03*
X1645423Y495088D03*
X1655776Y493839D03*
X1646158Y514608D03*
X1646080Y522134D03*
X1645465Y509626D03*
X1655776D03*
Y516713D03*
X1646562Y535677D03*
X1646723Y529136D03*
X1652236Y537973D03*
X1654716Y525483D03*
X1654637Y532756D03*
X1645465Y559665D03*
X1645846Y565574D03*
X1655776Y559665D03*
Y566752D03*
X1645493Y574338D03*
X1655626Y579978D03*
X1655776Y573839D03*
X1645592Y616358D03*
X1655840Y608117D03*
X1654572Y771702D03*
X1645128Y929263D03*
X1645342Y962120D03*
X1657091Y990823D03*
X1649571Y983857D03*
X1652000Y1644980D03*
X1669319Y3001D03*
X1676870Y55513D03*
X1673095Y68581D03*
X1673108Y80581D03*
X1675817Y117261D03*
X1664887Y117557D03*
Y122513D03*
Y131731D03*
X1662986Y146461D03*
X1664887Y136687D03*
X1661888Y152367D03*
X1663588Y180572D03*
X1668271Y180527D03*
X1671994Y192421D03*
X1663588Y185165D03*
X1668226Y185121D03*
X1662837Y206767D03*
X1667837D03*
X1665337D03*
X1667967Y221708D03*
X1665467D03*
X1664082Y231021D03*
Y228221D03*
X1672317Y221642D03*
X1662967Y221708D03*
X1662382Y224421D03*
X1669633Y236189D03*
X1667133D03*
X1664633D03*
X1667074Y248765D03*
X1664574D03*
X1669574D03*
X1661780Y279208D03*
X1665884Y281307D03*
X1676231Y265897D03*
X1673731D03*
X1670071Y268195D03*
Y270695D03*
X1667271Y268195D03*
X1664771D03*
Y270695D03*
X1667271D03*
X1670374Y290845D03*
Y288345D03*
X1667874Y290845D03*
Y288345D03*
X1670374Y293645D03*
X1667874D03*
X1664567Y451677D03*
X1667067D03*
X1664567Y454177D03*
X1667067D03*
X1663576Y493839D03*
Y523799D03*
Y516713D03*
Y509626D03*
Y537973D03*
Y530886D03*
Y559665D03*
Y566752D03*
Y580925D03*
Y588012D03*
Y573839D03*
Y602185D03*
Y595099D03*
Y616358D03*
Y609272D03*
X1672000Y1644980D03*
X1689319Y3001D03*
X1685313Y248371D03*
X1686115Y311740D03*
X1680518Y377912D03*
Y381912D03*
Y397912D03*
X1692253Y467306D03*
Y470706D03*
Y484879D03*
Y481479D03*
Y511439D03*
Y514839D03*
Y529013D03*
Y525613D03*
Y561479D03*
Y564879D03*
Y575652D03*
Y579052D03*
Y593225D03*
Y603999D03*
Y589825D03*
Y607399D03*
X1692000Y1644980D03*
X1705303Y4470D03*
X1706664Y24774D03*
Y44774D03*
X1704934Y97667D03*
X1695317Y116594D03*
Y119594D03*
X1708913Y195176D03*
X1710931Y199248D03*
X1706413Y195176D03*
X1703913D03*
X1707931Y199248D03*
Y201748D03*
X1706494Y210509D03*
X1703994D03*
X1705767Y206806D03*
X1708267D03*
X1701495Y289735D03*
X1698292Y303962D03*
X1702655Y474418D03*
Y477818D03*
Y488591D03*
Y491991D03*
Y521952D03*
Y518552D03*
Y536125D03*
Y532725D03*
Y571991D03*
Y568591D03*
Y586165D03*
Y582765D03*
Y600338D03*
Y596938D03*
Y611111D03*
Y614511D03*
X1713985Y53598D03*
X1725811Y130670D03*
X1725806Y137756D03*
X1711413Y195176D03*
X1710931Y202048D03*
X1710547Y238714D03*
X1724930Y473571D03*
Y476071D03*
Y478571D03*
Y481071D03*
X1712000Y1644980D03*
X1736405Y-69278D03*
Y-72678D03*
X1733985Y53598D03*
X1734444Y116496D03*
Y109410D03*
Y130670D03*
Y123583D03*
X1730647Y137756D03*
X1733079Y207978D03*
Y210478D03*
Y215478D03*
Y212978D03*
X1736408Y264180D03*
X1738908D03*
X1739125Y293796D03*
X1736625D03*
X1733014Y462060D03*
X1730014D03*
X1734952Y479217D03*
X1737646Y477213D03*
Y479713D03*
X1729002Y477053D03*
X1731502D03*
X1734952Y476717D03*
X1733147Y493758D03*
Y496258D03*
X1730675Y1132361D03*
X1726963Y1132319D03*
X1739508Y1137129D03*
X1739917Y1150087D03*
X1732000Y1644980D03*
X1752778Y5374D03*
X1752091Y24773D03*
Y44773D03*
X1751456Y98551D03*
X1742444Y116496D03*
Y109410D03*
X1751855Y110445D03*
Y115401D03*
X1756847D03*
Y110445D03*
X1755006Y103783D03*
X1742444Y130670D03*
Y123583D03*
X1751855Y129574D03*
Y124618D03*
X1756847D03*
Y129574D03*
X1742444Y137756D03*
X1756927Y181009D03*
X1750921Y181426D03*
X1754132Y181366D03*
X1751129Y184221D03*
X1753746Y184012D03*
X1747607Y211695D03*
X1755165Y211359D03*
Y213859D03*
X1750107Y211695D03*
X1747607Y208695D03*
X1750407D03*
X1743535Y208213D03*
Y213213D03*
Y210713D03*
Y215713D03*
X1750602Y267526D03*
X1745302D03*
X1748102D03*
X1745302Y270026D03*
X1748102D03*
X1750602D03*
X1749939Y288190D03*
X1747139D03*
X1744639D03*
X1749939Y285690D03*
X1744639D03*
X1747139D03*
X1758165Y290755D03*
X1754165D03*
X1753474Y542699D03*
X1757402Y825111D03*
Y820155D03*
X1744937Y912517D03*
X1747937D03*
X1750751Y910785D03*
X1748081Y984379D03*
X1756192Y996132D03*
X1743224Y1119055D03*
X1758583Y1581027D03*
X1750685Y1618504D03*
X1756422Y1640303D03*
X1752000Y1644980D03*
X1765559Y3001D03*
X1767249Y117557D03*
X1762257D03*
X1761941Y106186D03*
X1762257Y122513D03*
Y131731D03*
X1767249Y122513D03*
Y131731D03*
X1762257Y136687D03*
X1767249D03*
X1765950Y180572D03*
X1770633Y180527D03*
X1762102Y168697D03*
X1774356Y192421D03*
X1770588Y185121D03*
X1765950Y185165D03*
X1765199Y206767D03*
X1770199D03*
X1767699D03*
X1758868Y213132D03*
X1765329Y221708D03*
X1770329D03*
X1767829D03*
X1764744Y224421D03*
X1766444Y231021D03*
Y228221D03*
X1774679Y221642D03*
X1758868Y215632D03*
X1771995Y236189D03*
X1769495D03*
X1766995D03*
X1771936Y248765D03*
X1769436D03*
X1766936D03*
X1764142Y279208D03*
X1768246Y281307D03*
X1767133Y270695D03*
X1769633D03*
X1772433Y268195D03*
Y270695D03*
X1769633Y268195D03*
X1767133D03*
X1772736Y293645D03*
X1770236D03*
Y290845D03*
Y288345D03*
X1772736Y290845D03*
Y288345D03*
X1762165Y290755D03*
X1764903Y470382D03*
X1768575Y475560D03*
X1761953Y706827D03*
X1772768Y818696D03*
X1761953Y865160D03*
X1773600Y888100D03*
X1773614Y895275D03*
X1773600Y902800D03*
X1770680Y926322D03*
X1763818Y926241D03*
X1772599Y993053D03*
X1762898Y992883D03*
X1764744Y1101930D03*
Y1097879D03*
X1766899Y1121122D03*
X1769499D03*
X1772099D03*
X1774799D03*
X1766999Y1130822D03*
X1772199D03*
X1769599D03*
X1774339Y1437975D03*
X1774216Y1470165D03*
X1765294Y1575434D03*
X1759092Y1588137D03*
X1767142Y1588219D03*
X1764422Y1640303D03*
X1772000Y1644980D03*
X1779232Y55513D03*
X1775457Y68581D03*
X1775470Y80581D03*
X1778179Y117261D03*
X1778593Y265897D03*
X1776093D03*
X1784602Y564092D03*
X1778801Y836469D03*
X1782600Y874500D03*
X1788400Y888100D03*
X1781000Y888087D03*
X1788396Y895066D03*
X1788300Y902800D03*
X1780665Y902796D03*
X1786256Y927626D03*
X1784306Y924601D03*
X1786256Y930626D03*
X1781263Y964660D03*
X1784763D03*
X1774899Y1130822D03*
Y1139822D03*
X1777399D03*
Y1147822D03*
X1774899D03*
X1779581Y1222200D03*
Y1219400D03*
Y1216600D03*
Y1213800D03*
X1782581Y1222200D03*
Y1219400D03*
Y1216600D03*
Y1213800D03*
X1780397Y1237469D03*
Y1230569D03*
Y1228069D03*
X1779581Y1225000D03*
X1782581D03*
X1785961Y1224892D03*
X1780397Y1234969D03*
Y1241869D03*
Y1244369D03*
Y1248769D03*
Y1251269D03*
X1791099Y1260421D03*
X1779868Y1446668D03*
X1786564Y1478858D03*
X1777131Y1604357D03*
X1776422Y1640303D03*
X1801761Y-33888D03*
Y-30488D03*
X1791570Y74535D03*
X1804993Y297591D03*
X1804984Y433975D03*
X1803570Y436164D03*
X1793149Y662810D03*
X1798705Y718793D03*
X1791302Y829031D03*
X1794163Y968760D03*
X1797963D03*
X1792263Y962960D03*
X1798163Y982360D03*
X1793563D03*
X1805863Y980760D03*
X1805013Y1091877D03*
X1792847Y1099210D03*
X1799012Y1095893D03*
X1805013Y1096470D03*
X1792863Y1103246D03*
X1796607Y1200108D03*
X1801285Y1213373D03*
X1801147Y1208555D03*
X1802844Y1227695D03*
X1793976Y1440762D03*
X1807270Y1468535D03*
X1793879Y1472952D03*
X1792000Y1644980D03*
X1822983Y346053D03*
Y366053D03*
Y386053D03*
Y406053D03*
Y426053D03*
Y446053D03*
X1817439Y447101D03*
X1822983Y466053D03*
Y486053D03*
Y506053D03*
Y526053D03*
Y546053D03*
Y566053D03*
Y586053D03*
Y606053D03*
Y626053D03*
Y646053D03*
Y666053D03*
Y686053D03*
Y706053D03*
Y726053D03*
Y746053D03*
Y766053D03*
Y786053D03*
Y806053D03*
Y826053D03*
Y846053D03*
Y866053D03*
Y886053D03*
Y906053D03*
Y926053D03*
Y946053D03*
X1816322Y977215D03*
X1823074Y992833D03*
X1812296Y1075688D03*
X1809696Y1091832D03*
X1809651Y1096426D03*
X1823028Y1124289D03*
X1817728D03*
X1815128D03*
X1820328D03*
X1822928Y1114589D03*
X1820228D03*
X1815028D03*
X1817628D03*
X1816385Y1136912D03*
X1813885D03*
X1815865Y1133356D03*
X1813885Y1144912D03*
X1816385D03*
X1809897Y1237285D03*
Y1230385D03*
Y1232885D03*
Y1239785D03*
Y1244185D03*
Y1246685D03*
X1810018Y1295944D03*
X1812818D03*
X1815618Y1298744D03*
Y1295944D03*
X1812818Y1298744D03*
X1810018D03*
X1807393Y1436345D03*
X1812000Y1644980D03*
X1825559Y3001D03*
X1836543Y4470D03*
X1837904Y24774D03*
Y44774D03*
Y64774D03*
Y84774D03*
Y104774D03*
Y124774D03*
Y144774D03*
Y164774D03*
Y184774D03*
Y204774D03*
Y224774D03*
Y244774D03*
Y264774D03*
Y284774D03*
Y304774D03*
X1837728Y324733D03*
X1830094Y333210D03*
X1830472Y960970D03*
X1837937Y973244D03*
X1831511Y978888D03*
X1837937Y993244D03*
X1831914Y992877D03*
X1837937Y1013244D03*
Y1033244D03*
Y1053244D03*
Y1073244D03*
X1824706Y1081145D03*
Y1089145D03*
X1824733Y1102830D03*
X1837937Y1093244D03*
X1825832Y1097589D03*
X1837937Y1113244D03*
Y1133244D03*
Y1153244D03*
Y1173244D03*
Y1193244D03*
Y1213244D03*
Y1253244D03*
Y1273244D03*
Y1293244D03*
Y1313244D03*
Y1333244D03*
Y1353244D03*
Y1373244D03*
Y1393244D03*
Y1433244D03*
Y1453244D03*
Y1473244D03*
Y1493244D03*
Y1513244D03*
Y1533244D03*
Y1553244D03*
Y1573244D03*
X1837933Y1636171D03*
X1832000Y1644980D03*
G54D11*
X13780Y1226024D03*
X390354Y1141024D03*
X536418Y1086654D03*
X854291Y1225118D03*
X993504Y1170748D03*
X1304528Y1141024D03*
X1450591Y1086654D03*
X1827165Y1235630D03*
G54D20*
X190325Y368760D03*
X279360Y636752D03*
X647411Y368760D03*
X736446Y636752D03*
X1104498Y368760D03*
X1193533Y636752D03*
X1561585Y368760D03*
X1650620Y636752D03*
G54D30*
G01X70947Y1201565D02*
X72068Y1202686D01*
X86892D01*
X98974Y1190604D01*
X114252D01*
X115061Y1189795D01*
Y1167118D01*
X121464Y1160715D01*
X137837D01*
X140047Y1162925D01*
X230501D01*
X234000Y1166424D01*
Y1188639D01*
X234632Y1189271D01*
X236712D01*
G01X70947Y1205835D02*
X72296Y1204486D01*
X87638D01*
X99720Y1192404D01*
X114998D01*
X116861Y1190541D01*
Y1167864D01*
X122210Y1162515D01*
X137091D01*
X139301Y1164725D01*
X229755D01*
X232332Y1167302D01*
Y1189331D01*
X234501Y1191500D01*
X235201D01*
X236712Y1193011D01*
G01X461285Y1193471D02*
X460035Y1194721D01*
X398186D01*
X396356Y1192891D01*
Y1168886D01*
X374158Y1146688D01*
Y1129951D01*
X377359Y1122224D01*
X396907Y1102676D01*
X409400D01*
X423112Y1088964D01*
Y1056803D01*
X428452Y1051463D01*
X477683D01*
X481885Y1047261D01*
Y1039698D01*
X482753Y1038830D01*
X483139D01*
X484583Y1038813D01*
X485678Y1039880D01*
G01X461285Y1197471D02*
X460035Y1196221D01*
X397564D01*
X394856Y1193513D01*
Y1169508D01*
X372658Y1147310D01*
Y1129652D01*
X376087Y1121374D01*
X396285Y1101176D01*
X408778D01*
X421612Y1088342D01*
Y1056181D01*
X427830Y1049963D01*
X477061D01*
X480385Y1046639D01*
Y1039076D01*
X482131Y1037330D01*
X483129D01*
X484502Y1037313D01*
X485633Y1036155D01*
G01X459700Y1032266D02*
X460675Y1033241D01*
X464546D01*
X466187Y1031600D01*
Y1028095D01*
X468636Y1025646D01*
X485253D01*
X499237Y1039630D01*
X516711D01*
X554818Y1077737D01*
Y1094500D01*
X537964Y1111354D01*
Y1190638D01*
X532381Y1196221D01*
X467035D01*
X465785Y1197471D01*
G01X459700Y1035716D02*
X460675Y1034741D01*
X465168D01*
X467687Y1032222D01*
Y1028717D01*
X469258Y1027146D01*
X484631D01*
X498615Y1041130D01*
X516089D01*
X553318Y1078359D01*
Y1093878D01*
X536464Y1110732D01*
Y1190016D01*
X531759Y1194721D01*
X467035D01*
X465785Y1193471D01*
G01X777725Y1450193D02*
X779725D01*
X785538Y1456006D01*
X787946D01*
X793069Y1461129D01*
X828809D01*
X832541Y1457397D01*
X835474D01*
G01D02*
X837129Y1455742D01*
X842349D01*
X848520Y1461913D01*
X876190D01*
X881244Y1456859D01*
G01X1020023Y1489637D02*
X1019189Y1488803D01*
X1019188Y1488198D01*
Y1486970D01*
X1016642Y1484424D01*
X936748D01*
X928856Y1476532D01*
Y1471016D01*
X921852Y1464012D01*
Y1459585D01*
X925602Y1455835D01*
Y1423577D01*
X935425Y1413754D01*
Y1402693D01*
X931159Y1398427D01*
G01X1016769Y1489832D02*
X1017688Y1488911D01*
Y1487592D01*
X1016020Y1485924D01*
X936126D01*
X927356Y1477154D01*
Y1471638D01*
X920352Y1464634D01*
Y1458963D01*
X924102Y1455213D01*
Y1422955D01*
X933925Y1413132D01*
Y1408793D01*
X931159Y1406027D01*
G01X1150885Y1196751D02*
X1148305Y1194171D01*
Y1166576D01*
X1144654Y1162925D01*
X1054220D01*
X1052010Y1160715D01*
X1035637D01*
X1032193Y1164159D01*
Y1181684D01*
X1002028Y1211849D01*
X979895D01*
X978614Y1210568D01*
G01Y1214838D02*
X979803Y1213649D01*
X1002774D01*
X1033993Y1182430D01*
Y1164905D01*
X1036383Y1162515D01*
X1051264D01*
X1053474Y1164725D01*
X1143908D01*
X1146505Y1167322D01*
Y1191739D01*
X1145233Y1193011D01*
X1143405D01*
G01X1091529Y1528718D02*
X1091880Y1529069D01*
X1097577D01*
X1100615Y1526031D01*
Y1471252D01*
X1074904Y1445541D01*
X1069642D01*
G01X1068861Y1451311D02*
X1078552D01*
X1099115Y1471874D01*
Y1524365D01*
X1096780Y1526700D01*
G01X1375459Y1197471D02*
X1374209Y1196221D01*
X1311738D01*
X1309030Y1193513D01*
Y1169508D01*
X1286832Y1147310D01*
Y1124803D01*
X1309777Y1101858D01*
X1322270D01*
X1335786Y1088342D01*
Y1056181D01*
X1342004Y1049963D01*
X1391235D01*
X1394559Y1046639D01*
Y1039076D01*
X1396305Y1037330D01*
X1397303D01*
X1398676Y1037313D01*
X1399807Y1036155D01*
G01X1375459Y1193471D02*
X1374209Y1194721D01*
X1312360D01*
X1310530Y1192891D01*
Y1168886D01*
X1288332Y1146688D01*
Y1125425D01*
X1310399Y1103358D01*
X1322892D01*
X1337286Y1088964D01*
Y1056803D01*
X1342626Y1051463D01*
X1391857D01*
X1396059Y1047261D01*
Y1039698D01*
X1396927Y1038830D01*
X1397313D01*
X1398757Y1038813D01*
X1399748Y1039779D01*
X1399852D01*
G01X1373874Y1032266D02*
X1374849Y1033241D01*
X1378720D01*
X1380361Y1031600D01*
Y1028095D01*
X1382810Y1025646D01*
X1399427D01*
X1413411Y1039630D01*
X1430885D01*
X1468992Y1077737D01*
Y1094500D01*
X1452138Y1111354D01*
Y1190638D01*
X1446555Y1196221D01*
X1381209D01*
X1379959Y1197471D01*
G01Y1193471D02*
X1381209Y1194721D01*
X1445933D01*
X1450638Y1190016D01*
Y1110732D01*
X1467492Y1093878D01*
Y1078359D01*
X1430263Y1041130D01*
X1412789D01*
X1398805Y1027146D01*
X1383432D01*
X1381861Y1028717D01*
Y1032222D01*
X1379342Y1034741D01*
X1374849D01*
X1373874Y1035716D01*
G54D12*
X23622Y1604724D03*
X62205Y765197D03*
X74016Y333464D03*
X409488Y1604724D03*
X463386Y765197D03*
X920473Y765196D03*
X1347303Y70866D03*
X1431457Y1604724D03*
X1778740Y765197D03*
X1817323Y1604724D03*
G54D21*
X343212Y1774624D03*
Y1784624D03*
X595312Y1774624D03*
Y1784624D03*
X917279Y1738990D03*
Y1728990D03*
X1169329D03*
Y1738990D03*
G54D31*
G01X-20602Y-468335D02*
Y-543335D01*
X479398D01*
Y-468335D01*
X-20602D01*
G01X-8602Y-533335D02*
Y-538335D01*
G01X-10059Y-533335D02*
X-7145D01*
G01X-2235Y-538335D02*
X-4769D01*
Y-533335D01*
X-2235D01*
G01X-3249Y-535752D02*
X-4769D01*
G01X331Y-533335D02*
Y-538335D01*
X2865D01*
G01X6698Y-538502D02*
X6571Y-538418D01*
Y-538252D01*
X6698Y-538168D01*
X6825Y-538252D01*
Y-538418D01*
X6698Y-538502D01*
G01Y-536252D02*
X6571Y-536168D01*
Y-536002D01*
X6698Y-535918D01*
X6825Y-536002D01*
Y-536168D01*
X6698Y-536252D01*
G01X11481Y-540002D02*
X10848Y-539168D01*
X10531Y-538335D01*
Y-535002D01*
X10848Y-534168D01*
X11481Y-533335D01*
G01X16898D02*
X16391Y-533502D01*
X16011Y-533918D01*
X15758Y-534418D01*
X15568Y-535085D01*
X15505Y-535835D01*
X15568Y-536585D01*
X15758Y-537252D01*
X16011Y-537752D01*
X16391Y-538168D01*
X16898Y-538335D01*
X17405Y-538168D01*
X17785Y-537752D01*
X18038Y-537252D01*
X18228Y-536585D01*
X18291Y-535835D01*
X18228Y-535085D01*
X18038Y-534418D01*
X17785Y-533918D01*
X17405Y-533502D01*
X16898Y-533335D01*
G01X20605Y-537335D02*
X20985Y-537918D01*
X21491Y-538252D01*
X22061Y-538335D01*
X22568Y-538252D01*
X23075Y-537835D01*
X23391Y-537335D01*
X23455Y-536835D01*
X23328Y-536252D01*
X22885Y-535835D01*
X22441Y-535668D01*
X21871D01*
G01X22441D02*
X22821Y-535418D01*
X23138Y-535002D01*
X23265Y-534502D01*
X23138Y-534002D01*
X22821Y-533585D01*
X22251Y-533335D01*
X21681Y-533418D01*
X21111Y-533752D01*
G01X27415Y-540002D02*
X28048Y-539168D01*
X28365Y-538335D01*
Y-535002D01*
X28048Y-534168D01*
X27415Y-533335D01*
G01X30805Y-537335D02*
X31185Y-537918D01*
X31691Y-538252D01*
X32261Y-538335D01*
X32768Y-538252D01*
X33275Y-537835D01*
X33591Y-537335D01*
X33655Y-536835D01*
X33528Y-536252D01*
X33085Y-535835D01*
X32641Y-535668D01*
X32071D01*
G01X32641D02*
X33021Y-535418D01*
X33338Y-535002D01*
X33465Y-534502D01*
X33338Y-534002D01*
X33021Y-533585D01*
X32451Y-533335D01*
X31881Y-533418D01*
X31311Y-533752D01*
G01X36095Y-534168D02*
X36475Y-533668D01*
X36918Y-533418D01*
X37425Y-533335D01*
X38058Y-533502D01*
X38501Y-533918D01*
X38628Y-534418D01*
X38565Y-534918D01*
X38311Y-535335D01*
X37045Y-536168D01*
X36475Y-536752D01*
X36095Y-537585D01*
X35968Y-538335D01*
X38628D01*
G01X42271D02*
X42398Y-537252D01*
X42588Y-536335D01*
X42841Y-535502D01*
X43158Y-534585D01*
X43665Y-533335D01*
X41131D01*
G01X46675Y-536668D02*
X48321D01*
G01X51395Y-534168D02*
X51775Y-533668D01*
X52218Y-533418D01*
X52725Y-533335D01*
X53358Y-533502D01*
X53801Y-533918D01*
X53928Y-534418D01*
X53865Y-534918D01*
X53611Y-535335D01*
X52345Y-536168D01*
X51775Y-536752D01*
X51395Y-537585D01*
X51268Y-538335D01*
X53928D01*
G01X56305Y-537335D02*
X56685Y-537918D01*
X57191Y-538252D01*
X57761Y-538335D01*
X58268Y-538252D01*
X58775Y-537835D01*
X59091Y-537335D01*
X59155Y-536835D01*
X59028Y-536252D01*
X58585Y-535835D01*
X58141Y-535668D01*
X57571D01*
G01X58141D02*
X58521Y-535418D01*
X58838Y-535002D01*
X58965Y-534502D01*
X58838Y-534002D01*
X58521Y-533585D01*
X57951Y-533335D01*
X57381Y-533418D01*
X56811Y-533752D01*
G01X63558Y-538335D02*
Y-533335D01*
X61215Y-536918D01*
X64381D01*
G01X66505Y-537585D02*
X66885Y-538002D01*
X67328Y-538252D01*
X67898Y-538335D01*
X68468Y-538168D01*
X68911Y-537835D01*
X69228Y-537252D01*
X69291Y-536585D01*
X69165Y-535918D01*
X68848Y-535502D01*
X68405Y-535168D01*
X67961Y-535085D01*
X67518Y-535168D01*
X66948Y-535502D01*
X67138Y-533335D01*
X68848D01*
G01X76895Y-538335D02*
Y-533335D01*
X79301D01*
G01X78415Y-535752D02*
X76895D01*
G01X81615Y-538335D02*
X83198Y-533335D01*
X84781Y-538335D01*
G01X84211Y-536585D02*
X82185D01*
G01X86968Y-538335D02*
X89628Y-533335D01*
G01X86968D02*
X89628Y-538335D01*
G01X93398Y-538502D02*
X93271Y-538418D01*
Y-538252D01*
X93398Y-538168D01*
X93525Y-538252D01*
Y-538418D01*
X93398Y-538502D01*
G01Y-536252D02*
X93271Y-536168D01*
Y-536002D01*
X93398Y-535918D01*
X93525Y-536002D01*
Y-536168D01*
X93398Y-536252D01*
G01X98181Y-540002D02*
X97548Y-539168D01*
X97231Y-538335D01*
Y-535002D01*
X97548Y-534168D01*
X98181Y-533335D01*
G01X103598D02*
X103091Y-533502D01*
X102711Y-533918D01*
X102458Y-534418D01*
X102268Y-535085D01*
X102205Y-535835D01*
X102268Y-536585D01*
X102458Y-537252D01*
X102711Y-537752D01*
X103091Y-538168D01*
X103598Y-538335D01*
X104105Y-538168D01*
X104485Y-537752D01*
X104738Y-537252D01*
X104928Y-536585D01*
X104991Y-535835D01*
X104928Y-535085D01*
X104738Y-534418D01*
X104485Y-533918D01*
X104105Y-533502D01*
X103598Y-533335D01*
G01X107305Y-537335D02*
X107685Y-537918D01*
X108191Y-538252D01*
X108761Y-538335D01*
X109268Y-538252D01*
X109775Y-537835D01*
X110091Y-537335D01*
X110155Y-536835D01*
X110028Y-536252D01*
X109585Y-535835D01*
X109141Y-535668D01*
X108571D01*
G01X109141D02*
X109521Y-535418D01*
X109838Y-535002D01*
X109965Y-534502D01*
X109838Y-534002D01*
X109521Y-533585D01*
X108951Y-533335D01*
X108381Y-533418D01*
X107811Y-533752D01*
G01X114115Y-540002D02*
X114748Y-539168D01*
X115065Y-538335D01*
Y-535002D01*
X114748Y-534168D01*
X114115Y-533335D01*
G01X117505Y-537335D02*
X117885Y-537918D01*
X118391Y-538252D01*
X118961Y-538335D01*
X119468Y-538252D01*
X119975Y-537835D01*
X120291Y-537335D01*
X120355Y-536835D01*
X120228Y-536252D01*
X119785Y-535835D01*
X119341Y-535668D01*
X118771D01*
G01X119341D02*
X119721Y-535418D01*
X120038Y-535002D01*
X120165Y-534502D01*
X120038Y-534002D01*
X119721Y-533585D01*
X119151Y-533335D01*
X118581Y-533418D01*
X118011Y-533752D01*
G01X122921Y-537752D02*
X123365Y-538168D01*
X123871Y-538335D01*
X124378Y-538168D01*
X124821Y-537668D01*
X125138Y-536918D01*
X125265Y-536168D01*
Y-535252D01*
X125138Y-534502D01*
X124821Y-533835D01*
X124441Y-533502D01*
X123998Y-533335D01*
X123491Y-533502D01*
X123111Y-533835D01*
X122858Y-534335D01*
X122731Y-535002D01*
X122858Y-535585D01*
X123175Y-536168D01*
X123555Y-536502D01*
X123998Y-536585D01*
X124505Y-536418D01*
X124885Y-536002D01*
X125265Y-535252D01*
G01X128971Y-538335D02*
X129098Y-537252D01*
X129288Y-536335D01*
X129541Y-535502D01*
X129858Y-534585D01*
X130365Y-533335D01*
X127831D01*
G01X133375Y-536668D02*
X135021D01*
G01X137905Y-537335D02*
X138285Y-537918D01*
X138791Y-538252D01*
X139361Y-538335D01*
X139868Y-538252D01*
X140375Y-537835D01*
X140691Y-537335D01*
X140755Y-536835D01*
X140628Y-536252D01*
X140185Y-535835D01*
X139741Y-535668D01*
X139171D01*
G01X139741D02*
X140121Y-535418D01*
X140438Y-535002D01*
X140565Y-534502D01*
X140438Y-534002D01*
X140121Y-533585D01*
X139551Y-533335D01*
X138981Y-533418D01*
X138411Y-533752D01*
G01X143195Y-536252D02*
X143638Y-535668D01*
X144018Y-535335D01*
X144525Y-535168D01*
X144968Y-535335D01*
X145285Y-535668D01*
X145538Y-536168D01*
X145601Y-536752D01*
X145538Y-537252D01*
X145285Y-537752D01*
X144905Y-538168D01*
X144461Y-538335D01*
X143955Y-538168D01*
X143511Y-537668D01*
X143258Y-536918D01*
X143195Y-536085D01*
X143321Y-535002D01*
X143511Y-534418D01*
X143828Y-533835D01*
X144271Y-533418D01*
X144715Y-533335D01*
X145158Y-533502D01*
X145475Y-533918D01*
G01X149498Y-538335D02*
Y-533335D01*
X148738Y-534335D01*
G01Y-538335D02*
X150258D01*
G01X155358D02*
Y-533335D01*
X153015Y-536918D01*
X156181D01*
G01X174398Y-468335D02*
Y-543335D01*
G01Y-518335D02*
X277398D01*
Y-493335D01*
G01X174398D02*
X277398D01*
G01Y-468335D02*
Y-543335D01*
G01X279398Y-468335D02*
Y-543335D01*
G01X284905Y-528335D02*
Y-523335D01*
X286171D01*
X286678Y-523585D01*
X287058Y-523918D01*
X287375Y-524418D01*
X287628Y-525002D01*
X287691Y-525835D01*
X287628Y-526668D01*
X287375Y-527252D01*
X287058Y-527752D01*
X286678Y-528085D01*
X286171Y-528335D01*
X284905D01*
G01X289815D02*
X291398Y-523335D01*
X292981Y-528335D01*
G01X292411Y-526585D02*
X290385D01*
G01X296498Y-523335D02*
Y-528335D01*
G01X295041Y-523335D02*
X297955D01*
G01X302865Y-528335D02*
X300331D01*
Y-523335D01*
X302865D01*
G01X301851Y-525752D02*
X300331D01*
G01X306698Y-528502D02*
X306571Y-528418D01*
Y-528252D01*
X306698Y-528168D01*
X306825Y-528252D01*
Y-528418D01*
X306698Y-528502D01*
G01Y-526252D02*
X306571Y-526168D01*
Y-526002D01*
X306698Y-525918D01*
X306825Y-526002D01*
Y-526168D01*
X306698Y-526252D01*
G01X279398Y-518335D02*
X479398D01*
G01X285031Y-503335D02*
Y-498335D01*
X286551D01*
X287058Y-498585D01*
X287438Y-499168D01*
X287565Y-499835D01*
X287438Y-500502D01*
X287121Y-501002D01*
X286551Y-501252D01*
X285031D01*
G01X290258Y-503502D02*
X292538Y-498335D01*
G01X295041Y-503335D02*
Y-498335D01*
X297955Y-503335D01*
Y-498335D01*
G01X301598Y-503502D02*
X301471Y-503418D01*
Y-503252D01*
X301598Y-503168D01*
X301725Y-503252D01*
Y-503418D01*
X301598Y-503502D01*
G01Y-501252D02*
X301471Y-501168D01*
Y-501002D01*
X301598Y-500918D01*
X301725Y-501002D01*
Y-501168D01*
X301598Y-501252D01*
G01X279398Y-493335D02*
X479398D01*
G01X285031Y-478335D02*
Y-473335D01*
X286551D01*
X287058Y-473585D01*
X287438Y-474168D01*
X287565Y-474835D01*
X287438Y-475502D01*
X287121Y-476002D01*
X286551Y-476252D01*
X285031D01*
G01X290131Y-478335D02*
Y-473335D01*
X291715D01*
X292221Y-473585D01*
X292538Y-473918D01*
X292665Y-474585D01*
X292538Y-475252D01*
X292158Y-475668D01*
X291715Y-475918D01*
X290131D01*
G01X291715D02*
X292665Y-478335D01*
G01X296498D02*
X295991Y-478252D01*
X295548Y-477918D01*
X295168Y-477418D01*
X294915Y-476835D01*
X294788Y-476168D01*
Y-475502D01*
X294915Y-474835D01*
X295168Y-474252D01*
X295548Y-473752D01*
X295991Y-473418D01*
X296498Y-473335D01*
X297005Y-473418D01*
X297448Y-473752D01*
X297828Y-474252D01*
X298081Y-474835D01*
X298208Y-475502D01*
Y-476168D01*
X298081Y-476835D01*
X297828Y-477418D01*
X297448Y-477918D01*
X297005Y-478252D01*
X296498Y-478335D01*
G01X300331Y-477335D02*
X300648Y-477835D01*
X301028Y-478168D01*
X301471Y-478335D01*
X301978Y-478168D01*
X302358Y-477835D01*
X302738Y-477335D01*
X302865Y-476668D01*
Y-473335D01*
G01X307965Y-478335D02*
X305431D01*
Y-473335D01*
X307965D01*
G01X306951Y-475752D02*
X305431D01*
G01X313191Y-473752D02*
X312811Y-473502D01*
X312368Y-473335D01*
X311861D01*
X311291Y-473585D01*
X310848Y-474002D01*
X310531Y-474502D01*
X310278Y-475335D01*
X310215Y-476085D01*
X310341Y-476835D01*
X310531Y-477335D01*
X310911Y-477835D01*
X311355Y-478168D01*
X311798Y-478335D01*
X312241D01*
X312685Y-478168D01*
X313065Y-477918D01*
X313381Y-477585D01*
G01X316898Y-473335D02*
Y-478335D01*
G01X315441Y-473335D02*
X318355D01*
G01X321998Y-478502D02*
X321871Y-478418D01*
Y-478252D01*
X321998Y-478168D01*
X322125Y-478252D01*
Y-478418D01*
X321998Y-478502D01*
G01Y-476252D02*
X321871Y-476168D01*
Y-476002D01*
X321998Y-475918D01*
X322125Y-476002D01*
Y-476168D01*
X321998Y-476252D01*
G01X394258Y-543563D02*
Y-518563D01*
G01X397031Y-520835D02*
Y-525835D01*
X399565D01*
G01X402638Y-520835D02*
X404158D01*
G01X403398D02*
Y-525835D01*
G01X402638D02*
X404158D01*
G01X409005Y-523168D02*
X409258Y-522918D01*
X409448Y-522502D01*
X409575Y-521918D01*
X409448Y-521418D01*
X409195Y-521085D01*
X408751Y-520835D01*
X407041D01*
Y-525835D01*
X409131D01*
X409575Y-525502D01*
X409828Y-525002D01*
X409955Y-524418D01*
X409828Y-523835D01*
X409448Y-523335D01*
X409005Y-523168D01*
X407041D01*
G01X413598Y-526002D02*
X413471Y-525918D01*
Y-525752D01*
X413598Y-525668D01*
X413725Y-525752D01*
Y-525918D01*
X413598Y-526002D01*
G01Y-523752D02*
X413471Y-523668D01*
Y-523502D01*
X413598Y-523418D01*
X413725Y-523502D01*
Y-523668D01*
X413598Y-523752D01*
G01X437258Y-518563D02*
Y-543563D01*
G01X437398Y-518335D02*
Y-543335D01*
G01X441298Y-520835D02*
Y-525835D01*
G01X439841Y-520835D02*
X442755D01*
G01X446398Y-525835D02*
X446018Y-525752D01*
X445638Y-525418D01*
X445385Y-524835D01*
X445258Y-524168D01*
X445385Y-523502D01*
X445638Y-522918D01*
X446018Y-522585D01*
X446398Y-522502D01*
X446778Y-522585D01*
X447158Y-522918D01*
X447411Y-523502D01*
X447475Y-524168D01*
X447411Y-524835D01*
X447158Y-525418D01*
X446778Y-525752D01*
X446398Y-525835D01*
G01X451498D02*
X451118Y-525752D01*
X450738Y-525418D01*
X450485Y-524835D01*
X450358Y-524168D01*
X450485Y-523502D01*
X450738Y-522918D01*
X451118Y-522585D01*
X451498Y-522502D01*
X451878Y-522585D01*
X452258Y-522918D01*
X452511Y-523502D01*
X452575Y-524168D01*
X452511Y-524835D01*
X452258Y-525418D01*
X451878Y-525752D01*
X451498Y-525835D01*
G01X456598D02*
Y-520835D01*
G01X461698Y-526002D02*
X461571Y-525918D01*
Y-525752D01*
X461698Y-525668D01*
X461825Y-525752D01*
Y-525918D01*
X461698Y-526002D01*
G01Y-523752D02*
X461571Y-523668D01*
Y-523502D01*
X461698Y-523418D01*
X461825Y-523502D01*
Y-523668D01*
X461698Y-523752D01*
G01X437398Y-493335D02*
Y-518335D01*
G01X440031Y-500835D02*
Y-495835D01*
X441615D01*
X442121Y-496085D01*
X442438Y-496418D01*
X442565Y-497085D01*
X442438Y-497752D01*
X442058Y-498168D01*
X441615Y-498418D01*
X440031D01*
G01X441615D02*
X442565Y-500835D01*
G01X447665D02*
X445131D01*
Y-495835D01*
X447665D01*
G01X446651Y-498252D02*
X445131D01*
G01X449915Y-495835D02*
X451498Y-500835D01*
X453081Y-495835D01*
G01X456598Y-501002D02*
X456471Y-500918D01*
Y-500752D01*
X456598Y-500668D01*
X456725Y-500752D01*
Y-500918D01*
X456598Y-501002D01*
G01Y-498752D02*
X456471Y-498668D01*
Y-498502D01*
X456598Y-498418D01*
X456725Y-498502D01*
Y-498668D01*
X456598Y-498752D01*
G01X445411Y-546502D02*
X445518Y-546377D01*
X445598Y-546168D01*
X445651Y-545877D01*
X445598Y-545627D01*
X445491Y-545460D01*
X445305Y-545335D01*
X444585D01*
Y-547835D01*
X445465D01*
X445651Y-547668D01*
X445758Y-547418D01*
X445811Y-547127D01*
X445758Y-546835D01*
X445598Y-546585D01*
X445411Y-546502D01*
X444585D01*
G01X447878Y-547835D02*
Y-546168D01*
G01Y-546460D02*
X447771Y-546293D01*
X447611Y-546210D01*
X447425Y-546168D01*
X447238Y-546252D01*
X447078Y-546418D01*
X446971Y-546668D01*
X446918Y-547002D01*
X446971Y-547335D01*
X447078Y-547585D01*
X447238Y-547752D01*
X447425Y-547835D01*
X447611Y-547793D01*
X447771Y-547668D01*
X447878Y-547502D01*
G01X449198Y-547543D02*
X449331Y-547710D01*
X449518Y-547835D01*
X449678D01*
X449838Y-547752D01*
X449945Y-547627D01*
X449998Y-547460D01*
X449971Y-547210D01*
X449865Y-547085D01*
X449385Y-546835D01*
X449278Y-546543D01*
X449331Y-546335D01*
X449438Y-546210D01*
X449598Y-546168D01*
X449758Y-546210D01*
X449918Y-546335D01*
G01X451398Y-546710D02*
X452251D01*
X452171Y-546418D01*
X452038Y-546252D01*
X451851Y-546168D01*
X451665Y-546210D01*
X451505Y-546335D01*
X451398Y-546627D01*
X451345Y-546877D01*
Y-547127D01*
X451398Y-547377D01*
X451531Y-547627D01*
X451691Y-547793D01*
X451878Y-547835D01*
X452065Y-547752D01*
X452251Y-547502D01*
G01X453518Y-547835D02*
Y-545335D01*
G01Y-546585D02*
X453651Y-546335D01*
X453811Y-546210D01*
X453971Y-546168D01*
X454211Y-546252D01*
X454371Y-546418D01*
X454478Y-546710D01*
Y-547043D01*
X454425Y-547377D01*
X454318Y-547627D01*
X454131Y-547793D01*
X453971Y-547835D01*
X453811Y-547793D01*
X453651Y-547668D01*
X453518Y-547460D01*
G01X456198Y-547835D02*
X456038Y-547793D01*
X455878Y-547627D01*
X455771Y-547335D01*
X455718Y-547002D01*
X455771Y-546668D01*
X455878Y-546377D01*
X456038Y-546210D01*
X456198Y-546168D01*
X456358Y-546210D01*
X456518Y-546377D01*
X456625Y-546668D01*
X456651Y-547002D01*
X456625Y-547335D01*
X456518Y-547627D01*
X456358Y-547793D01*
X456198Y-547835D01*
G01X458878D02*
Y-546168D01*
G01Y-546460D02*
X458771Y-546293D01*
X458611Y-546210D01*
X458425Y-546168D01*
X458238Y-546252D01*
X458078Y-546418D01*
X457971Y-546668D01*
X457918Y-547002D01*
X457971Y-547335D01*
X458078Y-547585D01*
X458238Y-547752D01*
X458425Y-547835D01*
X458611Y-547793D01*
X458771Y-547668D01*
X458878Y-547502D01*
G01X460225Y-547835D02*
Y-546168D01*
G01Y-546502D02*
X460358Y-546335D01*
X460491Y-546210D01*
X460678Y-546168D01*
X460811Y-546210D01*
X460971Y-546335D01*
G01X463278Y-545335D02*
Y-547835D01*
G01Y-547460D02*
X463171Y-547668D01*
X463011Y-547793D01*
X462825Y-547835D01*
X462611Y-547752D01*
X462451Y-547543D01*
X462345Y-547293D01*
X462318Y-547002D01*
X462345Y-546710D01*
X462451Y-546460D01*
X462611Y-546252D01*
X462825Y-546168D01*
X463011Y-546210D01*
X463145Y-546293D01*
X463278Y-546460D01*
G01X466665Y-547835D02*
Y-545335D01*
X467331D01*
X467545Y-545460D01*
X467678Y-545627D01*
X467731Y-545960D01*
X467678Y-546293D01*
X467518Y-546502D01*
X467331Y-546627D01*
X466665D01*
G01X467331D02*
X467731Y-547835D01*
G01X468998Y-546710D02*
X469851D01*
X469771Y-546418D01*
X469638Y-546252D01*
X469451Y-546168D01*
X469265Y-546210D01*
X469105Y-546335D01*
X468998Y-546627D01*
X468945Y-546877D01*
Y-547127D01*
X468998Y-547377D01*
X469131Y-547627D01*
X469291Y-547793D01*
X469478Y-547835D01*
X469665Y-547752D01*
X469851Y-547502D01*
G01X471118Y-546168D02*
X471598Y-547835D01*
X472078Y-546168D01*
G01X473798Y-547918D02*
X473745Y-547877D01*
Y-547793D01*
X473798Y-547752D01*
X473851Y-547793D01*
Y-547877D01*
X473798Y-547918D01*
G01X475545Y-547543D02*
X475731Y-547752D01*
X475945Y-547835D01*
X476158Y-547752D01*
X476345Y-547502D01*
X476478Y-547127D01*
X476531Y-546752D01*
Y-546293D01*
X476478Y-545918D01*
X476345Y-545585D01*
X476185Y-545418D01*
X475998Y-545335D01*
X475785Y-545418D01*
X475625Y-545585D01*
X475518Y-545835D01*
X475465Y-546168D01*
X475518Y-546460D01*
X475651Y-546752D01*
X475811Y-546918D01*
X475998Y-546960D01*
X476211Y-546877D01*
X476371Y-546668D01*
X476531Y-546293D01*
G01X478411Y-546502D02*
X478518Y-546377D01*
X478598Y-546168D01*
X478651Y-545877D01*
X478598Y-545627D01*
X478491Y-545460D01*
X478305Y-545335D01*
X477585D01*
Y-547835D01*
X478465D01*
X478651Y-547668D01*
X478758Y-547418D01*
X478811Y-547127D01*
X478758Y-546835D01*
X478598Y-546585D01*
X478411Y-546502D01*
X477585D01*
G01X-1490433Y-1677216D02*
Y3837819D01*
X4496476D01*
Y-1677216D01*
X-1490433D01*
G01X-7782Y-515685D02*
X-6215D01*
Y-517575D01*
X-6685Y-518205D01*
X-7234Y-518625D01*
X-8017Y-518835D01*
X-8800Y-518625D01*
X-9349Y-518205D01*
X-9819Y-517575D01*
X-10132Y-516840D01*
X-10289Y-516000D01*
Y-515265D01*
X-10132Y-514635D01*
X-9819Y-513900D01*
X-9349Y-513270D01*
X-8879Y-512850D01*
X-8252Y-512535D01*
X-7704D01*
X-7077Y-512745D01*
X-6607Y-513165D01*
G01X-3675Y-512535D02*
Y-517050D01*
X-3362Y-517995D01*
X-2735Y-518625D01*
X-1952Y-518835D01*
X-1169Y-518625D01*
X-542Y-517995D01*
X-229Y-517050D01*
Y-512535D01*
G01X3408D02*
X5288D01*
G01X4348D02*
Y-518835D01*
G01X3408D02*
X5288D01*
G01X9003Y-517995D02*
X9630Y-518520D01*
X10335Y-518835D01*
X10961D01*
X11588Y-518520D01*
X12058Y-517995D01*
X12293Y-517260D01*
X12136Y-516525D01*
X11745Y-515895D01*
X11040Y-515475D01*
X10100Y-515265D01*
X9551Y-514845D01*
X9316Y-514110D01*
X9473Y-513375D01*
X9865Y-512850D01*
X10413Y-512535D01*
X10961D01*
X11510Y-512745D01*
X11980Y-513270D01*
G01X15303Y-518835D02*
Y-512535D01*
G01X18593D02*
Y-518835D01*
G01Y-515685D02*
X15303D01*
G01X21290Y-518835D02*
X23248Y-512535D01*
X25206Y-518835D01*
G01X24501Y-516630D02*
X21995D01*
G01X27746Y-518835D02*
Y-512535D01*
X31350Y-518835D01*
Y-512535D01*
G01X40425Y-518835D02*
Y-512535D01*
X41991D01*
X42618Y-512850D01*
X43088Y-513270D01*
X43480Y-513900D01*
X43793Y-514635D01*
X43871Y-515685D01*
X43793Y-516735D01*
X43480Y-517470D01*
X43088Y-518100D01*
X42618Y-518520D01*
X41991Y-518835D01*
X40425D01*
G01X47508Y-512535D02*
X49388D01*
G01X48448D02*
Y-518835D01*
G01X47508D02*
X49388D01*
G01X53103Y-517995D02*
X53730Y-518520D01*
X54435Y-518835D01*
X55061D01*
X55688Y-518520D01*
X56158Y-517995D01*
X56393Y-517260D01*
X56236Y-516525D01*
X55845Y-515895D01*
X55140Y-515475D01*
X54200Y-515265D01*
X53651Y-514845D01*
X53416Y-514110D01*
X53573Y-513375D01*
X53965Y-512850D01*
X54513Y-512535D01*
X55061D01*
X55610Y-512745D01*
X56080Y-513270D01*
G01X61048Y-512535D02*
Y-518835D01*
G01X59246Y-512535D02*
X62850D01*
G01X67348Y-519045D02*
X67191Y-518940D01*
Y-518730D01*
X67348Y-518625D01*
X67505Y-518730D01*
Y-518940D01*
X67348Y-519045D01*
G01X73491Y-519990D02*
X73805Y-518625D01*
G01X79948Y-512535D02*
Y-518835D01*
G01X78146Y-512535D02*
X81750D01*
G01X84290Y-518835D02*
X86248Y-512535D01*
X88206Y-518835D01*
G01X87501Y-516630D02*
X84995D01*
G01X92548Y-518835D02*
X91921Y-518730D01*
X91373Y-518310D01*
X90903Y-517680D01*
X90590Y-516945D01*
X90433Y-516105D01*
Y-515265D01*
X90590Y-514425D01*
X90903Y-513690D01*
X91373Y-513060D01*
X91921Y-512640D01*
X92548Y-512535D01*
X93175Y-512640D01*
X93723Y-513060D01*
X94193Y-513690D01*
X94506Y-514425D01*
X94663Y-515265D01*
Y-516105D01*
X94506Y-516945D01*
X94193Y-517680D01*
X93723Y-518310D01*
X93175Y-518730D01*
X92548Y-518835D01*
G01X98848D02*
Y-516000D01*
X97281Y-512535D01*
G01X100415D02*
X98848Y-516000D01*
G01X103425Y-512535D02*
Y-517050D01*
X103738Y-517995D01*
X104365Y-518625D01*
X105148Y-518835D01*
X105931Y-518625D01*
X106558Y-517995D01*
X106871Y-517050D01*
Y-512535D01*
G01X109490Y-518835D02*
X111448Y-512535D01*
X113406Y-518835D01*
G01X112701Y-516630D02*
X110195D01*
G01X115946Y-518835D02*
Y-512535D01*
X119550Y-518835D01*
Y-512535D01*
G01X-6529Y-523060D02*
X-6999Y-522745D01*
X-7547Y-522535D01*
X-8174D01*
X-8879Y-522850D01*
X-9427Y-523375D01*
X-9819Y-524005D01*
X-10132Y-525055D01*
X-10210Y-526000D01*
X-10054Y-526945D01*
X-9819Y-527575D01*
X-9349Y-528205D01*
X-8800Y-528625D01*
X-8252Y-528835D01*
X-7704D01*
X-7155Y-528625D01*
X-6685Y-528310D01*
X-6294Y-527890D01*
G01X-2892Y-522535D02*
X-1012D01*
G01X-1952D02*
Y-528835D01*
G01X-2892D02*
X-1012D01*
G01X4348Y-522535D02*
Y-528835D01*
G01X2546Y-522535D02*
X6150D01*
G01X10648Y-528835D02*
Y-526000D01*
X9081Y-522535D01*
G01X12215D02*
X10648Y-526000D01*
G01X21525Y-527575D02*
X21995Y-528310D01*
X22621Y-528730D01*
X23326Y-528835D01*
X23953Y-528730D01*
X24580Y-528205D01*
X24971Y-527575D01*
X25050Y-526945D01*
X24893Y-526210D01*
X24345Y-525685D01*
X23796Y-525475D01*
X23091D01*
G01X23796D02*
X24266Y-525160D01*
X24658Y-524635D01*
X24815Y-524005D01*
X24658Y-523375D01*
X24266Y-522850D01*
X23561Y-522535D01*
X22856Y-522640D01*
X22151Y-523060D01*
G01X27825Y-527575D02*
X28295Y-528310D01*
X28921Y-528730D01*
X29626Y-528835D01*
X30253Y-528730D01*
X30880Y-528205D01*
X31271Y-527575D01*
X31350Y-526945D01*
X31193Y-526210D01*
X30645Y-525685D01*
X30096Y-525475D01*
X29391D01*
G01X30096D02*
X30566Y-525160D01*
X30958Y-524635D01*
X31115Y-524005D01*
X30958Y-523375D01*
X30566Y-522850D01*
X29861Y-522535D01*
X29156Y-522640D01*
X28451Y-523060D01*
G01X34125Y-527575D02*
X34595Y-528310D01*
X35221Y-528730D01*
X35926Y-528835D01*
X36553Y-528730D01*
X37180Y-528205D01*
X37571Y-527575D01*
X37650Y-526945D01*
X37493Y-526210D01*
X36945Y-525685D01*
X36396Y-525475D01*
X35691D01*
G01X36396D02*
X36866Y-525160D01*
X37258Y-524635D01*
X37415Y-524005D01*
X37258Y-523375D01*
X36866Y-522850D01*
X36161Y-522535D01*
X35456Y-522640D01*
X34751Y-523060D01*
G01X41991Y-528835D02*
X42148Y-527470D01*
X42383Y-526315D01*
X42696Y-525265D01*
X43088Y-524110D01*
X43715Y-522535D01*
X40581D01*
G01X48291Y-528835D02*
X48448Y-527470D01*
X48683Y-526315D01*
X48996Y-525265D01*
X49388Y-524110D01*
X50015Y-522535D01*
X46881D01*
G01X54591Y-529990D02*
X54905Y-528625D01*
G01X61048Y-522535D02*
Y-528835D01*
G01X59246Y-522535D02*
X62850D01*
G01X65390Y-528835D02*
X67348Y-522535D01*
X69306Y-528835D01*
G01X68601Y-526630D02*
X66095D01*
G01X72708Y-522535D02*
X74588D01*
G01X73648D02*
Y-528835D01*
G01X72708D02*
X74588D01*
G01X77598Y-522535D02*
X78695Y-528835D01*
X79948Y-522535D01*
X81201Y-528835D01*
X82298Y-522535D01*
G01X84290Y-528835D02*
X86248Y-522535D01*
X88206Y-528835D01*
G01X87501Y-526630D02*
X84995D01*
G01X90746Y-528835D02*
Y-522535D01*
X94350Y-528835D01*
Y-522535D01*
G01X104756Y-530935D02*
X103973Y-529885D01*
X103581Y-528835D01*
Y-524635D01*
X103973Y-523585D01*
X104756Y-522535D01*
G01X116181Y-528835D02*
Y-522535D01*
X118140D01*
X118766Y-522850D01*
X119158Y-523270D01*
X119315Y-524110D01*
X119158Y-524950D01*
X118688Y-525475D01*
X118140Y-525790D01*
X116181D01*
G01X118140D02*
X119315Y-528835D01*
G01X124048Y-529045D02*
X123891Y-528940D01*
Y-528730D01*
X124048Y-528625D01*
X124205Y-528730D01*
Y-528940D01*
X124048Y-529045D01*
G01X130348Y-528835D02*
X129721Y-528730D01*
X129173Y-528310D01*
X128703Y-527680D01*
X128390Y-526945D01*
X128233Y-526105D01*
Y-525265D01*
X128390Y-524425D01*
X128703Y-523690D01*
X129173Y-523060D01*
X129721Y-522640D01*
X130348Y-522535D01*
X130975Y-522640D01*
X131523Y-523060D01*
X131993Y-523690D01*
X132306Y-524425D01*
X132463Y-525265D01*
Y-526105D01*
X132306Y-526945D01*
X131993Y-527680D01*
X131523Y-528310D01*
X130975Y-528730D01*
X130348Y-528835D01*
G01X136648Y-529045D02*
X136491Y-528940D01*
Y-528730D01*
X136648Y-528625D01*
X136805Y-528730D01*
Y-528940D01*
X136648Y-529045D01*
G01X144671Y-523060D02*
X144201Y-522745D01*
X143653Y-522535D01*
X143026D01*
X142321Y-522850D01*
X141773Y-523375D01*
X141381Y-524005D01*
X141068Y-525055D01*
X140990Y-526000D01*
X141146Y-526945D01*
X141381Y-527575D01*
X141851Y-528205D01*
X142400Y-528625D01*
X142948Y-528835D01*
X143496D01*
X144045Y-528625D01*
X144515Y-528310D01*
X144906Y-527890D01*
G01X149248Y-529045D02*
X149091Y-528940D01*
Y-528730D01*
X149248Y-528625D01*
X149405Y-528730D01*
Y-528940D01*
X149248Y-529045D01*
G01X155940Y-530935D02*
X156723Y-529885D01*
X157115Y-528835D01*
Y-524635D01*
X156723Y-523585D01*
X155940Y-522535D01*
G01X-10054Y-508835D02*
Y-502535D01*
X-6450Y-508835D01*
Y-502535D01*
G01X-1952Y-508835D02*
X-2579Y-508730D01*
X-3127Y-508310D01*
X-3597Y-507680D01*
X-3910Y-506945D01*
X-4067Y-506105D01*
Y-505265D01*
X-3910Y-504425D01*
X-3597Y-503690D01*
X-3127Y-503060D01*
X-2579Y-502640D01*
X-1952Y-502535D01*
X-1325Y-502640D01*
X-777Y-503060D01*
X-307Y-503690D01*
X6Y-504425D01*
X163Y-505265D01*
Y-506105D01*
X6Y-506945D01*
X-307Y-507680D01*
X-777Y-508310D01*
X-1325Y-508730D01*
X-1952Y-508835D01*
G01X4348Y-509045D02*
X4191Y-508940D01*
Y-508730D01*
X4348Y-508625D01*
X4505Y-508730D01*
Y-508940D01*
X4348Y-509045D01*
G01X9160Y-503585D02*
X9630Y-502955D01*
X10178Y-502640D01*
X10805Y-502535D01*
X11588Y-502745D01*
X12136Y-503270D01*
X12293Y-503900D01*
X12215Y-504530D01*
X11901Y-505055D01*
X10335Y-506105D01*
X9630Y-506840D01*
X9160Y-507890D01*
X9003Y-508835D01*
X12293D01*
G01X16948D02*
Y-502535D01*
X16008Y-503795D01*
G01Y-508835D02*
X17888D01*
G01X23248D02*
Y-502535D01*
X22308Y-503795D01*
G01Y-508835D02*
X24188D01*
G01X29391Y-509990D02*
X29705Y-508625D01*
G01X33498Y-502535D02*
X34595Y-508835D01*
X35848Y-502535D01*
X37101Y-508835D01*
X38198Y-502535D01*
G01X43715Y-508835D02*
X40581D01*
Y-502535D01*
X43715D01*
G01X42461Y-505580D02*
X40581D01*
G01X46646Y-508835D02*
Y-502535D01*
X50250Y-508835D01*
Y-502535D01*
G01X53103Y-508835D02*
Y-502535D01*
G01X56393D02*
Y-508835D01*
G01Y-505685D02*
X53103D01*
G01X59325Y-502535D02*
Y-507050D01*
X59638Y-507995D01*
X60265Y-508625D01*
X61048Y-508835D01*
X61831Y-508625D01*
X62458Y-507995D01*
X62771Y-507050D01*
Y-502535D01*
G01X65390Y-508835D02*
X67348Y-502535D01*
X69306Y-508835D01*
G01X68601Y-506630D02*
X66095D01*
G01X78460Y-503585D02*
X78930Y-502955D01*
X79478Y-502640D01*
X80105Y-502535D01*
X80888Y-502745D01*
X81436Y-503270D01*
X81593Y-503900D01*
X81515Y-504530D01*
X81201Y-505055D01*
X79635Y-506105D01*
X78930Y-506840D01*
X78460Y-507890D01*
X78303Y-508835D01*
X81593D01*
G01X84446D02*
Y-502535D01*
X88050Y-508835D01*
Y-502535D01*
G01X90825Y-508835D02*
Y-502535D01*
X92391D01*
X93018Y-502850D01*
X93488Y-503270D01*
X93880Y-503900D01*
X94193Y-504635D01*
X94271Y-505685D01*
X94193Y-506735D01*
X93880Y-507470D01*
X93488Y-508100D01*
X93018Y-508520D01*
X92391Y-508835D01*
X90825D01*
G01X103581D02*
Y-502535D01*
X105540D01*
X106166Y-502850D01*
X106558Y-503270D01*
X106715Y-504110D01*
X106558Y-504950D01*
X106088Y-505475D01*
X105540Y-505790D01*
X103581D01*
G01X105540D02*
X106715Y-508835D01*
G01X109725D02*
Y-502535D01*
X111291D01*
X111918Y-502850D01*
X112388Y-503270D01*
X112780Y-503900D01*
X113093Y-504635D01*
X113171Y-505685D01*
X113093Y-506735D01*
X112780Y-507470D01*
X112388Y-508100D01*
X111918Y-508520D01*
X111291Y-508835D01*
X109725D01*
G01X117748Y-509045D02*
X117591Y-508940D01*
Y-508730D01*
X117748Y-508625D01*
X117905Y-508730D01*
Y-508940D01*
X117748Y-509045D01*
G01X14048Y-498135D02*
X11528Y-497718D01*
X9323Y-496052D01*
X7433Y-493552D01*
X6173Y-490635D01*
X5543Y-487302D01*
Y-483968D01*
X6173Y-480635D01*
X7433Y-477718D01*
X9323Y-475219D01*
X11528Y-473552D01*
X14048Y-473135D01*
X16568Y-473552D01*
X18773Y-475219D01*
X20663Y-477718D01*
X21923Y-480635D01*
X22553Y-483968D01*
Y-487302D01*
X21923Y-490635D01*
X20663Y-493552D01*
X18773Y-496052D01*
X16568Y-497718D01*
X14048Y-498135D01*
G01X16568Y-491468D02*
X20348Y-498135D01*
G01X33893Y-481469D02*
Y-493135D01*
X35153Y-496052D01*
X37043Y-497718D01*
X39248Y-498135D01*
X41453Y-497718D01*
X43343Y-496052D01*
X44603Y-493135D01*
G01Y-498135D02*
Y-481469D01*
G01X70118Y-498135D02*
Y-481469D01*
G01Y-484385D02*
X68858Y-482719D01*
X66968Y-481885D01*
X64763Y-481469D01*
X62558Y-482302D01*
X60668Y-483968D01*
X59408Y-486469D01*
X58778Y-489802D01*
X59408Y-493135D01*
X60668Y-495636D01*
X62558Y-497302D01*
X64763Y-498135D01*
X66968Y-497718D01*
X68858Y-496469D01*
X70118Y-494802D01*
G01X84293Y-498135D02*
Y-481469D01*
G01Y-485635D02*
X85553Y-483552D01*
X87443Y-481885D01*
X89963Y-481469D01*
X92168Y-481885D01*
X94058Y-483552D01*
X95003Y-486469D01*
Y-498135D01*
G01X114848Y-473135D02*
Y-498135D01*
G01X110438Y-481469D02*
X119258D01*
G01X145718Y-498135D02*
Y-481469D01*
G01Y-484385D02*
X144458Y-482719D01*
X142568Y-481885D01*
X140363Y-481469D01*
X138158Y-482302D01*
X136268Y-483968D01*
X135008Y-486469D01*
X134378Y-489802D01*
X135008Y-493135D01*
X136268Y-495636D01*
X138158Y-497302D01*
X140363Y-498135D01*
X142568Y-497718D01*
X144458Y-496469D01*
X145718Y-494802D01*
G01X185398Y-477835D02*
Y-485835D01*
X189398D01*
G01X197198D02*
Y-480502D01*
G01Y-481435D02*
X196798Y-480902D01*
X196198Y-480635D01*
X195498Y-480502D01*
X194798Y-480768D01*
X194198Y-481302D01*
X193798Y-482102D01*
X193598Y-483168D01*
X193798Y-484235D01*
X194198Y-485035D01*
X194798Y-485568D01*
X195498Y-485835D01*
X196198Y-485702D01*
X196798Y-485302D01*
X197198Y-484769D01*
G01X201298Y-488235D02*
X201898Y-488502D01*
X202698Y-488235D01*
X203198Y-487702D01*
X203598Y-487035D01*
X204198Y-484902D01*
X205498Y-480502D01*
G01X202298D02*
X204198Y-484902D01*
G01X209898Y-482235D02*
X213098D01*
X212798Y-481302D01*
X212298Y-480768D01*
X211598Y-480502D01*
X210898Y-480635D01*
X210298Y-481035D01*
X209898Y-481968D01*
X209698Y-482769D01*
Y-483568D01*
X209898Y-484368D01*
X210398Y-485168D01*
X210998Y-485702D01*
X211698Y-485835D01*
X212398Y-485568D01*
X213098Y-484769D01*
G01X217998Y-485835D02*
Y-480502D01*
G01Y-481568D02*
X218498Y-481035D01*
X218998Y-480635D01*
X219698Y-480502D01*
X220198Y-480635D01*
X220798Y-481035D01*
G01X211398Y-535835D02*
Y-532235D01*
X209398Y-527835D01*
G01X213398D02*
X211398Y-532235D01*
G01X217698Y-530502D02*
Y-534235D01*
X218098Y-535168D01*
X218698Y-535702D01*
X219398Y-535835D01*
X220098Y-535702D01*
X220698Y-535168D01*
X221098Y-534235D01*
G01Y-535835D02*
Y-530502D01*
G01X225698Y-535835D02*
Y-530502D01*
G01Y-531835D02*
X226098Y-531168D01*
X226698Y-530635D01*
X227498Y-530502D01*
X228198Y-530635D01*
X228798Y-531168D01*
X229098Y-532102D01*
Y-535835D01*
G01X237198D02*
Y-530502D01*
G01Y-531435D02*
X236798Y-530902D01*
X236198Y-530635D01*
X235498Y-530502D01*
X234798Y-530768D01*
X234198Y-531302D01*
X233798Y-532102D01*
X233598Y-533168D01*
X233798Y-534235D01*
X234198Y-535035D01*
X234798Y-535568D01*
X235498Y-535835D01*
X236198Y-535702D01*
X236798Y-535302D01*
X237198Y-534769D01*
G01X217698Y-502835D02*
X220098D01*
G01X218898D02*
Y-510835D01*
G01X217698D02*
X220098D01*
G01X224598D02*
Y-502835D01*
X229198Y-510835D01*
Y-502835D01*
G01X232698Y-509235D02*
X233298Y-510168D01*
X234098Y-510702D01*
X234998Y-510835D01*
X235798Y-510702D01*
X236598Y-510035D01*
X237098Y-509235D01*
X237198Y-508435D01*
X236998Y-507502D01*
X236298Y-506835D01*
X235598Y-506568D01*
X234698D01*
G01X235598D02*
X236198Y-506168D01*
X236698Y-505502D01*
X236898Y-504702D01*
X236698Y-503902D01*
X236198Y-503235D01*
X235298Y-502835D01*
X234398Y-502968D01*
X233498Y-503502D01*
G01X238898Y-485835D02*
Y-477835D01*
X237698Y-479435D01*
G01Y-485835D02*
X240098D01*
G01X246898Y-477835D02*
X246098Y-478102D01*
X245498Y-478768D01*
X245098Y-479568D01*
X244798Y-480635D01*
X244698Y-481835D01*
X244798Y-483035D01*
X245098Y-484102D01*
X245498Y-484902D01*
X246098Y-485568D01*
X246898Y-485835D01*
X247698Y-485568D01*
X248298Y-484902D01*
X248698Y-484102D01*
X248998Y-483035D01*
X249098Y-481835D01*
X248998Y-480635D01*
X248698Y-479568D01*
X248298Y-478768D01*
X247698Y-478102D01*
X246898Y-477835D01*
G01X311998Y-529168D02*
X312598Y-528368D01*
X313298Y-527968D01*
X314098Y-527835D01*
X315098Y-528102D01*
X315798Y-528768D01*
X315998Y-529568D01*
X315898Y-530369D01*
X315498Y-531035D01*
X313498Y-532368D01*
X312598Y-533302D01*
X311998Y-534635D01*
X311798Y-535835D01*
X315998D01*
G01X321898Y-527835D02*
X321098Y-528102D01*
X320498Y-528768D01*
X320098Y-529568D01*
X319798Y-530635D01*
X319698Y-531835D01*
X319798Y-533035D01*
X320098Y-534102D01*
X320498Y-534902D01*
X321098Y-535568D01*
X321898Y-535835D01*
X322698Y-535568D01*
X323298Y-534902D01*
X323698Y-534102D01*
X323998Y-533035D01*
X324098Y-531835D01*
X323998Y-530635D01*
X323698Y-529568D01*
X323298Y-528768D01*
X322698Y-528102D01*
X321898Y-527835D01*
G01X327998Y-529168D02*
X328598Y-528368D01*
X329298Y-527968D01*
X330098Y-527835D01*
X331098Y-528102D01*
X331798Y-528768D01*
X331998Y-529568D01*
X331898Y-530369D01*
X331498Y-531035D01*
X329498Y-532368D01*
X328598Y-533302D01*
X327998Y-534635D01*
X327798Y-535835D01*
X331998D01*
G01X335698Y-534235D02*
X336298Y-535168D01*
X337098Y-535702D01*
X337998Y-535835D01*
X338798Y-535702D01*
X339598Y-535035D01*
X340098Y-534235D01*
X340198Y-533435D01*
X339998Y-532502D01*
X339298Y-531835D01*
X338598Y-531568D01*
X337698D01*
G01X338598D02*
X339198Y-531168D01*
X339698Y-530502D01*
X339898Y-529702D01*
X339698Y-528902D01*
X339198Y-528235D01*
X338298Y-527835D01*
X337398Y-527968D01*
X336498Y-528502D01*
G01X344098Y-536102D02*
X347698Y-527835D01*
G01X353898D02*
X353098Y-528102D01*
X352498Y-528768D01*
X352098Y-529568D01*
X351798Y-530635D01*
X351698Y-531835D01*
X351798Y-533035D01*
X352098Y-534102D01*
X352498Y-534902D01*
X353098Y-535568D01*
X353898Y-535835D01*
X354698Y-535568D01*
X355298Y-534902D01*
X355698Y-534102D01*
X355998Y-533035D01*
X356098Y-531835D01*
X355998Y-530635D01*
X355698Y-529568D01*
X355298Y-528768D01*
X354698Y-528102D01*
X353898Y-527835D01*
G01X361898Y-535835D02*
Y-527835D01*
X360698Y-529435D01*
G01Y-535835D02*
X363098D01*
G01X368098Y-536102D02*
X371698Y-527835D01*
G01X377898D02*
X377098Y-528102D01*
X376498Y-528768D01*
X376098Y-529568D01*
X375798Y-530635D01*
X375698Y-531835D01*
X375798Y-533035D01*
X376098Y-534102D01*
X376498Y-534902D01*
X377098Y-535568D01*
X377898Y-535835D01*
X378698Y-535568D01*
X379298Y-534902D01*
X379698Y-534102D01*
X379998Y-533035D01*
X380098Y-531835D01*
X379998Y-530635D01*
X379698Y-529568D01*
X379298Y-528768D01*
X378698Y-528102D01*
X377898Y-527835D01*
G01X384198Y-534902D02*
X384898Y-535568D01*
X385698Y-535835D01*
X386498Y-535568D01*
X387198Y-534769D01*
X387698Y-533568D01*
X387898Y-532368D01*
Y-530902D01*
X387698Y-529702D01*
X387198Y-528635D01*
X386598Y-528102D01*
X385898Y-527835D01*
X385098Y-528102D01*
X384498Y-528635D01*
X384098Y-529435D01*
X383898Y-530502D01*
X384098Y-531435D01*
X384598Y-532368D01*
X385198Y-532902D01*
X385898Y-533035D01*
X386698Y-532769D01*
X387298Y-532102D01*
X387898Y-530902D01*
G01X311698Y-510835D02*
Y-502835D01*
X313698D01*
X314498Y-503235D01*
X315098Y-503768D01*
X315598Y-504568D01*
X315998Y-505502D01*
X316098Y-506835D01*
X315998Y-508168D01*
X315598Y-509102D01*
X315098Y-509902D01*
X314498Y-510435D01*
X313698Y-510835D01*
X311698D01*
G01X319398D02*
X321898Y-502835D01*
X324398Y-510835D01*
G01X323498Y-508035D02*
X320298D01*
G01X329898Y-502835D02*
X329098Y-503102D01*
X328498Y-503768D01*
X328098Y-504568D01*
X327798Y-505635D01*
X327698Y-506835D01*
X327798Y-508035D01*
X328098Y-509102D01*
X328498Y-509902D01*
X329098Y-510568D01*
X329898Y-510835D01*
X330698Y-510568D01*
X331298Y-509902D01*
X331698Y-509102D01*
X331998Y-508035D01*
X332098Y-506835D01*
X331998Y-505635D01*
X331698Y-504568D01*
X331298Y-503768D01*
X330698Y-503102D01*
X329898Y-502835D01*
G01X335998Y-510835D02*
Y-502835D01*
X339798D01*
G01X338398Y-506702D02*
X335998D01*
G01X345898Y-502835D02*
X345098Y-503102D01*
X344498Y-503768D01*
X344098Y-504568D01*
X343798Y-505635D01*
X343698Y-506835D01*
X343798Y-508035D01*
X344098Y-509102D01*
X344498Y-509902D01*
X345098Y-510568D01*
X345898Y-510835D01*
X346698Y-510568D01*
X347298Y-509902D01*
X347698Y-509102D01*
X347998Y-508035D01*
X348098Y-506835D01*
X347998Y-505635D01*
X347698Y-504568D01*
X347298Y-503768D01*
X346698Y-503102D01*
X345898Y-502835D01*
G01X353898D02*
Y-510835D01*
G01X351598Y-502835D02*
X356198D01*
G01X363898Y-510835D02*
X359898D01*
Y-502835D01*
X363898D01*
G01X362298Y-506702D02*
X359898D01*
G01X370698Y-506568D02*
X371098Y-506168D01*
X371398Y-505502D01*
X371598Y-504568D01*
X371398Y-503768D01*
X370998Y-503235D01*
X370298Y-502835D01*
X367598D01*
Y-510835D01*
X370898D01*
X371598Y-510302D01*
X371998Y-509502D01*
X372198Y-508568D01*
X371998Y-507635D01*
X371398Y-506835D01*
X370698Y-506568D01*
X367598D01*
G01X376698Y-502835D02*
X379098D01*
G01X377898D02*
Y-510835D01*
G01X376698D02*
X379098D01*
G01X383998D02*
Y-502835D01*
X387798D01*
G01X386398Y-506702D02*
X383998D01*
G01X393898Y-502835D02*
X393098Y-503102D01*
X392498Y-503768D01*
X392098Y-504568D01*
X391798Y-505635D01*
X391698Y-506835D01*
X391798Y-508035D01*
X392098Y-509102D01*
X392498Y-509902D01*
X393098Y-510568D01*
X393898Y-510835D01*
X394698Y-510568D01*
X395298Y-509902D01*
X395698Y-509102D01*
X395998Y-508035D01*
X396098Y-506835D01*
X395998Y-505635D01*
X395698Y-504568D01*
X395298Y-503768D01*
X394698Y-503102D01*
X393898Y-502835D01*
G01X329498Y-485835D02*
Y-477835D01*
X333298D01*
G01X331898Y-481702D02*
X329498D01*
G01X339398Y-477835D02*
X338598Y-478102D01*
X337998Y-478768D01*
X337598Y-479568D01*
X337298Y-480635D01*
X337198Y-481835D01*
X337298Y-483035D01*
X337598Y-484102D01*
X337998Y-484902D01*
X338598Y-485568D01*
X339398Y-485835D01*
X340198Y-485568D01*
X340798Y-484902D01*
X341198Y-484102D01*
X341498Y-483035D01*
X341598Y-481835D01*
X341498Y-480635D01*
X341198Y-479568D01*
X340798Y-478768D01*
X340198Y-478102D01*
X339398Y-477835D01*
G01X347398D02*
Y-485835D01*
G01X345098Y-477835D02*
X349698D01*
G01X352398Y-488502D02*
X358398D01*
G01X361898Y-482235D02*
X365098D01*
X364798Y-481302D01*
X364298Y-480768D01*
X363598Y-480502D01*
X362898Y-480635D01*
X362298Y-481035D01*
X361898Y-481968D01*
X361698Y-482769D01*
Y-483568D01*
X361898Y-484368D01*
X362398Y-485168D01*
X362998Y-485702D01*
X363698Y-485835D01*
X364398Y-485568D01*
X365098Y-484769D01*
G01X369898Y-480502D02*
X372898Y-485835D01*
G01Y-480502D02*
X369898Y-485835D01*
G01X377598Y-488502D02*
Y-480502D01*
G01Y-481702D02*
X378098Y-481035D01*
X378598Y-480635D01*
X379398Y-480502D01*
X380098Y-480635D01*
X380798Y-481302D01*
X381098Y-482235D01*
X381198Y-483168D01*
X381098Y-484102D01*
X380798Y-485035D01*
X380198Y-485568D01*
X379398Y-485835D01*
X378698Y-485702D01*
X377998Y-485302D01*
X377598Y-484769D01*
G01X389198Y-485835D02*
Y-480502D01*
G01Y-481435D02*
X388798Y-480902D01*
X388198Y-480635D01*
X387498Y-480502D01*
X386798Y-480768D01*
X386198Y-481302D01*
X385798Y-482102D01*
X385598Y-483168D01*
X385798Y-484235D01*
X386198Y-485035D01*
X386798Y-485568D01*
X387498Y-485835D01*
X388198Y-485702D01*
X388798Y-485302D01*
X389198Y-484769D01*
G01X393698Y-485835D02*
Y-480502D01*
G01Y-481835D02*
X394098Y-481168D01*
X394698Y-480635D01*
X395498Y-480502D01*
X396198Y-480635D01*
X396798Y-481168D01*
X397098Y-482102D01*
Y-485835D01*
G01X405198Y-477835D02*
Y-485835D01*
G01Y-484635D02*
X404798Y-485302D01*
X404198Y-485702D01*
X403498Y-485835D01*
X402698Y-485568D01*
X402098Y-484902D01*
X401698Y-484102D01*
X401598Y-483168D01*
X401698Y-482235D01*
X402098Y-481435D01*
X402698Y-480768D01*
X403498Y-480502D01*
X404198Y-480635D01*
X404698Y-480902D01*
X405198Y-481435D01*
G01X409898Y-482235D02*
X413098D01*
X412798Y-481302D01*
X412298Y-480768D01*
X411598Y-480502D01*
X410898Y-480635D01*
X410298Y-481035D01*
X409898Y-481968D01*
X409698Y-482769D01*
Y-483568D01*
X409898Y-484368D01*
X410398Y-485168D01*
X410998Y-485702D01*
X411698Y-485835D01*
X412398Y-485568D01*
X413098Y-484769D01*
G01X417998Y-485835D02*
Y-480502D01*
G01Y-481568D02*
X418498Y-481035D01*
X418998Y-480635D01*
X419698Y-480502D01*
X420198Y-480635D01*
X420798Y-481035D01*
G01X424398Y-488502D02*
X430398D01*
G01X433598Y-485835D02*
Y-477835D01*
G01Y-481835D02*
X434098Y-481035D01*
X434698Y-480635D01*
X435298Y-480502D01*
X436198Y-480768D01*
X436798Y-481302D01*
X437198Y-482235D01*
Y-483302D01*
X436998Y-484368D01*
X436598Y-485168D01*
X435898Y-485702D01*
X435298Y-485835D01*
X434698Y-485702D01*
X434098Y-485302D01*
X433598Y-484635D01*
G01X445198Y-477835D02*
Y-485835D01*
G01Y-484635D02*
X444798Y-485302D01*
X444198Y-485702D01*
X443498Y-485835D01*
X442698Y-485568D01*
X442098Y-484902D01*
X441698Y-484102D01*
X441598Y-483168D01*
X441698Y-482235D01*
X442098Y-481435D01*
X442698Y-480768D01*
X443498Y-480502D01*
X444198Y-480635D01*
X444698Y-480902D01*
X445198Y-481435D01*
G01X400398Y-538835D02*
Y-530835D01*
X399198Y-532435D01*
G01Y-538835D02*
X401598D01*
G01X406498Y-535502D02*
X407198Y-534568D01*
X407798Y-534035D01*
X408598Y-533768D01*
X409298Y-534035D01*
X409798Y-534568D01*
X410198Y-535368D01*
X410298Y-536302D01*
X410198Y-537102D01*
X409798Y-537902D01*
X409198Y-538568D01*
X408498Y-538835D01*
X407698Y-538568D01*
X406998Y-537769D01*
X406598Y-536568D01*
X406498Y-535235D01*
X406698Y-533502D01*
X406998Y-532568D01*
X407498Y-531635D01*
X408198Y-530968D01*
X408898Y-530835D01*
X409598Y-531102D01*
X410098Y-531768D01*
G01X416398Y-539102D02*
X416198Y-538968D01*
Y-538702D01*
X416398Y-538568D01*
X416598Y-538702D01*
Y-538968D01*
X416398Y-539102D01*
G01X422498Y-535502D02*
X423198Y-534568D01*
X423798Y-534035D01*
X424598Y-533768D01*
X425298Y-534035D01*
X425798Y-534568D01*
X426198Y-535368D01*
X426298Y-536302D01*
X426198Y-537102D01*
X425798Y-537902D01*
X425198Y-538568D01*
X424498Y-538835D01*
X423698Y-538568D01*
X422998Y-537769D01*
X422598Y-536568D01*
X422498Y-535235D01*
X422698Y-533502D01*
X422998Y-532568D01*
X423498Y-531635D01*
X424198Y-530968D01*
X424898Y-530835D01*
X425598Y-531102D01*
X426098Y-531768D01*
G01X445398Y-538835D02*
Y-530835D01*
X444198Y-532435D01*
G01Y-538835D02*
X446598D01*
G01X453198D02*
X453398Y-537102D01*
X453698Y-535635D01*
X454098Y-534302D01*
X454598Y-532835D01*
X455398Y-530835D01*
X451398D01*
G01X461398Y-539102D02*
X461198Y-538968D01*
Y-538702D01*
X461398Y-538568D01*
X461598Y-538702D01*
Y-538968D01*
X461398Y-539102D01*
G01X467498Y-532168D02*
X468098Y-531368D01*
X468798Y-530968D01*
X469598Y-530835D01*
X470598Y-531102D01*
X471298Y-531768D01*
X471498Y-532568D01*
X471398Y-533369D01*
X470998Y-534035D01*
X468998Y-535368D01*
X468098Y-536302D01*
X467498Y-537635D01*
X467298Y-538835D01*
X471498D01*
G01X465498Y-513835D02*
Y-505835D01*
X469298D01*
G01X467898Y-509702D02*
X465498D01*
G54D22*
X420661Y1119422D03*
X423141Y1113822D03*
Y1119422D03*
X418181Y1113822D03*
Y1119422D03*
X420661Y1113822D03*
X455269Y1119422D03*
X450309Y1113822D03*
Y1119422D03*
X452789Y1113822D03*
Y1119422D03*
X455269Y1113822D03*
X488728Y1119422D03*
X483768Y1113822D03*
X486248D03*
Y1119422D03*
X483768D03*
X488728Y1113822D03*
X518376D03*
Y1119422D03*
X520856Y1113822D03*
Y1119422D03*
X515896Y1113822D03*
Y1119422D03*
X1332355Y1113822D03*
Y1119422D03*
X1334835Y1113822D03*
Y1119422D03*
X1337315Y1113822D03*
Y1119422D03*
X1366963D03*
Y1113822D03*
X1364483Y1119422D03*
Y1113822D03*
X1369443Y1119422D03*
Y1113822D03*
X1397942Y1119422D03*
X1400422D03*
Y1113822D03*
X1397942D03*
X1402902Y1119422D03*
Y1113822D03*
X1432550Y1119422D03*
Y1113822D03*
X1430070Y1119422D03*
Y1113822D03*
X1435030Y1119422D03*
Y1113822D03*
G54D13*
X51043Y150197D03*
X153405D03*
X190325Y455492D03*
Y503760D03*
Y583957D03*
Y636752D03*
X255767Y150197D03*
X279360Y368760D03*
Y421555D03*
Y501752D03*
Y550020D03*
X358129Y150197D03*
X508130D03*
X610492D03*
X647411Y455492D03*
Y503760D03*
Y583957D03*
Y636752D03*
X712854Y150197D03*
X736446Y368760D03*
Y421555D03*
Y501752D03*
Y550020D03*
X815216Y150197D03*
X965216D03*
X1067578D03*
X1104498Y455492D03*
Y503760D03*
Y583957D03*
Y636752D03*
X1169940Y150197D03*
X1193533Y368760D03*
Y421555D03*
Y501752D03*
Y550020D03*
X1272302Y150197D03*
X1422303D03*
X1524665D03*
X1561585Y455492D03*
Y503760D03*
Y583957D03*
Y636752D03*
X1627027Y150197D03*
X1650620Y501752D03*
Y550020D03*
X1729389Y150197D03*
G54D32*
G01X255909Y1542043D02*
X246352Y1551600D01*
X208900D01*
X208400Y1552100D01*
Y1630300D01*
X199500Y1639200D01*
X180100D01*
X174100Y1633200D01*
X120680D01*
X109882Y1622402D01*
G01X225765Y1471985D02*
X219701Y1478049D01*
X216233D01*
X208000Y1469816D01*
Y1453601D01*
X199599Y1445200D01*
X126060D01*
X118543Y1452717D01*
G01X127205Y1622402D02*
X135546Y1630743D01*
X177234D01*
X181528Y1635037D01*
X199226D01*
X205547Y1628716D01*
Y1550862D01*
X207360Y1549049D01*
X232227D01*
X239949Y1541327D01*
G01X148061Y378600D02*
X154659Y385198D01*
Y441021D01*
X146473Y449207D01*
Y457008D01*
X148176Y458711D01*
G01X235790Y754332D02*
X241412Y748710D01*
Y732504D01*
X213200Y704292D01*
Y583299D01*
X207550Y577649D01*
Y566250D01*
X204800Y563500D01*
X199156D01*
X194001Y568655D01*
X185555D01*
X166210Y549310D01*
Y479545D01*
X145376Y458711D01*
G01X224780Y1478149D02*
X222201Y1480728D01*
X216512D01*
X206052Y1470268D01*
Y1454446D01*
X198606Y1447000D01*
X141583D01*
X135866Y1452717D01*
G01X217985Y1483055D02*
X217460Y1483580D01*
X216854D01*
X204222Y1470948D01*
Y1455397D01*
X197425Y1448600D01*
X157306D01*
X153189Y1452717D01*
G01X221899Y1488800D02*
X219701D01*
X202330Y1471429D01*
Y1456386D01*
X196344Y1450400D01*
X172829D01*
X170512Y1452717D01*
G01X226135Y1502442D02*
X223845Y1504732D01*
X222205D01*
X219889Y1507048D01*
X208723D01*
X193331Y1522440D01*
X186779D01*
X184000Y1519661D01*
Y1494158D01*
X179173Y1489331D01*
G01X230758Y1505046D02*
X228716D01*
X224676Y1509086D01*
X209314D01*
X194000Y1524400D01*
X185500D01*
X181943Y1520843D01*
Y1497219D01*
X179173Y1494449D01*
G01X226971Y1522578D02*
X224562D01*
X210468Y1536672D01*
X202828D01*
X194000Y1545500D01*
Y1583099D01*
X188882Y1588217D01*
X182649D01*
X179173Y1591693D01*
G01Y1607048D02*
X183500Y1611375D01*
Y1624500D01*
X185456Y1626456D01*
X195772D01*
X197706Y1624522D01*
Y1547894D01*
X205659Y1539941D01*
X222119D01*
G01X179173Y1596811D02*
X185000Y1602638D01*
Y1623563D01*
X186372Y1624935D01*
X194464D01*
X195876Y1623523D01*
Y1546983D01*
X204748Y1538111D01*
X212667D01*
X219981Y1530797D01*
G01X179173Y1612166D02*
X181875Y1614868D01*
Y1625476D01*
X184516Y1628117D01*
X196718D01*
X199900Y1624935D01*
Y1548501D01*
X206395Y1542006D01*
X226692D01*
X227882Y1540816D01*
G01X179173Y1622402D02*
Y1625673D01*
X183500Y1630000D01*
X197599D01*
X202000Y1625599D01*
Y1549300D01*
X207441Y1543859D01*
X229646D01*
X233753Y1539752D01*
G01X217614Y1489671D02*
X200400Y1472457D01*
Y1457103D01*
X196014Y1452717D01*
X187835D01*
G01X218021Y1494724D02*
X217299Y1495446D01*
X189619D01*
X187835Y1493662D01*
G01Y1498780D02*
X188173Y1498442D01*
X222843D01*
G01X223322Y1518578D02*
Y1520391D01*
X208813Y1534900D01*
X201801D01*
X192400Y1544301D01*
Y1581223D01*
X187835Y1585788D01*
G01X226971Y1514578D02*
X225430Y1516119D01*
X221097D01*
X219917Y1517299D01*
X217401D01*
X190900Y1543800D01*
Y1580121D01*
X190351Y1580670D01*
X187835D01*
G01X246102Y656321D02*
X225640Y635859D01*
Y574339D01*
X220900Y569599D01*
Y525400D01*
X225600Y520700D01*
Y462168D01*
X212432Y449000D01*
X203301D01*
X201190Y446889D01*
Y387807D01*
X204675Y384322D01*
Y382109D01*
G01X248556Y824003D02*
Y815255D01*
X245200Y811899D01*
Y730800D01*
X217200Y702800D01*
Y580300D01*
X211882Y574982D01*
Y564382D01*
X206417Y558917D01*
X204674D01*
G01X255289Y824340D02*
X252578Y827051D01*
X247992D01*
X243299Y822358D01*
Y731620D01*
X215276Y703597D01*
Y580961D01*
X209971Y575656D01*
Y565171D01*
X206220Y561420D01*
X204674D01*
G01X205941Y668934D02*
X211591Y663284D01*
Y583843D01*
X205685Y577937D01*
X200495D01*
G01X225000Y540500D02*
X222961Y538461D01*
Y526040D01*
X227331Y521670D01*
Y460982D01*
X221375Y455026D01*
Y455024D01*
G01X254512Y438323D02*
X252602D01*
X229197Y461728D01*
Y522423D01*
X225500Y526120D01*
Y530000D01*
G01X352401Y1612166D02*
X355450Y1615215D01*
Y1623249D01*
X341209Y1637490D01*
X277633D01*
X265921Y1625778D01*
Y1541540D01*
X253481Y1529100D01*
X242699D01*
X240099Y1526500D01*
X231727D01*
X227552Y1530675D01*
G01X232622Y1531104D02*
X229826Y1533900D01*
X226299D01*
X225300Y1532901D01*
Y1528601D01*
X229301Y1524600D01*
X241500D01*
X243800Y1526900D01*
X253807D01*
X254197Y1527290D01*
X254231D01*
X267731Y1540790D01*
Y1624732D01*
X278679Y1635680D01*
X339123D01*
X352401Y1622402D01*
G01X245362Y546712D02*
X247536Y544538D01*
Y470392D01*
X249125Y468803D01*
Y465874D01*
G01X243278Y618288D02*
Y631879D01*
X245142Y633743D01*
Y642796D01*
X250102Y647756D01*
Y656321D01*
G01X243535Y1511473D02*
X253473D01*
X278151Y1536151D01*
Y1617443D01*
X283110Y1622402D01*
G01X237633Y1511909D02*
X239891Y1514167D01*
X253466D01*
X276181Y1536882D01*
Y1619449D01*
X281509Y1624777D01*
X298058D01*
X300433Y1622402D01*
G01X240808Y1519942D02*
X254043D01*
X272421Y1538320D01*
Y1621722D01*
X280036Y1629337D01*
X328143D01*
X335078Y1622402D01*
G01X235687Y1522578D02*
X244484D01*
X245362Y1521700D01*
X253700D01*
X270951Y1538951D01*
Y1622651D01*
X279106Y1630806D01*
X339054D01*
X346505Y1623355D01*
Y1593594D01*
X348406Y1591693D01*
X352401D01*
G01Y1607048D02*
X357000Y1611647D01*
Y1624900D01*
X343000Y1638900D01*
X277048D01*
X264511Y1626363D01*
Y1543210D01*
X256401Y1535100D01*
X244076D01*
X237580Y1528604D01*
G01X245500Y1517033D02*
X253733D01*
X274251Y1537551D01*
Y1620550D01*
X280708Y1627007D01*
X313151D01*
X317756Y1622402D01*
G01X352401Y1596811D02*
X348989D01*
X348100Y1597700D01*
Y1623755D01*
X339639Y1632216D01*
X278017D01*
X269541Y1623740D01*
Y1540040D01*
X254980Y1525479D01*
X254946D01*
X253704Y1524237D01*
X245937D01*
G01X370415Y766108D02*
Y767692D01*
X374023Y771300D01*
X390162D01*
X393462Y774600D01*
X434000D01*
X486200Y826800D01*
X514100D01*
X525700Y838400D01*
X532800D01*
X537300Y842900D01*
G01X459645Y509486D02*
X458000Y507841D01*
Y475665D01*
X451144Y468809D01*
G01X456339Y1622402D02*
X465837Y1631900D01*
X538000D01*
X554600Y1615300D01*
Y1551899D01*
X555199Y1551300D01*
X588462D01*
X593548Y1546214D01*
X595809D01*
G01X481485Y439900D02*
X475700Y445685D01*
Y492527D01*
X468558Y499669D01*
G01X581803Y1493687D02*
Y1488402D01*
X537101Y1443700D01*
X474017D01*
X465000Y1452717D01*
G01X473662Y1622402D02*
X481514Y1630254D01*
X537233D01*
X553000Y1614487D01*
Y1550899D01*
X554099Y1549800D01*
X587344D01*
X591809Y1545335D01*
Y1542407D01*
G01X578859Y1497758D02*
Y1488146D01*
X536495Y1445782D01*
X489258D01*
X482323Y1452717D01*
G01X499646D02*
X504751Y1447612D01*
X535912D01*
X576385Y1488085D01*
Y1498241D01*
X579831Y1501687D01*
X580914D01*
X582027Y1502800D01*
G01X587809Y1545854D02*
X585463Y1548200D01*
X553478D01*
X551012Y1550666D01*
Y1613994D01*
X536506Y1628500D01*
X497083D01*
X490985Y1622402D01*
G01X577931Y1505687D02*
Y1503638D01*
X574335Y1500042D01*
Y1488684D01*
X535393Y1449742D01*
X519944D01*
X516969Y1452717D01*
G01X508307Y1622402D02*
X512505Y1626600D01*
X536159D01*
X549282Y1613477D01*
Y1550117D01*
X552699Y1546700D01*
X582104D01*
X583809Y1544995D01*
Y1541607D01*
G01X578271Y763556D02*
X571542Y770285D01*
Y777489D01*
X575682Y781629D01*
Y788819D01*
X570500Y794001D01*
Y817500D01*
X564300Y823700D01*
Y828100D01*
X565804Y829604D01*
Y840804D01*
X563580Y843028D01*
Y850719D01*
X554102Y860197D01*
X553271D01*
X548603Y855529D01*
X547691D01*
X546570Y856650D01*
Y857400D01*
X551291Y862121D01*
Y862871D01*
X550252Y863910D01*
X549502D01*
X542419Y856827D01*
X540873D01*
X533468Y864232D01*
Y878533D01*
G01X583102Y767137D02*
Y776161D01*
X577839Y781424D01*
Y790057D01*
X573100Y794796D01*
Y825700D01*
X568200Y830600D01*
Y841527D01*
X565800Y843927D01*
Y852000D01*
X550813Y866987D01*
X549182D01*
X542616Y860421D01*
X541866D01*
X540827Y861460D01*
Y862210D01*
X545955Y867338D01*
Y868088D01*
X544916Y869127D01*
X544166D01*
X538606Y863567D01*
X537856D01*
X536817Y864606D01*
Y865356D01*
X542377Y870916D01*
Y871666D01*
X540968Y873075D01*
Y878360D01*
G01X528975Y898346D02*
Y891600D01*
X529475Y891100D01*
X531658D01*
X532158Y891600D01*
Y894051D01*
X532688Y894581D01*
X534158D01*
X534688Y894051D01*
Y891590D01*
X535278Y891000D01*
X540616D01*
X549984Y881632D01*
X551490Y877998D01*
Y870209D01*
X569500Y852199D01*
X570900D01*
X575366Y847733D01*
X578103Y841129D01*
X577816Y840438D01*
X576666Y839961D01*
X576379Y839270D01*
X576943Y837910D01*
X577635Y837623D01*
X578785Y838100D01*
X579476Y837813D01*
X586326Y821275D01*
Y811480D01*
X580633Y805787D01*
Y793667D01*
X585200Y789100D01*
X587423D01*
X588659Y790336D01*
G01X537279Y897943D02*
X538057D01*
X551717Y884283D01*
X554126Y878467D01*
Y871374D01*
X569700Y855800D01*
X571000D01*
X578700Y848100D01*
Y846800D01*
X589218Y836282D01*
X593070Y826983D01*
Y789567D01*
X590284Y782842D01*
X585912Y778470D01*
G01X534292Y1452717D02*
X572137Y1490562D01*
Y1503401D01*
X578423Y1509687D01*
X581803D01*
G01X572507Y1541375D02*
Y1538149D01*
X567539Y1533181D01*
X550718D01*
X537300Y1546599D01*
Y1582780D01*
X534292Y1585788D01*
G01X565400Y1535100D02*
X565346Y1535046D01*
X551154D01*
X539200Y1547000D01*
Y1590099D01*
X535599Y1593700D01*
X527637D01*
X525630Y1591693D01*
G01Y1607048D02*
X527682Y1609100D01*
X536139D01*
X542900Y1602339D01*
Y1548300D01*
X552800Y1538400D01*
X560923D01*
X563968Y1541445D01*
G01X568279Y1538438D02*
X565438D01*
X563500Y1536500D01*
X551799D01*
X541000Y1547299D01*
Y1593200D01*
X535700Y1598500D01*
X527319D01*
X525630Y1596811D01*
G01Y1612166D02*
X528007D01*
X529741Y1613900D01*
X536122D01*
X545100Y1604922D01*
Y1548901D01*
X553430Y1540571D01*
X560371D01*
X563813Y1544013D01*
X577571D01*
G01X557584Y1543411D02*
X553373D01*
X547200Y1549584D01*
Y1612912D01*
X535548Y1624564D01*
X527792D01*
X525630Y1622402D01*
G01X570796Y1530309D02*
X572605Y1528500D01*
X576323D01*
X577742Y1529919D01*
Y1532964D01*
X581378Y1536600D01*
X585100D01*
X586800Y1538300D01*
X597301D01*
X611300Y1552299D01*
Y1618601D01*
X624496Y1631797D01*
X696104D01*
X703900Y1624001D01*
Y1599678D01*
X701033Y1596811D01*
X698858D01*
G01X579809Y1528163D02*
Y1532510D01*
X582399Y1535100D01*
X585799D01*
X587399Y1536700D01*
X598500D01*
X613000Y1551200D01*
Y1617820D01*
X625347Y1630167D01*
X695469D01*
X702207Y1623429D01*
Y1615515D01*
X698858Y1612166D01*
G01X575809Y1532912D02*
Y1534408D01*
X579701Y1538300D01*
X584501D01*
X586301Y1540100D01*
X596800D01*
X609600Y1552900D01*
Y1618900D01*
X624200Y1633500D01*
X699700D01*
X710500Y1622700D01*
Y1588768D01*
X707520Y1585788D01*
G01X583809Y1533025D02*
X586210D01*
X588185Y1535000D01*
X599199D01*
X614600Y1550401D01*
Y1616773D01*
X626164Y1628337D01*
X675600D01*
X681535Y1622402D01*
G01X605147Y378600D02*
X611745Y385198D01*
Y441021D01*
X603559Y449207D01*
Y457008D01*
X605262Y458711D01*
G01X602462D02*
X623297Y479546D01*
Y584275D01*
X630276Y591254D01*
Y630214D01*
X639485Y676509D01*
X683990Y783952D01*
X722306Y822268D01*
Y866305D01*
X720499Y868112D01*
Y870914D01*
X722650Y873065D01*
Y891086D01*
X724707Y893143D01*
G01X613738Y1546507D02*
Y1547339D01*
X617800Y1551401D01*
Y1614811D01*
X627866Y1624877D01*
X644415D01*
X646890Y1622402D01*
G01X621727Y1556800D02*
Y1614562D01*
X629567Y1622402D01*
G01X705390Y655789D02*
X702656D01*
X675200Y628333D01*
Y568816D01*
X677300Y566716D01*
Y464200D01*
X673962Y460862D01*
X672563D01*
X658300Y446599D01*
Y385570D01*
X661761Y382109D01*
G01X661760Y561420D02*
X663020D01*
X671320Y569720D01*
Y700420D01*
X724551Y753651D01*
Y885450D01*
X728503Y889402D01*
Y891692D01*
G01X661760Y558917D02*
X663244D01*
X673200Y568873D01*
Y698344D01*
X726588Y751732D01*
Y884549D01*
X728692Y886653D01*
G01X657581Y577937D02*
X658785Y579141D01*
X663975D01*
X669409Y584575D01*
Y702052D01*
X692478Y725121D01*
Y730641D01*
G01X682086Y540500D02*
X678961Y537375D01*
Y456481D01*
X678461Y455981D01*
G01X682586Y530000D02*
X681000Y528414D01*
Y468921D01*
X711598Y438323D01*
G01X702448Y546712D02*
Y546495D01*
X706211Y542732D01*
Y465874D01*
G01X842476Y482382D02*
X842261Y482167D01*
Y478639D01*
X845598Y475302D01*
Y454250D01*
X830214Y438866D01*
X811604D01*
X802136Y448334D01*
G01X943891Y1306608D02*
Y1276065D01*
X939556Y1271730D01*
X921329D01*
X917286Y1267687D01*
Y1112790D01*
X905149Y1100653D01*
Y1074784D01*
X908800Y1071133D01*
Y1032100D01*
X902000Y1025300D01*
Y1014701D01*
X884600Y997301D01*
Y959801D01*
X862079Y937280D01*
Y931999D01*
X859359Y929279D01*
Y905759D01*
X855187Y901587D01*
X837727D01*
X834640Y898500D01*
X830063D01*
G01X848045Y1019310D02*
X846690D01*
X845697Y1020303D01*
Y1029359D01*
X854116Y1037778D01*
X859012Y1049599D01*
Y1091843D01*
X830700Y1120155D01*
Y1235900D01*
X845900Y1251100D01*
Y1268500D01*
X854400Y1277000D01*
X881100D01*
X898000Y1293900D01*
Y1314700D01*
X921100Y1337800D01*
X935851D01*
X947308Y1326343D01*
Y1325035D01*
G01X941872Y440942D02*
X944737Y443807D01*
Y466191D01*
X935088Y475840D01*
Y480823D01*
X914191Y501720D01*
X852448D01*
X842476Y491748D01*
Y482382D01*
G01X944207Y1320739D02*
Y1324574D01*
X934071Y1334710D01*
X922110D01*
X900900Y1313500D01*
Y1292700D01*
X882100Y1273900D01*
X855500D01*
X848900Y1267300D01*
Y1250055D01*
X833700Y1234855D01*
Y1121400D01*
X862000Y1093100D01*
Y1048505D01*
X853242Y1027362D01*
X848070Y1022190D01*
G01X908700Y1316300D02*
Y1296400D01*
X883300Y1271000D01*
X856800D01*
X851867Y1266067D01*
Y1248861D01*
X836633Y1233627D01*
Y1122468D01*
X864900Y1094201D01*
Y1047908D01*
X856797Y1028345D01*
Y1017221D01*
X863334Y1010684D01*
Y1009393D01*
G01X981857Y605637D02*
X980494Y607000D01*
Y607546D01*
X977371Y610669D01*
X974351D01*
X970620Y614400D01*
X955001D01*
X952359Y611758D01*
Y608908D01*
X936459Y593008D01*
Y576136D01*
X939347Y573248D01*
Y560877D01*
X929848Y551378D01*
Y510299D01*
X939347Y500800D01*
Y478624D01*
X956483Y461488D01*
Y454929D01*
X954950Y453396D01*
Y449195D01*
X956482Y447663D01*
Y423758D01*
X945199Y412475D01*
X932863D01*
X914888Y394500D01*
X909645D01*
X900080Y384935D01*
Y382587D01*
X897560Y380067D01*
X871581D01*
X870404Y381244D01*
Y385829D01*
X868962Y387271D01*
X866237D01*
X864086Y385120D01*
Y384000D01*
G01X872126Y934766D02*
Y931964D01*
X869596Y929434D01*
Y881871D01*
X851184Y863459D01*
G01X867096Y935963D02*
X866166Y935033D01*
Y930109D01*
X867096Y929179D01*
Y882286D01*
X852269Y867459D01*
X851184D01*
G01X855524Y898505D02*
X862870Y905851D01*
Y906930D01*
X861242Y908558D01*
Y927796D01*
X864100Y930654D01*
Y936499D01*
X886495Y958894D01*
Y995995D01*
X904100Y1013600D01*
Y1024799D01*
X910724Y1031423D01*
Y1102425D01*
X919300Y1111001D01*
Y1267006D01*
X921936Y1269642D01*
X942023D01*
X948259Y1275878D01*
Y1295965D01*
G01X868086Y373750D02*
X870732Y376396D01*
X899281D01*
X904313Y381428D01*
Y383778D01*
X911335Y390800D01*
X916932D01*
X934546Y408414D01*
X946882D01*
X960833Y422365D01*
Y465634D01*
X956500Y469967D01*
X953365D01*
X943408Y479924D01*
Y502483D01*
X933909Y511982D01*
Y549695D01*
X943408Y559194D01*
Y574931D01*
X940520Y577819D01*
Y590921D01*
X955042Y605443D01*
X973857D01*
G01X867586Y385000D02*
Y380774D01*
X870147Y378213D01*
X898452D01*
X902145Y381906D01*
Y384260D01*
X910519Y392634D01*
X916070D01*
X933756Y410320D01*
X946092D01*
X959012Y423240D01*
Y464759D01*
X955634Y468137D01*
X952514D01*
X941502Y479149D01*
Y501693D01*
X932003Y511192D01*
Y550485D01*
X941502Y559984D01*
Y574141D01*
X938614Y577029D01*
Y591713D01*
X957400Y610499D01*
Y611547D01*
X958380Y612527D01*
X969841D01*
X976077Y606291D01*
X977009D01*
X977857Y605443D01*
G01X880040Y792851D02*
Y801539D01*
X883198Y804697D01*
X903642D01*
X906900Y807955D01*
Y812811D01*
X904728Y814983D01*
Y826710D01*
X907884Y829866D01*
G01X883552Y357276D02*
X886751Y360475D01*
Y366067D01*
X893114Y372430D01*
X900779D01*
X910896Y382547D01*
X990947D01*
X1011794Y361700D01*
X1044731D01*
X1052231Y354200D01*
X1070421D01*
X1091031Y374810D01*
G01X917803Y811365D02*
X919400Y803335D01*
Y799977D01*
X918415Y797598D01*
X915716Y794899D01*
X900988Y788800D01*
X898248D01*
X896900Y789358D01*
X889516Y792851D01*
G01X1090469Y1588435D02*
X1095365D01*
X1109900Y1573900D01*
Y1461599D01*
X1048100Y1399799D01*
Y1361700D01*
X1039100Y1352700D01*
X929501D01*
X896321Y1319520D01*
X888721D01*
X885200Y1315999D01*
Y1300438D01*
X886926Y1298712D01*
G01X1083900Y1593206D02*
X1102294D01*
X1111634Y1583866D01*
Y1460576D01*
X1049601Y1398543D01*
Y1361001D01*
X1039688Y1351088D01*
X930346D01*
X895000Y1315742D01*
Y1300787D01*
X889729Y1295516D01*
G01X898869Y351114D02*
Y367930D01*
X911425Y380486D01*
X989933D01*
X1010587Y359832D01*
X1043846D01*
X1051378Y352300D01*
X1078410D01*
X1080279Y354169D01*
Y354919D01*
X1078221Y356977D01*
Y357727D01*
X1079260Y358766D01*
X1080010D01*
X1082068Y356708D01*
X1082818D01*
X1083857Y357747D01*
Y358497D01*
X1081799Y360555D01*
Y361305D01*
X1082838Y362344D01*
Y362776D01*
X1090339Y370277D01*
X1092783D01*
X1093841Y371335D01*
G01X913716Y811954D02*
Y810734D01*
X911794Y806094D01*
X906437Y800737D01*
X905447Y798348D01*
X899848Y792749D01*
X898737Y792289D01*
G01X916875Y1098643D02*
X914500Y1096268D01*
Y1072774D01*
X915600Y1071674D01*
Y1059970D01*
X916159Y1059411D01*
X918041D01*
X918600Y1058852D01*
Y1058060D01*
X918041Y1057501D01*
X916159D01*
X915600Y1056942D01*
Y1056150D01*
X916159Y1055591D01*
X918041D01*
X918600Y1055032D01*
Y1054240D01*
X918041Y1053681D01*
X916159D01*
X915600Y1053122D01*
Y1052330D01*
X916159Y1051771D01*
X918041D01*
X918600Y1051212D01*
Y1050420D01*
X918041Y1049861D01*
X916159D01*
X915600Y1049302D01*
Y1048510D01*
X916159Y1047951D01*
X918041D01*
X918600Y1047392D01*
Y1046600D01*
X918041Y1046041D01*
X916159D01*
X915600Y1045482D01*
Y1044690D01*
X916159Y1044131D01*
X918041D01*
X918600Y1043572D01*
Y1042780D01*
X918041Y1042221D01*
X916159D01*
X915600Y1041662D01*
Y1030281D01*
X908422Y1023103D01*
G01X908856Y1017677D02*
X906200Y1020333D01*
Y1024100D01*
X913724Y1031624D01*
Y1069975D01*
X912600Y1071099D01*
Y1100510D01*
X916749Y1104659D01*
G01X911135Y1345560D02*
X913251Y1343444D01*
X917273D01*
X928418Y1354589D01*
X1038101D01*
X1045563Y1362051D01*
Y1400056D01*
X1107924Y1462417D01*
Y1536876D01*
X1098617Y1546183D01*
G01X980726Y1092664D02*
X975163D01*
X973399Y1090900D01*
X970872D01*
X968313Y1088341D01*
X955823D01*
X949782Y1082300D01*
X927113D01*
X916749Y1092664D01*
G01X916875Y1098643D02*
X918705Y1100473D01*
X947643D01*
X947970Y1100800D01*
X952611D01*
X953798Y1099613D01*
X968710D01*
X969802Y1098521D01*
X972000D01*
X972122Y1098643D01*
X980852D01*
G01X916749Y1104659D02*
X921442D01*
X922997Y1105303D01*
X958528D01*
X962368Y1101463D01*
X969019D01*
X971391Y1103835D01*
X979902D01*
X980726Y1104659D01*
G01X914033Y1345613D02*
X916257D01*
X927274Y1356630D01*
X1036898D01*
X1042958Y1362690D01*
Y1400806D01*
X1082514Y1440362D01*
Y1441080D01*
X1079884Y1443710D01*
Y1444428D01*
X1080390Y1444934D01*
X1081108D01*
X1083738Y1442304D01*
X1084456D01*
X1084962Y1442810D01*
Y1443528D01*
X1082332Y1446158D01*
Y1446876D01*
X1082838Y1447382D01*
X1083556D01*
X1086186Y1444752D01*
X1086904D01*
X1087410Y1445258D01*
Y1445976D01*
X1084780Y1448606D01*
Y1449324D01*
X1085286Y1449830D01*
X1086004D01*
X1088634Y1447200D01*
X1089352D01*
X1089858Y1447706D01*
Y1448424D01*
X1087228Y1451054D01*
Y1451772D01*
X1087734Y1452278D01*
X1088452D01*
X1091082Y1449648D01*
X1091800D01*
X1092306Y1450154D01*
Y1450872D01*
X1089676Y1453502D01*
Y1454220D01*
X1090182Y1454726D01*
X1090900D01*
X1093530Y1452096D01*
X1094248D01*
X1105308Y1463156D01*
Y1533092D01*
X1092100Y1546300D01*
X1091525D01*
G01X975631Y343112D02*
X978884Y346365D01*
Y352621D01*
X982363Y356100D01*
X1042101D01*
X1049640Y348561D01*
X1079861D01*
X1086898Y355598D01*
X1096651D01*
X1098845Y353404D01*
G01X975631Y346612D02*
Y352068D01*
X981538Y357975D01*
X1042893D01*
X1050490Y350378D01*
X1079079D01*
X1086201Y357500D01*
X1101016D01*
X1105012Y353504D01*
G01X998643Y1398271D02*
Y1388448D01*
X1003889Y1383202D01*
X1035187D01*
X1037856Y1385871D01*
Y1402940D01*
X1062590Y1427674D01*
Y1453363D01*
X1073878Y1464651D01*
X1079119D01*
X1093216Y1478748D01*
Y1505904D01*
X1081067Y1518053D01*
Y1528167D01*
X1082500Y1529600D01*
X1084000D01*
G01X1010499Y309062D02*
X1012553D01*
X1020936Y317445D01*
X1049536D01*
X1067744Y335653D01*
X1100831D01*
X1108779Y327705D01*
G01X1062349Y458711D02*
X1064658D01*
X1068832Y454537D01*
Y385198D01*
X1062234Y378600D01*
G01X1059549Y458711D02*
X1080383Y479545D01*
Y595784D01*
X1091610Y607011D01*
Y658354D01*
X1096104Y669204D01*
X1111628Y684728D01*
X1116455D01*
X1179700Y747973D01*
Y805686D01*
X1172300Y823552D01*
Y916525D01*
X1182420Y931669D01*
X1195708Y963750D01*
Y988082D01*
X1195757Y988131D01*
G01X1217177Y369925D02*
X1194436Y347184D01*
X1093912D01*
X1088654Y341926D01*
X1083453D01*
X1082297Y340770D01*
G01X1222601Y369251D02*
X1219801D01*
X1195643Y345093D01*
X1094273D01*
X1088995Y339815D01*
X1085615D01*
G01X1225755Y369391D02*
X1222758Y372388D01*
X1216316D01*
X1192791Y348863D01*
X1086449D01*
X1086087Y348501D01*
X1082787D01*
G01X1229122Y369355D02*
X1226969Y367202D01*
X1220753D01*
X1196819Y343268D01*
X1095504D01*
X1092554Y340318D01*
G01X1118848Y382109D02*
X1115100Y385857D01*
Y446862D01*
X1124770Y456532D01*
X1130433D01*
X1139900Y465999D01*
Y521101D01*
X1133000Y528001D01*
Y571788D01*
X1139741Y578529D01*
Y635787D01*
X1160275Y656321D01*
G01X1171934Y733857D02*
X1168749Y730672D01*
X1164805D01*
X1140578Y706445D01*
Y665211D01*
X1128565Y653198D01*
Y581010D01*
X1125492Y577937D01*
X1114668D01*
G01X1111785Y686971D02*
X1115672D01*
X1152512Y723811D01*
Y728543D01*
G01X1135548Y455804D02*
Y459122D01*
X1141604Y465178D01*
Y521570D01*
X1134673Y528501D01*
Y536000D01*
X1139173Y540500D01*
G01X1168685Y438323D02*
X1149100Y457908D01*
Y520573D01*
X1139673Y530000D01*
G01X1254275Y1539334D02*
X1242166D01*
X1229245Y1552255D01*
Y1615155D01*
X1213400Y1631000D01*
X1140448D01*
X1131850Y1622402D01*
G01X1149173D02*
X1155708Y1628937D01*
X1212648D01*
X1227515Y1614070D01*
Y1551486D01*
X1241410Y1537591D01*
X1245165D01*
X1247422Y1535334D01*
X1250434D01*
G01X1159535Y546712D02*
X1161709Y544538D01*
Y467463D01*
X1163298Y465874D01*
G01X1157451Y618288D02*
Y631879D01*
X1159315Y633743D01*
Y642796D01*
X1164275Y647756D01*
Y656321D01*
G01X1166496Y1622402D02*
X1171101Y1627007D01*
X1211697D01*
X1225694Y1613010D01*
Y1550530D01*
X1240197Y1536027D01*
X1244310D01*
X1249003Y1531334D01*
X1254275D01*
G01X1181706Y310131D02*
X1182437Y309400D01*
X1219601D01*
X1227165Y316964D01*
X1232197D01*
G01X1174929Y319167D02*
X1180096Y314000D01*
X1198200D01*
X1199200Y313000D01*
X1214762D01*
X1223338Y321576D01*
X1226948D01*
X1229922Y324550D01*
G01X1178045Y312193D02*
X1197806D01*
X1198699Y311300D01*
X1215706D01*
X1223406Y319000D01*
X1236589D01*
X1238293Y317296D01*
G01X1183818Y1622402D02*
X1186593Y1625177D01*
X1210846D01*
X1223964Y1612059D01*
Y1549235D01*
X1239070Y1534129D01*
X1243570D01*
X1249894Y1527805D01*
G01X1220723Y324466D02*
X1223373D01*
X1225913Y327006D01*
X1228342D01*
X1256376Y355040D01*
X1285445D01*
X1291256Y360851D01*
Y366922D01*
X1295410Y371076D01*
G01X1263328Y309003D02*
X1290444D01*
X1307134Y325693D01*
X1317683D01*
X1319400Y327410D01*
Y353394D01*
X1331606Y365600D01*
X1350300D01*
X1368700Y384000D01*
Y477689D01*
X1363020Y483369D01*
Y545079D01*
X1358800Y549299D01*
Y718800D01*
X1337661Y739939D01*
X1333362D01*
X1319000Y754301D01*
Y811620D01*
G01X1326946Y567906D02*
X1328087D01*
X1329412Y569231D01*
Y579999D01*
X1328229Y581182D01*
X1326218D01*
X1324401Y582999D01*
Y589799D01*
X1319800Y594400D01*
X1317738D01*
X1313800Y598338D01*
Y666700D01*
X1277069Y703431D01*
X1273844Y711216D01*
X1270200Y752865D01*
Y758071D01*
X1270190Y758173D01*
Y787510D01*
X1266880Y790820D01*
X1265624Y805167D01*
Y863565D01*
X1271365Y869306D01*
X1276016D01*
X1277822Y867500D01*
X1280400D01*
X1280800Y867900D01*
X1283200D01*
X1283600Y867500D01*
X1285500D01*
G01X1327000Y583826D02*
Y589299D01*
X1320330Y595969D01*
X1318830D01*
X1315500Y599299D01*
Y667120D01*
X1278407Y704213D01*
X1275194Y711976D01*
X1271610Y752927D01*
Y758140D01*
X1271600Y758244D01*
Y788095D01*
X1268241Y791455D01*
X1267034Y805229D01*
Y841945D01*
X1273423Y848334D01*
Y856224D01*
X1278900Y861701D01*
X1283701D01*
X1285500Y863500D01*
G01X1319323Y598454D02*
X1317000Y600777D01*
Y667801D01*
X1279473Y705328D01*
X1276580Y712317D01*
X1273020Y752989D01*
Y758208D01*
X1273010Y758315D01*
Y787509D01*
X1273011Y787510D01*
Y788679D01*
X1269601Y792089D01*
X1268444Y805291D01*
Y840439D01*
X1273000Y844995D01*
Y845011D01*
X1276308Y848319D01*
Y854409D01*
X1279027Y857128D01*
X1283128D01*
X1285500Y859500D01*
G01Y855500D02*
X1269854Y839854D01*
Y805353D01*
X1270962Y792724D01*
X1274421Y789264D01*
Y786925D01*
X1274420Y786924D01*
Y762996D01*
X1274490Y762284D01*
Y760296D01*
X1276271Y742221D01*
X1276645Y741371D01*
X1280200Y738115D01*
Y721491D01*
X1278960Y720251D01*
Y716839D01*
X1279339Y712987D01*
X1282906Y704376D01*
X1315782Y671500D01*
X1320000D01*
X1321200Y670300D01*
Y599323D01*
X1323020Y597503D01*
Y595291D01*
X1331096Y587215D01*
Y549931D01*
G01X1357047Y1622402D02*
X1350449Y1629000D01*
X1302799D01*
X1292512Y1618713D01*
Y1553513D01*
X1285111Y1546112D01*
X1266513D01*
X1258900Y1538499D01*
Y1533385D01*
X1262891Y1529394D01*
Y1527334D01*
G01X1305079Y1622402D02*
X1297702Y1615025D01*
Y1550102D01*
X1286934Y1539334D01*
X1267183D01*
G01X1267333Y1531334D02*
X1262953D01*
X1260700Y1533587D01*
Y1538200D01*
X1266480Y1543980D01*
X1285808D01*
X1294242Y1552414D01*
Y1617822D01*
X1303727Y1627307D01*
X1334820D01*
X1339725Y1622402D01*
G01X1262891Y1535334D02*
Y1537980D01*
X1266949Y1542038D01*
X1286747D01*
X1295972Y1551263D01*
Y1617171D01*
X1303978Y1625177D01*
X1319627D01*
X1322402Y1622402D01*
G01X1281331Y843331D02*
X1271264Y833264D01*
Y805415D01*
X1272310Y793500D01*
X1275900Y789910D01*
Y760366D01*
X1277582Y743307D01*
X1277644Y743156D01*
X1281800Y739000D01*
Y721000D01*
X1281200Y720400D01*
Y715572D01*
X1284786Y706919D01*
X1313979Y677726D01*
G01X1281269Y835492D02*
Y835269D01*
X1274084Y828084D01*
Y805539D01*
X1275032Y794768D01*
X1284690Y785110D01*
Y769314D01*
X1288090Y765914D01*
Y720190D01*
X1283400Y715500D01*
G01X1285500Y843500D02*
X1272674Y830674D01*
Y805477D01*
X1273671Y794134D01*
X1277634Y790171D01*
Y783786D01*
X1278749Y782671D01*
X1282129D01*
X1283280Y781520D01*
Y768729D01*
X1286680Y765329D01*
Y722980D01*
X1283400Y719700D01*
G01X1285500Y835500D02*
X1275494Y825494D01*
Y805601D01*
X1276392Y795409D01*
X1286100Y785701D01*
Y769899D01*
X1289500Y766499D01*
Y709699D01*
X1292732Y706467D01*
Y705067D01*
X1318299Y679500D01*
X1321300D01*
X1327000Y673800D01*
Y657500D01*
G01X1310971Y842319D02*
X1305798Y837146D01*
Y833701D01*
X1292200Y820103D01*
Y816701D01*
X1285900Y810401D01*
Y797900D01*
X1307500Y776300D01*
Y747941D01*
X1321044Y734397D01*
Y725989D01*
X1331079Y715954D01*
Y696761D01*
X1337500Y690340D01*
Y683300D01*
X1344628Y676172D01*
Y654907D01*
X1345619Y653916D01*
Y632100D01*
X1340148Y626629D01*
Y625049D01*
X1341729Y623468D01*
Y609314D01*
X1344129Y606914D01*
G01X1313756Y858218D02*
X1312579Y857041D01*
X1295841D01*
X1291200Y852400D01*
Y822200D01*
X1290017Y821017D01*
Y817459D01*
X1284400Y811842D01*
Y797200D01*
X1296252Y785348D01*
Y716610D01*
X1314362Y698500D01*
X1320900D01*
X1327100Y692300D01*
X1330200D01*
X1333095Y689405D01*
Y680710D01*
X1334400Y679405D01*
X1335790D01*
X1336905Y678290D01*
Y677795D01*
X1340148Y674552D01*
Y669549D01*
X1342800Y666897D01*
Y643500D01*
X1341095Y641795D01*
Y636168D01*
X1342600Y634663D01*
Y631076D01*
X1338700Y627176D01*
Y620500D01*
X1335354Y617154D01*
Y607116D01*
X1341269Y601201D01*
X1344433D01*
G01X1285500Y827500D02*
Y823599D01*
X1280600Y818699D01*
Y795700D01*
X1289600Y786700D01*
Y770700D01*
X1292500Y767800D01*
Y714700D01*
X1314610Y692590D01*
X1316510D01*
X1329475Y679625D01*
Y677665D01*
X1333095Y674045D01*
Y635095D01*
X1327000Y629000D01*
G01X1329504Y861367D02*
X1326210Y864661D01*
X1299695D01*
X1287954Y852920D01*
Y818154D01*
X1282500Y812700D01*
Y796499D01*
X1294400Y784599D01*
Y715500D01*
X1315500Y694400D01*
X1322200D01*
X1331285Y685315D01*
Y678415D01*
X1337000Y672700D01*
Y658300D01*
X1340990Y654310D01*
Y644300D01*
X1338617Y641927D01*
Y629653D01*
X1333224Y624260D01*
Y615484D01*
G01X1281388Y827388D02*
X1276904Y822904D01*
Y805663D01*
X1277752Y796048D01*
X1288100Y785700D01*
Y770099D01*
X1291000Y767199D01*
Y710799D01*
X1318394Y683405D01*
X1323699D01*
X1324104Y683000D01*
X1328065Y679040D01*
Y677080D01*
X1331685Y673460D01*
Y637385D01*
X1324900Y630600D01*
Y615100D01*
X1327000Y613000D01*
G01X1274264Y898591D02*
X1279335Y903662D01*
X1299680D01*
X1300826Y904808D01*
X1307245D01*
X1310295Y901758D01*
X1314884D01*
X1317637Y899005D01*
X1325787D01*
X1331056Y904274D01*
Y904557D01*
G01X1336000Y900500D02*
X1333683Y902817D01*
Y904817D01*
X1319100Y919400D01*
X1301397D01*
X1298000Y922797D01*
Y928199D01*
X1287100Y939099D01*
Y947800D01*
X1285500Y949400D01*
Y994101D01*
X1313618Y1022219D01*
Y1029514D01*
X1313118Y1030014D01*
X1313017D01*
X1306385Y1036646D01*
G01X1295410Y371076D02*
X1298962Y374628D01*
X1312227D01*
X1313496Y375897D01*
X1332196D01*
X1352893Y396594D01*
Y417305D01*
X1357882Y422294D01*
Y453890D01*
X1352615Y459157D01*
X1346296D01*
X1343846Y461607D01*
G01X1315321Y827822D02*
X1313245Y825746D01*
X1310226D01*
X1299380Y814900D01*
X1296301D01*
X1292135Y810734D01*
Y796966D01*
X1311600Y777501D01*
Y754764D01*
X1330300Y736064D01*
Y722200D01*
X1335799Y716701D01*
Y699047D01*
X1345604Y689242D01*
Y687697D01*
X1351600Y681701D01*
Y627201D01*
X1348133Y623734D01*
X1346378D01*
G01X1344680Y619085D02*
X1344200Y619565D01*
Y624600D01*
X1345300Y625700D01*
X1347300D01*
X1349600Y628000D01*
Y680800D01*
X1333700Y696700D01*
Y715999D01*
X1322974Y726725D01*
Y735751D01*
X1309600Y749125D01*
Y776800D01*
X1287800Y798600D01*
Y809600D01*
X1295462Y817262D01*
X1298578D01*
X1305959Y824643D01*
Y830485D01*
X1310084Y834610D01*
X1312196D01*
X1313756Y836170D01*
G01X1336096Y905042D02*
X1319667Y921471D01*
X1304067D01*
X1300200Y925338D01*
Y928600D01*
X1291500Y937300D01*
Y953326D01*
X1288770Y956056D01*
Y968300D01*
X1290000Y969530D01*
Y995310D01*
X1316118Y1021428D01*
Y1033298D01*
X1312873Y1036543D01*
G01X1319500Y905000D02*
X1315046Y909454D01*
X1309546D01*
X1302000Y917000D01*
G01X1395955Y832697D02*
Y827655D01*
X1398110Y825500D01*
X1406931D01*
X1408047Y826616D01*
Y897436D01*
X1403383Y902100D01*
X1400048D01*
X1394648Y907500D01*
X1361100D01*
X1360108Y908492D01*
X1346211D01*
X1344003Y910700D01*
X1337627D01*
X1320627Y927700D01*
X1313074D01*
X1311521Y926147D01*
X1303000D01*
X1302500Y926647D01*
Y928999D01*
X1293400Y938099D01*
Y954388D01*
X1291461Y956327D01*
Y960401D01*
X1290792Y961070D01*
Y961363D01*
G01X1320549Y1037876D02*
X1318896Y1036223D01*
Y1020511D01*
X1298876Y1000491D01*
Y982248D01*
X1311000Y970124D01*
G01X1322773Y1040599D02*
Y1036554D01*
X1320721Y1034502D01*
Y1019755D01*
X1300701Y999735D01*
Y983381D01*
X1311438Y972644D01*
X1315755D01*
X1325550Y962849D01*
Y960445D01*
G01X1315000Y811620D02*
Y756000D01*
X1336472Y734528D01*
X1340872D01*
X1357300Y718100D01*
Y548800D01*
X1361610Y544490D01*
Y482784D01*
X1367200Y477194D01*
Y385099D01*
X1349360Y367259D01*
X1331060D01*
X1317941Y354140D01*
Y336253D01*
X1315397Y333709D01*
G01X1316906Y829871D02*
Y819459D01*
X1311000Y813553D01*
Y783034D01*
X1313300Y780734D01*
Y755511D01*
X1332100Y736711D01*
Y732200D01*
X1333800Y730500D01*
X1336100D01*
X1338095Y728505D01*
Y716005D01*
X1342276Y711824D01*
Y696001D01*
X1347334Y690943D01*
X1350756D01*
X1353136Y688563D01*
Y560193D01*
X1355700Y557629D01*
Y548301D01*
X1360200Y543801D01*
Y482199D01*
X1365700Y476699D01*
Y387845D01*
X1349763Y371908D01*
G01X1428823Y1020266D02*
X1430822Y1018267D01*
Y995822D01*
X1414870Y979870D01*
X1307707D01*
G01X1428864Y996766D02*
X1414841Y982743D01*
X1311731D01*
X1307561Y986913D01*
Y986951D01*
G01X1310773Y1282411D02*
X1313400D01*
X1326672Y1295683D01*
Y1298268D01*
X1329633Y1301229D01*
X1332218D01*
X1344268Y1313279D01*
X1401052Y1336800D01*
X1423199D01*
X1431900Y1345501D01*
Y1414242D01*
X1432258Y1414600D01*
G01X1325000Y804000D02*
Y802000D01*
X1327000Y800000D01*
Y760500D01*
X1343800Y743700D01*
X1346401D01*
X1361800Y728301D01*
Y550601D01*
X1365840Y546561D01*
Y484539D01*
X1371700Y478679D01*
Y382400D01*
X1353643Y364343D01*
Y335142D01*
X1341186Y322685D01*
X1332359D01*
G01X1323000Y811620D02*
Y786900D01*
X1322100Y786000D01*
Y762601D01*
X1334600Y750101D01*
Y745001D01*
X1360300Y719301D01*
Y549800D01*
X1364430Y545670D01*
Y483954D01*
X1370200Y478184D01*
Y383101D01*
X1341169Y354070D01*
Y325926D01*
G01X1327000Y811620D02*
Y802800D01*
X1331021Y798779D01*
Y786742D01*
X1334475Y783288D01*
Y759104D01*
X1338800Y754779D01*
Y752701D01*
X1343801Y747700D01*
X1347401D01*
X1363300Y731801D01*
Y551100D01*
X1367300Y547100D01*
Y485200D01*
X1373440Y479060D01*
Y434154D01*
X1375360Y432234D01*
G01X1331000Y811620D02*
Y802636D01*
X1331936Y801700D01*
X1333100D01*
X1334924Y799876D01*
Y786629D01*
X1339700Y781853D01*
Y759400D01*
X1340800Y758300D01*
Y754700D01*
X1343800Y751700D01*
X1346801D01*
X1364840Y733661D01*
Y551559D01*
X1368800Y547599D01*
Y485701D01*
X1375400Y479101D01*
Y435192D01*
G01X1333000Y804000D02*
X1339006Y797994D01*
Y785935D01*
X1342191Y782750D01*
Y768610D01*
X1346952Y763849D01*
Y754448D01*
X1366250Y735150D01*
Y552144D01*
X1370300Y548094D01*
Y486400D01*
X1377400Y479300D01*
Y401899D01*
X1379400Y399899D01*
Y387800D01*
X1355402Y363802D01*
Y333063D01*
X1347990Y325651D01*
Y322539D01*
G01X1344007Y279054D02*
Y315664D01*
X1352443Y324100D01*
Y327343D01*
X1357354Y332254D01*
Y363105D01*
X1381400Y387151D01*
Y400800D01*
X1379300Y402900D01*
Y479961D01*
X1372110Y487151D01*
Y548845D01*
X1368060Y552895D01*
Y736041D01*
X1349100Y755001D01*
Y783900D01*
X1347000Y786000D01*
Y796700D01*
X1342000Y801700D01*
X1340100D01*
X1338995Y802805D01*
Y807625D01*
X1335000Y811620D01*
G01X1329504Y833021D02*
Y827689D01*
X1339499Y817694D01*
X1352206D01*
X1357074Y812826D01*
Y808606D01*
X1359014Y806666D01*
Y802786D01*
X1363502Y798298D01*
X1378302D01*
X1400900Y775700D01*
Y749301D01*
X1390677Y739078D01*
Y673177D01*
X1385400Y667900D01*
Y635458D01*
X1382700Y632758D01*
Y630600D01*
X1383400Y629900D01*
Y621400D01*
X1385700Y619100D01*
Y603900D01*
X1380900Y599100D01*
Y553800D01*
X1381200Y553500D01*
Y490700D01*
X1388400Y483500D01*
Y458644D01*
X1423200Y423844D01*
Y361019D01*
X1409830Y347649D01*
G01X1319554Y925585D02*
X1319639D01*
X1336424Y908800D01*
X1342711D01*
X1351511Y900000D01*
G01X1330500Y925500D02*
X1343300Y912700D01*
X1344662D01*
X1346983Y910379D01*
X1360621D01*
X1361481Y909519D01*
X1395680D01*
X1399099Y906100D01*
X1406600D01*
X1411300Y901400D01*
Y809731D01*
X1422376Y798655D01*
Y753824D01*
X1435764Y740436D01*
X1448344D01*
X1460816Y727964D01*
G01X1390271Y417578D02*
X1381200Y426649D01*
Y480800D01*
X1373920Y488080D01*
Y549595D01*
X1369870Y553645D01*
Y737030D01*
X1352300Y754600D01*
Y785500D01*
X1350900Y786900D01*
Y797500D01*
X1350200Y798200D01*
X1348101D01*
X1342301Y804000D01*
X1341000D01*
G01X1351000Y811620D02*
X1355000Y807620D01*
Y803000D01*
X1363777Y794223D01*
X1379478D01*
X1398900Y774801D01*
Y753343D01*
X1377000Y731443D01*
Y715106D01*
X1380400Y711706D01*
Y687851D01*
X1375300Y682751D01*
Y556701D01*
X1379600Y552401D01*
Y490201D01*
X1386900Y482901D01*
Y440400D01*
X1395300Y432000D01*
Y419558D01*
X1383963Y408221D01*
Y366675D01*
G01X1389557Y424678D02*
X1385000Y429235D01*
Y482200D01*
X1377700Y489500D01*
Y551101D01*
X1373490Y555311D01*
Y738610D01*
X1356100Y756000D01*
Y780400D01*
X1356900Y781200D01*
Y798000D01*
X1352900Y802000D01*
X1351701D01*
X1351000Y802701D01*
Y807620D01*
X1347000Y811620D01*
G01X1389431Y421593D02*
X1383100Y427924D01*
Y481499D01*
X1375800Y488799D01*
Y550275D01*
X1371680Y554395D01*
Y737819D01*
X1354200Y755299D01*
Y782700D01*
X1354900Y783400D01*
Y796900D01*
X1351700Y800100D01*
X1349799D01*
X1346916Y802983D01*
Y807704D01*
X1343000Y811620D01*
G01X1385360Y811757D02*
X1381831Y815286D01*
X1363807D01*
X1353302Y825791D01*
Y828698D01*
X1349316Y832684D01*
Y846427D01*
X1351550Y848661D01*
Y848769D01*
G01X1362583Y828918D02*
X1369501Y822000D01*
X1387800D01*
X1395938Y813862D01*
Y805020D01*
X1396599Y804359D01*
Y796935D01*
X1412800Y780734D01*
Y764673D01*
X1414094Y763379D01*
Y752506D01*
X1420000Y746600D01*
Y668634D01*
X1430481Y658153D01*
G01X1359434Y833707D02*
X1361200Y831941D01*
Y827600D01*
X1369419Y819381D01*
X1387220D01*
X1393420Y813181D01*
Y810059D01*
X1392534Y809173D01*
Y794866D01*
X1407000Y780400D01*
Y767764D01*
X1412222Y762542D01*
Y750338D01*
X1415899Y746661D01*
Y742101D01*
X1418000Y740000D01*
G01X1353115Y831484D02*
X1367481Y817118D01*
X1385949D01*
X1391040Y812027D01*
G01X1425909Y691120D02*
X1421881Y695148D01*
Y747707D01*
X1415826Y753762D01*
Y783804D01*
X1402061Y797569D01*
Y799345D01*
X1400435Y800971D01*
Y812911D01*
X1388734Y824612D01*
X1372688D01*
X1368882Y828418D01*
G01X1405500Y868000D02*
X1398959D01*
X1396616Y865657D01*
X1370023D01*
X1367298Y862932D01*
Y861367D01*
G01X1382073Y856653D02*
X1383301Y855425D01*
X1390075D01*
X1397500Y848000D01*
X1402000D01*
G01Y864000D02*
X1398273Y860273D01*
X1395220D01*
X1391990Y863503D01*
X1370103D01*
X1368863Y862263D01*
G01X1385314Y844035D02*
X1393251Y836098D01*
X1397450D01*
X1400069Y833479D01*
Y827515D01*
G01X1378957Y630957D02*
X1381000Y628914D01*
Y626700D01*
X1380400Y626100D01*
Y604400D01*
X1378957Y602957D01*
Y584457D01*
G01X1384657Y631620D02*
X1386900Y629377D01*
Y622300D01*
X1388200Y621000D01*
Y589700D01*
X1383000Y584500D01*
G01X1378957Y675457D02*
Y679632D01*
X1382018Y687022D01*
X1382546Y688297D01*
Y718868D01*
X1378957Y722457D01*
G01X1385290Y722400D02*
X1385600Y722090D01*
Y678100D01*
X1383000Y675500D01*
G01X1426615Y674112D02*
X1427055Y674552D01*
Y686034D01*
X1428393Y687372D01*
Y694249D01*
X1424095Y698547D01*
Y748268D01*
X1420457Y751906D01*
Y792642D01*
X1404441Y808658D01*
Y812726D01*
X1390459Y826708D01*
X1376091D01*
X1372012Y830787D01*
G01X1384316Y847184D02*
X1393408Y838092D01*
X1403408D01*
X1405500Y836000D01*
G01X1386166Y850334D02*
X1396500Y840000D01*
X1402000D01*
G01X1387997Y853503D02*
X1398500Y843000D01*
X1404500D01*
X1405500Y844000D01*
G01X1392513Y859800D02*
X1395542Y856771D01*
X1402271D01*
X1405500Y860000D01*
G01X1445906Y366030D02*
Y403585D01*
X1389900Y459591D01*
Y483999D01*
X1386037Y487862D01*
Y584738D01*
X1390700Y589401D01*
Y604601D01*
X1392700Y606601D01*
Y616300D01*
X1390800Y618200D01*
Y621200D01*
X1388800Y623200D01*
Y630400D01*
X1386900Y632300D01*
Y667099D01*
X1393200Y673399D01*
Y739100D01*
X1403200Y749100D01*
Y775873D01*
X1386335Y792949D01*
Y803704D01*
G01X1443041Y363648D02*
X1446448D01*
X1448200Y365400D01*
Y403500D01*
X1391400Y460300D01*
Y485092D01*
X1387500Y488992D01*
Y583500D01*
X1392200Y588200D01*
Y604100D01*
X1394200Y606100D01*
Y616900D01*
X1393500Y617600D01*
Y628800D01*
X1388500Y633800D01*
Y666110D01*
X1394900Y672510D01*
Y738199D01*
X1405000Y748299D01*
Y777624D01*
X1390537Y792087D01*
Y803679D01*
G01X1410817Y1305417D02*
X1414548D01*
X1430399Y1321268D01*
Y1323560D01*
X1438510Y1331671D01*
Y1413852D01*
X1439258Y1414600D01*
G01X1495630Y1622402D02*
X1500132Y1626904D01*
X1558452D01*
X1574248Y1611108D01*
Y1555115D01*
X1583319Y1546044D01*
X1601694D01*
X1603148Y1544590D01*
Y1528408D01*
X1607183Y1524373D01*
Y1518172D01*
X1606500Y1517489D01*
Y1515000D01*
X1593444Y1501944D01*
Y1484581D01*
X1596212Y1481813D01*
X1598953D01*
X1602620Y1478146D01*
Y1473573D01*
X1601171Y1470075D01*
X1594103Y1463007D01*
X1584889D01*
X1542915Y1421033D01*
X1525438D01*
X1518598Y1414193D01*
Y1391566D01*
X1516994Y1389962D01*
X1509115D01*
X1505966Y1386813D01*
Y1344526D01*
X1491457Y1330017D01*
X1459395D01*
X1447378Y1318000D01*
Y1308151D01*
X1445194Y1305967D01*
X1435345D01*
X1431080Y1301702D01*
G01X1421238Y1301712D02*
Y1304461D01*
X1455047Y1338270D01*
Y1384116D01*
X1461566Y1390635D01*
X1479278D01*
X1481428Y1392785D01*
Y1413887D01*
X1499435Y1431894D01*
X1541854D01*
X1587856Y1477896D01*
Y1518753D01*
X1556988Y1549621D01*
X1548680D01*
X1543480Y1554821D01*
Y1610400D01*
X1545246Y1612166D01*
X1547598D01*
G01X1556260Y1452717D02*
Y1452261D01*
X1540286Y1436287D01*
X1494338D01*
X1451996Y1393945D01*
Y1337779D01*
X1417711Y1303494D01*
Y1301729D01*
G01X1428009Y1301760D02*
X1429088Y1304363D01*
X1457655Y1332930D01*
X1482291D01*
X1493634Y1344273D01*
Y1386346D01*
X1499030Y1391742D01*
X1504623D01*
X1505966Y1393085D01*
Y1413085D01*
X1518412Y1425531D01*
X1543439D01*
X1584302Y1466394D01*
X1592483D01*
X1595000Y1468911D01*
Y1473061D01*
X1597039Y1475100D01*
G01X1424732Y1301603D02*
Y1303981D01*
X1456650Y1335899D01*
X1479509D01*
X1481429Y1337819D01*
Y1386857D01*
X1484698Y1390126D01*
X1490126D01*
X1493634Y1393634D01*
Y1414144D01*
X1508574Y1429084D01*
X1543018D01*
X1591889Y1477955D01*
X1598369D01*
X1599726Y1476598D01*
Y1474990D01*
G01X1432258Y1414600D02*
X1433200Y1415542D01*
Y1418200D01*
X1443600Y1428600D01*
X1463499D01*
X1486968Y1452069D01*
Y1452717D01*
G01X1441200Y1338700D02*
Y1386710D01*
X1493890Y1439400D01*
X1525620D01*
X1538937Y1452717D01*
G01X1504291D02*
X1497474Y1445900D01*
X1492934D01*
X1473117Y1426083D01*
X1445383D01*
X1435900Y1416600D01*
Y1340800D01*
G01X1439258Y1414600D02*
X1447447Y1422789D01*
X1473210D01*
X1493521Y1443100D01*
X1511997D01*
X1521614Y1452717D01*
G01X1734069Y1807909D02*
X1440636D01*
X1436666Y1803939D01*
Y1801879D01*
X1440636Y1797909D01*
X1734069D01*
G01X1486957Y792457D02*
Y747633D01*
X1482908Y743584D01*
Y725086D01*
X1481276Y723454D01*
X1478861D01*
X1471356Y715949D01*
Y708356D01*
X1469957Y706957D01*
G01X1495170Y796670D02*
Y794170D01*
X1489044Y788044D01*
Y745777D01*
X1485026Y741759D01*
Y722640D01*
X1476500Y714114D01*
Y709500D01*
X1474000Y707000D01*
G01X1469957Y750957D02*
Y753138D01*
X1469624Y753471D01*
Y816724D01*
X1486957Y834057D01*
Y836457D01*
G01X1474000Y753093D02*
X1471616Y755477D01*
Y815759D01*
X1491568Y835711D01*
Y836267D01*
X1492625Y837324D01*
G01X1519321Y378600D02*
X1525919Y385198D01*
Y441021D01*
X1517733Y449207D01*
Y457008D01*
X1519436Y458711D01*
G01X1516636D02*
Y466377D01*
X1537470Y487211D01*
Y574605D01*
X1547391Y624486D01*
Y631267D01*
X1561552Y665455D01*
G01X1598574Y1543373D02*
X1597972Y1542771D01*
X1584084D01*
X1572642Y1554213D01*
Y1610719D01*
X1557867Y1625494D01*
X1533367D01*
X1530275Y1622402D01*
G01X1590748Y1523377D02*
X1586252D01*
X1553421Y1556208D01*
Y1585870D01*
X1547598Y1591693D01*
G01X1604000Y1519000D02*
Y1523582D01*
X1596880Y1530702D01*
X1588530D01*
X1567252Y1551980D01*
Y1588165D01*
X1557178Y1598239D01*
X1549026D01*
X1547598Y1596811D01*
G01X1601500Y1514500D02*
X1600591Y1515409D01*
Y1523017D01*
X1595716Y1527892D01*
X1587366D01*
X1564442Y1550816D01*
Y1577606D01*
X1556260Y1585788D01*
G01X1617362Y656321D02*
X1589760Y628719D01*
Y521128D01*
X1592888Y518000D01*
Y470323D01*
X1587686Y465121D01*
Y462361D01*
X1572450Y447125D01*
Y387807D01*
X1575935Y384322D01*
Y382109D01*
G01X1575934Y561420D02*
X1577372D01*
X1585763Y569811D01*
Y620336D01*
X1578499Y627600D01*
X1576297D01*
G01X1577077Y631712D02*
X1587878Y620911D01*
Y569238D01*
X1577557Y558917D01*
X1575934D01*
G01X1571755Y577937D02*
X1570059Y579633D01*
Y633201D01*
X1584119Y647261D01*
Y667882D01*
X1574890Y677111D01*
X1569434D01*
G01X1592635Y455911D02*
X1594465Y457741D01*
Y519176D01*
X1591760Y521881D01*
Y536000D01*
X1596260Y540500D01*
G01X1596760Y530000D02*
X1606187Y520573D01*
Y457908D01*
X1625772Y438323D01*
G01X1611316Y685800D02*
X1610900Y685384D01*
Y666783D01*
X1621362Y656321D01*
G01X1720826Y1591693D02*
X1724825Y1595692D01*
Y1623532D01*
X1719510Y1628847D01*
X1648843D01*
X1641542Y1621546D01*
Y1559615D01*
X1621362Y1539435D01*
X1608758D01*
X1605968Y1536645D01*
Y1530714D01*
X1609348Y1527334D01*
G01X1613790Y1523334D02*
X1610652D01*
X1604558Y1529428D01*
Y1537230D01*
X1608173Y1540845D01*
X1620777D01*
X1640132Y1560200D01*
Y1622131D01*
X1648258Y1630257D01*
X1720095D01*
X1725457Y1624895D01*
X1730051D01*
X1732077Y1622869D01*
Y1583259D01*
X1729488Y1580670D01*
G01X1609348Y1535334D02*
X1621251D01*
X1644362Y1558445D01*
Y1620376D01*
X1650013Y1626027D01*
X1717201D01*
X1720826Y1622402D01*
G01Y1607048D02*
X1723415Y1609637D01*
Y1622947D01*
X1718925Y1627437D01*
X1649428D01*
X1642952Y1620961D01*
Y1559030D01*
X1621947Y1538025D01*
X1609343D01*
X1607378Y1536060D01*
Y1534608D01*
X1610652Y1531334D01*
X1613790D01*
G01X1616622Y546712D02*
X1618796Y544538D01*
Y467463D01*
X1620385Y465874D01*
G01X1621362Y656321D02*
Y647756D01*
X1616402Y642796D01*
Y633743D01*
X1614538Y631879D01*
Y618288D01*
G01X1703503Y1622402D02*
X1701288Y1624617D01*
X1650616D01*
X1646559Y1620560D01*
Y1557885D01*
X1640581Y1551907D01*
G54D23*
X849441Y1367717D03*
G54D14*
G01X825335Y1137129D02*
X821699Y1140765D01*
Y1148652D01*
X823134Y1150087D01*
X825744D01*
G01X891251Y387484D02*
X872647D01*
X870561Y389570D01*
X852014D01*
X840196Y401388D01*
Y419132D01*
X847648Y426584D01*
Y476461D01*
X844227Y479882D01*
G01X1023358Y1363921D02*
X1017070D01*
X1013991Y1360842D01*
G01X1023358Y1363921D02*
X1026437Y1360842D01*
X1035925D01*
X1040140Y1365057D01*
Y1401461D01*
X1064621Y1425942D01*
Y1452454D01*
X1074565Y1462398D01*
X1080491D01*
X1095668Y1477575D01*
Y1512810D01*
X1095080Y1513398D01*
G01X1083283Y1526583D02*
X1085175D01*
X1090192Y1531600D01*
X1095250D01*
G01X1435197Y1028372D02*
X1455271D01*
X1459743Y1023900D01*
X1465846D01*
X80290Y1345691D03*
Y1350683D03*
X75334Y1345691D03*
Y1350683D03*
X80290Y1357603D03*
Y1362595D03*
X75334Y1357603D03*
Y1362595D03*
X80290Y1381801D03*
Y1369889D03*
Y1374881D03*
X75334Y1381801D03*
Y1374881D03*
Y1369889D03*
X80290Y1386793D03*
X75334D03*
X87574Y1345691D03*
Y1350683D03*
X99814D03*
Y1345691D03*
X92530D03*
Y1350683D03*
X87574Y1362595D03*
Y1357603D03*
X99814Y1362595D03*
Y1357603D03*
X92530Y1362595D03*
Y1357603D03*
X87574Y1374881D03*
Y1369795D03*
Y1381801D03*
X99814D03*
Y1374881D03*
Y1369889D03*
X92530Y1374881D03*
Y1369795D03*
Y1381801D03*
X87574Y1399079D03*
Y1393993D03*
Y1386793D03*
X99814Y1399079D03*
Y1394087D03*
Y1386793D03*
X92530Y1393993D03*
Y1399079D03*
Y1386793D03*
X87574Y1410991D03*
Y1405999D03*
X99814Y1410991D03*
Y1405999D03*
X92530Y1410991D03*
Y1405999D03*
X104770Y1350683D03*
Y1345691D03*
X112054D03*
Y1350683D03*
X117010Y1345691D03*
Y1350683D03*
X104770Y1362595D03*
Y1357603D03*
X112054Y1362595D03*
Y1357603D03*
X117010Y1362595D03*
Y1357603D03*
Y1369889D03*
Y1374881D03*
Y1381801D03*
X104770D03*
Y1374881D03*
Y1369889D03*
X112054D03*
Y1374881D03*
Y1381801D03*
X104770Y1399079D03*
Y1394087D03*
Y1386793D03*
X112054Y1399079D03*
Y1394087D03*
Y1386793D03*
X117010Y1394087D03*
Y1399079D03*
Y1386793D03*
X104770Y1410991D03*
Y1405999D03*
X112054Y1410991D03*
Y1405999D03*
X117010Y1410991D03*
Y1405999D03*
X124294Y1350683D03*
Y1345691D03*
X129250Y1350683D03*
Y1345691D03*
X124294Y1362595D03*
Y1357603D03*
X129250D03*
Y1362595D03*
X124294Y1374881D03*
Y1369889D03*
Y1381801D03*
X129250Y1374881D03*
Y1369889D03*
Y1381801D03*
X124294Y1394087D03*
Y1399079D03*
Y1386793D03*
X129250Y1394087D03*
Y1399079D03*
Y1386793D03*
X124294Y1405999D03*
Y1410991D03*
X129250Y1405999D03*
Y1410991D03*
X141490Y1345691D03*
Y1350683D03*
X136534D03*
Y1345691D03*
X148774Y1350683D03*
Y1345691D03*
X141490Y1357603D03*
Y1362595D03*
X136534D03*
Y1357603D03*
X148774D03*
Y1362595D03*
X141490Y1369889D03*
Y1374881D03*
Y1381801D03*
X136534Y1369889D03*
Y1381801D03*
Y1374881D03*
X148774Y1369889D03*
Y1381801D03*
Y1374881D03*
X141490Y1386793D03*
Y1394087D03*
Y1399079D03*
X136534D03*
Y1394087D03*
Y1386793D03*
X148774Y1394087D03*
Y1399079D03*
Y1386793D03*
X141490Y1405999D03*
Y1410991D03*
X136534D03*
Y1405999D03*
X148774D03*
Y1410991D03*
X161014Y1345691D03*
Y1350683D03*
X153730Y1345691D03*
Y1350683D03*
X165970Y1345691D03*
Y1350683D03*
X161014Y1362595D03*
Y1357603D03*
X153730Y1362595D03*
Y1357603D03*
X165970Y1362595D03*
Y1357603D03*
X161014Y1381801D03*
Y1369889D03*
Y1374881D03*
X153730Y1369889D03*
Y1381801D03*
Y1374881D03*
X165970D03*
Y1381801D03*
Y1369889D03*
X161014Y1394087D03*
Y1386793D03*
X153730Y1394087D03*
Y1386793D03*
X165970Y1394087D03*
Y1386793D03*
X161014Y1399079D03*
X153730D03*
X165970D03*
X161014Y1410991D03*
Y1405999D03*
X153730D03*
Y1410991D03*
X165970D03*
Y1405999D03*
X173254Y1345691D03*
Y1350683D03*
X178210Y1345691D03*
Y1350683D03*
X173254Y1362595D03*
Y1357603D03*
X178210D03*
Y1362595D03*
X173254Y1374881D03*
Y1369889D03*
Y1381801D03*
X178210Y1374881D03*
Y1369889D03*
Y1381801D03*
X173254Y1394087D03*
Y1386793D03*
X178210Y1394087D03*
Y1386793D03*
X173254Y1399079D03*
X178210D03*
X173254Y1405999D03*
Y1410991D03*
X178210Y1405999D03*
Y1410991D03*
X185494Y1345597D03*
Y1350683D03*
X190450Y1345597D03*
Y1350683D03*
X197734Y1345691D03*
Y1350683D03*
X185494Y1362595D03*
Y1357603D03*
X197734Y1362595D03*
Y1357603D03*
X190450Y1362595D03*
Y1357603D03*
X185494Y1374881D03*
Y1381801D03*
Y1369889D03*
X197734D03*
Y1381801D03*
Y1374881D03*
X190450Y1369889D03*
Y1374881D03*
Y1381801D03*
X185494Y1393993D03*
Y1386793D03*
X190450Y1393993D03*
Y1386793D03*
X197734Y1394087D03*
Y1386793D03*
X185494Y1399079D03*
X190450D03*
X197734D03*
X185494Y1410991D03*
Y1405999D03*
X190450Y1410991D03*
Y1405999D03*
X197734D03*
Y1410991D03*
X202690Y1345597D03*
Y1350683D03*
Y1362595D03*
Y1357603D03*
Y1369889D03*
Y1381801D03*
Y1374881D03*
Y1394087D03*
Y1386793D03*
Y1399079D03*
Y1405999D03*
Y1410991D03*
X211473Y1446675D03*
Y1451631D03*
Y1462631D03*
Y1457675D03*
X216465Y1446675D03*
X229745D03*
X224753D03*
X216465Y1451631D03*
Y1462631D03*
Y1457675D03*
X224753Y1462631D03*
X229745Y1457675D03*
X224753D03*
X229745Y1451631D03*
Y1462631D03*
X224753Y1451631D03*
X408523Y1332967D03*
X404657D03*
X439624Y1345691D03*
Y1350683D03*
Y1357603D03*
Y1362595D03*
Y1381801D03*
Y1369889D03*
Y1374881D03*
Y1386793D03*
X435881Y1394934D03*
Y1398800D03*
X456820Y1345691D03*
X451864D03*
Y1350683D03*
X456820D03*
X444580Y1345691D03*
Y1350683D03*
X456820Y1362595D03*
Y1357603D03*
X451864Y1362595D03*
Y1357603D03*
X444580D03*
Y1362595D03*
X456820Y1374881D03*
X451864D03*
X444580Y1369889D03*
X456820Y1369795D03*
X451864D03*
X444580Y1374881D03*
Y1381801D03*
X456820D03*
X451864D03*
X456820Y1399079D03*
X451864Y1393993D03*
Y1399079D03*
X456820Y1393993D03*
Y1386793D03*
X451864D03*
X444580D03*
X456820Y1405999D03*
X451864D03*
Y1410991D03*
X456820D03*
X454125Y1461182D03*
Y1465913D03*
Y1481267D03*
Y1476536D03*
Y1491890D03*
Y1496621D03*
Y1511976D03*
Y1507245D03*
Y1578898D03*
Y1568275D03*
Y1563544D03*
Y1583629D03*
Y1594253D03*
Y1609607D03*
Y1598984D03*
Y1614338D03*
X469060Y1345691D03*
Y1350683D03*
X464104Y1345691D03*
Y1350683D03*
X469060Y1357603D03*
Y1362595D03*
X464104D03*
Y1357603D03*
Y1381801D03*
X469060D03*
X464104Y1369889D03*
X469060D03*
X464104Y1374881D03*
X469060D03*
Y1386793D03*
X464104D03*
X469060Y1399079D03*
X464104Y1394087D03*
X469060D03*
X464104Y1399079D03*
Y1405999D03*
X469060D03*
X464104Y1410991D03*
X469060D03*
X471448Y1461182D03*
Y1465913D03*
X462786Y1465513D03*
X471448Y1481267D03*
X462786Y1480867D03*
X471448Y1476536D03*
X462786Y1470244D03*
X471448Y1496621D03*
X462786Y1496221D03*
X471448Y1491890D03*
X462786Y1485598D03*
X471448Y1511976D03*
Y1507245D03*
X462786Y1511576D03*
Y1500952D03*
Y1516307D03*
X471448Y1568275D03*
Y1563544D03*
X462786Y1567875D03*
Y1572606D03*
X471448Y1578898D03*
Y1594253D03*
Y1583629D03*
X462786Y1583229D03*
Y1587960D03*
X471448Y1598984D03*
X462786Y1598584D03*
Y1603315D03*
X471448Y1609607D03*
Y1614338D03*
X462786Y1613938D03*
Y1618669D03*
X488584Y1345691D03*
Y1350683D03*
X481300Y1345691D03*
X476344D03*
X481300Y1350683D03*
X476344D03*
X488584Y1357603D03*
Y1362595D03*
X481300D03*
Y1357603D03*
X476344Y1362595D03*
Y1357603D03*
X488584Y1381801D03*
X481300D03*
X488584Y1374881D03*
Y1369889D03*
X481300D03*
Y1374881D03*
X476344Y1381801D03*
Y1369889D03*
Y1374881D03*
X488584Y1386793D03*
X481300D03*
Y1399079D03*
X476344Y1394087D03*
Y1399079D03*
X488584Y1394087D03*
X481300D03*
X488584Y1399079D03*
X476344Y1386793D03*
Y1410991D03*
X481300Y1405999D03*
X476344D03*
X488584D03*
Y1410991D03*
X481300D03*
X480109Y1465513D03*
X488771Y1465913D03*
Y1461182D03*
X480109Y1470244D03*
X488771Y1476536D03*
Y1481267D03*
X480109Y1480867D03*
Y1496221D03*
X488771Y1491890D03*
X480109Y1485598D03*
X488771Y1496621D03*
Y1511976D03*
X480109Y1511576D03*
Y1500952D03*
X488771Y1507245D03*
X480109Y1516307D03*
X488771Y1578898D03*
Y1568275D03*
Y1563544D03*
X480109Y1567875D03*
Y1572606D03*
X488771Y1583629D03*
X480109Y1583229D03*
Y1587960D03*
X488771Y1594253D03*
Y1609607D03*
Y1598984D03*
X480109Y1598584D03*
Y1603315D03*
X488771Y1614338D03*
X480109Y1613938D03*
Y1618669D03*
X500824Y1350683D03*
Y1345691D03*
X505780Y1350683D03*
Y1345691D03*
X493540D03*
Y1350683D03*
X505780Y1362595D03*
Y1357603D03*
X500824Y1362595D03*
Y1357603D03*
X493540Y1362595D03*
Y1357603D03*
Y1381801D03*
Y1374881D03*
Y1369889D03*
X505780Y1381801D03*
Y1374881D03*
Y1369889D03*
X500824D03*
Y1381801D03*
Y1374881D03*
Y1394087D03*
X505780Y1399079D03*
X500824D03*
X505780Y1394087D03*
X493540Y1386793D03*
Y1394087D03*
Y1399079D03*
X505780Y1386793D03*
X500824D03*
X505780Y1410991D03*
X500824D03*
X505780Y1405999D03*
X500824D03*
X493540D03*
Y1410991D03*
X497432Y1465513D03*
X506093Y1465913D03*
Y1461182D03*
X497432Y1480867D03*
X506093Y1481267D03*
X497432Y1470244D03*
X506093Y1476536D03*
X497432Y1496221D03*
Y1485598D03*
X506093Y1491890D03*
Y1496621D03*
Y1511976D03*
X497432Y1500952D03*
X506093Y1507245D03*
X497432Y1511576D03*
Y1516307D03*
X506093Y1578898D03*
X497432Y1567875D03*
Y1572606D03*
X506093Y1568275D03*
Y1563544D03*
X497432Y1587960D03*
X506093Y1583629D03*
Y1594253D03*
X497432Y1583229D03*
X506093Y1598984D03*
Y1609607D03*
X497432Y1598584D03*
Y1603315D03*
Y1613938D03*
Y1618669D03*
X506093Y1614338D03*
X513064Y1345691D03*
X518020Y1350683D03*
X513064D03*
X518020Y1345691D03*
Y1357603D03*
X513064Y1362595D03*
Y1357603D03*
X518020Y1362595D03*
X513064Y1369889D03*
Y1381801D03*
Y1374881D03*
X518020Y1369889D03*
Y1381801D03*
Y1374881D03*
Y1394087D03*
Y1399079D03*
X513064Y1394087D03*
Y1399079D03*
Y1386793D03*
X518020D03*
Y1405999D03*
Y1410991D03*
X513064D03*
Y1405999D03*
X514755Y1465513D03*
Y1480867D03*
Y1470244D03*
Y1485598D03*
Y1496221D03*
Y1511576D03*
Y1500952D03*
Y1516307D03*
Y1567875D03*
Y1572606D03*
Y1583229D03*
Y1587960D03*
Y1603315D03*
Y1598584D03*
Y1613938D03*
Y1618669D03*
X525304Y1345691D03*
X530260D03*
X537544Y1350683D03*
X525304D03*
X530260D03*
X537544Y1345691D03*
Y1357603D03*
X525304Y1362595D03*
X530260D03*
X525304Y1357603D03*
X530260D03*
X537544Y1362595D03*
Y1374881D03*
X525304Y1369889D03*
Y1381801D03*
Y1374881D03*
X530260Y1369889D03*
Y1381801D03*
Y1374881D03*
X537544Y1369889D03*
Y1381801D03*
Y1399079D03*
Y1394087D03*
X530260D03*
Y1399079D03*
X525304Y1394087D03*
Y1399079D03*
X537544Y1386793D03*
X525304D03*
X530260D03*
X537544Y1410991D03*
Y1405999D03*
X530260D03*
X525304D03*
X530260Y1410991D03*
X525304D03*
X542500Y1345691D03*
X549784Y1345597D03*
X542500Y1350683D03*
X549784D03*
X542500Y1362595D03*
X549784D03*
X542500Y1357603D03*
X549784D03*
X542500Y1374881D03*
X549784Y1369889D03*
Y1381801D03*
Y1374881D03*
X542500Y1369889D03*
Y1381801D03*
X554740Y1399079D03*
Y1393993D03*
X542500Y1399079D03*
X549784Y1393993D03*
Y1399079D03*
X542500Y1394087D03*
X549784Y1386793D03*
X542500D03*
X554740Y1410991D03*
Y1405999D03*
X542500Y1410991D03*
X549784D03*
X542500Y1405999D03*
X549784D03*
X562024Y1399079D03*
Y1410991D03*
Y1405999D03*
X698950Y1350683D03*
Y1345597D03*
X691666Y1350683D03*
Y1345691D03*
X698950Y1362595D03*
Y1357603D03*
X691666D03*
Y1362595D03*
X698950Y1369889D03*
X716146Y1350683D03*
X711190D03*
X716146Y1345691D03*
X711190D03*
X703906Y1350683D03*
Y1345597D03*
X716146Y1357603D03*
X711190D03*
Y1362595D03*
X716146D03*
X703906Y1357603D03*
Y1362595D03*
X716146Y1374881D03*
Y1381801D03*
Y1369889D03*
X711190D03*
Y1374881D03*
Y1381801D03*
X703906D03*
Y1369889D03*
Y1374881D03*
X716146Y1399079D03*
X711190D03*
X716146Y1393993D03*
X711190D03*
X703906Y1394087D03*
Y1399079D03*
X716146Y1386793D03*
X711190D03*
X703906D03*
X716146Y1405999D03*
X711190D03*
X716146Y1410991D03*
X711190D03*
X703906Y1405999D03*
Y1410991D03*
X723430Y1350683D03*
X728386Y1345691D03*
X723430D03*
X728386Y1350683D03*
Y1357603D03*
Y1362595D03*
X723430Y1357603D03*
Y1362595D03*
X728386Y1381801D03*
Y1374881D03*
Y1369889D03*
X723430D03*
Y1381801D03*
Y1374881D03*
X728386Y1386793D03*
X723430D03*
X728386Y1398985D03*
Y1393993D03*
X723430Y1398985D03*
Y1393993D03*
X728386Y1410897D03*
Y1405905D03*
X723430Y1410897D03*
Y1405905D03*
X747910Y1345691D03*
Y1350683D03*
X735670D03*
X740626D03*
X735670Y1345691D03*
X740626D03*
X747910Y1357603D03*
Y1362595D03*
X735670Y1357603D03*
Y1362595D03*
X740626Y1357603D03*
Y1362595D03*
X747910Y1374881D03*
Y1381801D03*
Y1369889D03*
X740626Y1381801D03*
Y1369889D03*
Y1374881D03*
X735670Y1381801D03*
Y1369889D03*
Y1374881D03*
X747910Y1386793D03*
X735670Y1393993D03*
X740626D03*
Y1398985D03*
X735670D03*
X740626Y1386793D03*
X735670D03*
Y1405905D03*
Y1410897D03*
X740626Y1405905D03*
Y1410897D03*
X765106Y1350683D03*
Y1345597D03*
X760150D03*
Y1350683D03*
X752866Y1345691D03*
Y1350683D03*
X765106Y1362595D03*
Y1357603D03*
X760150D03*
Y1362595D03*
X752866Y1357603D03*
Y1362595D03*
X765106Y1374881D03*
Y1381801D03*
Y1369889D03*
X760150Y1374881D03*
Y1381801D03*
Y1369889D03*
X752866Y1374881D03*
Y1381801D03*
Y1369889D03*
X765106Y1386793D03*
X760150D03*
X752866D03*
X772390Y1350683D03*
X777346D03*
Y1345691D03*
X772390D03*
Y1357603D03*
Y1362595D03*
X777346Y1357603D03*
Y1362595D03*
X897118Y851592D03*
X890818Y864189D03*
Y857891D03*
Y867338D03*
X900267Y851592D03*
X906565D03*
X900267Y876787D03*
X906565D03*
X912864Y873638D03*
X916014Y857891D03*
Y854742D03*
X1058891Y1345691D03*
Y1350683D03*
X1053935Y1345691D03*
Y1350683D03*
X1058891Y1362595D03*
X1053935D03*
X1058891Y1357603D03*
X1053935D03*
X1058891Y1381801D03*
Y1374881D03*
Y1369889D03*
X1053935Y1381801D03*
Y1374881D03*
Y1369889D03*
X1058891Y1386793D03*
X1053935D03*
X1066175Y1350683D03*
Y1345691D03*
X1071131Y1350683D03*
Y1345691D03*
X1066175Y1357603D03*
Y1362595D03*
X1071131Y1357603D03*
Y1362595D03*
X1066175Y1381801D03*
Y1369795D03*
Y1374881D03*
X1071131Y1381801D03*
Y1369795D03*
Y1374881D03*
X1066175Y1393993D03*
Y1399079D03*
Y1386793D03*
X1071131Y1399079D03*
Y1393993D03*
Y1386793D03*
X1066175Y1405999D03*
Y1410991D03*
X1071131Y1405999D03*
Y1410991D03*
X1090655Y1350683D03*
Y1345691D03*
X1083371D03*
Y1350683D03*
X1078415Y1345691D03*
Y1350683D03*
X1090655Y1357603D03*
Y1362595D03*
X1083371Y1357603D03*
Y1362595D03*
X1078415D03*
Y1357603D03*
X1090655Y1381801D03*
Y1374881D03*
Y1369889D03*
X1083371D03*
Y1374881D03*
Y1381801D03*
X1078415Y1369889D03*
Y1374881D03*
Y1381801D03*
X1090655Y1394087D03*
Y1399079D03*
Y1386793D03*
X1083371D03*
Y1399079D03*
Y1394087D03*
X1078415Y1386793D03*
Y1394087D03*
Y1399079D03*
X1090655Y1405999D03*
Y1410991D03*
X1083371Y1405999D03*
Y1410991D03*
X1078415Y1405999D03*
Y1410991D03*
X1107851Y1345691D03*
X1102895Y1350683D03*
Y1345691D03*
X1107851Y1350683D03*
X1095611D03*
Y1345691D03*
X1107851Y1357603D03*
X1102895Y1362595D03*
Y1357603D03*
X1107851Y1362595D03*
X1095611Y1357603D03*
Y1362595D03*
X1107851Y1369889D03*
Y1374881D03*
Y1381801D03*
X1102895Y1374881D03*
Y1369889D03*
Y1381801D03*
X1095611D03*
Y1374881D03*
Y1369889D03*
X1107851Y1386793D03*
Y1394087D03*
Y1399079D03*
X1102895Y1386793D03*
Y1394087D03*
Y1399079D03*
X1095611D03*
Y1394087D03*
Y1386793D03*
X1107851Y1405999D03*
Y1410991D03*
X1102895Y1405999D03*
Y1410991D03*
X1095611Y1405999D03*
Y1410991D03*
X1115135Y1345691D03*
Y1350683D03*
X1120091Y1345691D03*
Y1350683D03*
X1115135Y1357603D03*
Y1362595D03*
X1120091Y1357603D03*
Y1362595D03*
X1115135Y1374881D03*
Y1381801D03*
Y1369889D03*
X1120091D03*
Y1374881D03*
Y1381801D03*
X1115135Y1394087D03*
Y1399079D03*
Y1386793D03*
X1120091Y1399079D03*
Y1394087D03*
Y1386793D03*
X1115135Y1405999D03*
Y1410991D03*
X1120091Y1405999D03*
Y1410991D03*
X1139615Y1350683D03*
Y1345691D03*
X1132331D03*
Y1350683D03*
X1127375D03*
Y1345691D03*
X1139615Y1357603D03*
Y1362595D03*
X1132331D03*
Y1357603D03*
X1127375D03*
Y1362595D03*
X1139615Y1374881D03*
Y1369889D03*
Y1381801D03*
X1132331Y1369889D03*
Y1381801D03*
Y1374881D03*
X1127375Y1369889D03*
Y1381801D03*
Y1374881D03*
X1139615Y1394087D03*
Y1399079D03*
Y1386793D03*
X1132331D03*
Y1394087D03*
Y1399079D03*
X1127375Y1386793D03*
Y1394087D03*
Y1399079D03*
X1139615Y1405999D03*
Y1410991D03*
X1132331Y1405999D03*
Y1410991D03*
X1127375Y1405999D03*
Y1410991D03*
X1156811Y1350683D03*
Y1345691D03*
X1151855D03*
Y1350683D03*
X1144571D03*
Y1345691D03*
X1156811Y1357603D03*
Y1362595D03*
X1151855D03*
Y1357603D03*
X1144571D03*
Y1362595D03*
X1156811Y1374881D03*
Y1369889D03*
Y1381801D03*
X1151855Y1374881D03*
Y1369889D03*
Y1381801D03*
X1144571Y1369889D03*
Y1381801D03*
Y1374881D03*
X1156811Y1386793D03*
Y1399079D03*
Y1394087D03*
X1151855Y1386793D03*
Y1399079D03*
Y1394087D03*
X1144571D03*
Y1399079D03*
Y1386793D03*
X1156811Y1405999D03*
Y1410991D03*
X1151855Y1405999D03*
Y1410991D03*
X1144571Y1405999D03*
Y1410991D03*
X1169051Y1345597D03*
Y1350683D03*
X1164095D03*
Y1345597D03*
X1169051Y1357603D03*
Y1362595D03*
X1164095Y1357603D03*
Y1362595D03*
X1169051Y1381801D03*
Y1374881D03*
Y1369889D03*
X1164095D03*
Y1381801D03*
Y1374881D03*
X1169051Y1393993D03*
Y1399079D03*
Y1386793D03*
X1164095Y1393993D03*
Y1399079D03*
Y1386793D03*
X1169051Y1410991D03*
Y1405999D03*
X1164095D03*
Y1410991D03*
X1181291Y1350683D03*
X1176335Y1345691D03*
Y1350683D03*
X1181291Y1362595D03*
Y1357603D03*
X1176335Y1362595D03*
Y1357603D03*
X1181291Y1369889D03*
Y1381801D03*
Y1374881D03*
X1176335Y1369889D03*
Y1381801D03*
Y1374881D03*
X1181291Y1386793D03*
Y1399079D03*
Y1394087D03*
X1176335Y1386793D03*
Y1399079D03*
Y1394087D03*
X1181291Y1405999D03*
Y1410991D03*
X1176335Y1405999D03*
Y1410991D03*
X1316906Y829871D03*
X1313756Y833021D03*
Y836170D03*
Y858218D03*
X1329504Y833021D03*
Y861367D03*
X1335803Y873964D03*
Y870814D03*
X1320055Y883413D03*
X1351550Y848769D03*
Y845619D03*
Y858218D03*
X1345252D03*
Y861367D03*
X1342103Y858218D03*
X1351550Y861367D03*
X1342103Y870814D03*
X1345252D03*
Y867665D03*
X1351550Y870814D03*
Y867665D03*
X1367298Y845619D03*
X1360999Y839320D03*
X1367298Y861367D03*
X1364148Y858218D03*
Y855068D03*
X1367298Y858218D03*
X1354699D03*
X1367298Y855068D03*
X1354699Y870814D03*
X1370447Y848769D03*
X1376747D03*
Y851918D03*
Y855068D03*
X1370447Y858218D03*
X1526748Y1345691D03*
Y1350683D03*
X1521792Y1345691D03*
Y1350683D03*
X1526748Y1357603D03*
Y1362595D03*
X1521792Y1357603D03*
Y1362595D03*
X1526748Y1369889D03*
Y1374881D03*
Y1381801D03*
Y1386793D03*
Y1399079D03*
Y1394087D03*
X1546272Y1350683D03*
Y1345691D03*
X1534032Y1350683D03*
Y1345691D03*
X1538988D03*
Y1350683D03*
X1546272Y1357603D03*
Y1362595D03*
X1534032Y1357603D03*
Y1362595D03*
X1538988D03*
Y1357603D03*
X1546272Y1374881D03*
Y1369889D03*
Y1381801D03*
X1534032Y1369889D03*
Y1381801D03*
Y1374881D03*
X1538988Y1369889D03*
Y1381801D03*
Y1374881D03*
X1546272Y1386793D03*
Y1394087D03*
Y1399079D03*
X1534032Y1394087D03*
Y1399079D03*
Y1386793D03*
X1538988Y1394087D03*
Y1399079D03*
Y1386793D03*
X1546272Y1405999D03*
Y1410991D03*
X1534032Y1405999D03*
Y1410991D03*
X1538988Y1405999D03*
Y1410991D03*
X1558512Y1345691D03*
Y1350683D03*
X1563468D03*
Y1345691D03*
X1551228Y1350683D03*
Y1345691D03*
X1563468Y1362595D03*
X1551228Y1357603D03*
Y1362595D03*
X1558512D03*
Y1357603D03*
X1563468D03*
X1558512Y1374881D03*
Y1369889D03*
Y1381801D03*
X1563468Y1374881D03*
Y1369889D03*
Y1381801D03*
X1551228Y1369889D03*
Y1381801D03*
Y1374881D03*
X1558512Y1399079D03*
Y1394087D03*
Y1386793D03*
X1563468Y1399079D03*
Y1394087D03*
Y1386793D03*
X1551228D03*
Y1394087D03*
Y1399079D03*
X1558512Y1405999D03*
Y1410991D03*
X1563468Y1405999D03*
Y1410991D03*
X1551228Y1405999D03*
Y1410991D03*
X1575708Y1381801D03*
Y1374881D03*
Y1369889D03*
X1570752D03*
Y1381801D03*
Y1374881D03*
X1575708Y1386793D03*
Y1399079D03*
Y1393993D03*
X1570752Y1386793D03*
Y1393993D03*
Y1399079D03*
X1575708Y1405999D03*
Y1410991D03*
X1570752Y1405999D03*
Y1410991D03*
X1582992Y1399079D03*
Y1394087D03*
Y1405999D03*
Y1410991D03*
G54D33*
G01X1072342Y1178051D02*
X1071197D01*
X1070847Y1178401D01*
Y1179207D01*
X1069738Y1180316D01*
X1055869D01*
X1054633Y1181552D01*
Y1181554D01*
X1053497Y1182690D01*
Y1183080D01*
X1053436Y1183141D01*
G01X1068602Y1178051D02*
X1069747D01*
X1070097Y1178401D01*
Y1178896D01*
X1069427Y1179566D01*
X1055558D01*
X1052963Y1182161D01*
X1052577D01*
X1052516Y1182222D01*
G01X1313756Y833021D02*
X1315321Y831456D01*
Y827822D01*
G01X1364148Y858218D02*
X1362583Y856653D01*
Y828918D01*
G01X1360999Y839320D02*
X1359434Y837755D01*
Y833707D01*
G01X1351550Y845619D02*
X1353115Y844054D01*
Y831484D01*
G01X1368882Y828418D02*
Y844035D01*
X1367298Y845619D01*
G01X1364148Y855068D02*
X1365733Y856653D01*
X1382073D01*
G01X1368863Y862263D02*
Y859783D01*
X1367298Y858218D01*
G01Y855068D02*
X1368882Y853484D01*
Y851269D01*
X1369817Y850334D01*
X1374246D01*
X1375182Y849398D01*
Y844970D01*
X1376117Y844035D01*
X1385314D01*
G01X1372012Y830787D02*
Y847204D01*
X1370447Y848769D01*
G01X1376747D02*
X1378332Y847184D01*
X1384316D01*
G01X1376747Y851918D02*
X1378331Y850334D01*
X1386166D01*
G01X1376747Y855068D02*
X1378312Y853503D01*
X1387997D01*
G01X1370447Y858218D02*
X1372029Y859800D01*
X1392513D01*
G54D24*
X843012Y1592787D03*
Y1602787D03*
Y1612787D03*
Y1622787D03*
X853012Y1592787D03*
Y1602787D03*
Y1612787D03*
Y1622787D03*
X878012Y1592787D03*
Y1602787D03*
Y1612787D03*
Y1622787D03*
X888012Y1592787D03*
Y1602787D03*
Y1612787D03*
Y1622787D03*
X913012Y1592787D03*
Y1602787D03*
Y1612787D03*
Y1622787D03*
X923012Y1592787D03*
Y1602787D03*
Y1612787D03*
Y1622787D03*
X948012Y1592787D03*
Y1602787D03*
Y1612787D03*
Y1622787D03*
X958012Y1592787D03*
Y1602787D03*
Y1612787D03*
Y1622787D03*
X983012Y1592787D03*
X993012D03*
X983012Y1602787D03*
Y1612787D03*
X993012Y1602787D03*
Y1612787D03*
X983012Y1622787D03*
X993012D03*
X1018012Y1592787D03*
X1028012D03*
X1018012Y1602787D03*
Y1612787D03*
X1028012Y1602787D03*
Y1612787D03*
X1018012Y1622787D03*
X1028012D03*
G54D15*
X73872Y1348187D03*
X81752D03*
X73872Y1360099D03*
X81752D03*
X73872Y1384297D03*
Y1372385D03*
X81752Y1384297D03*
Y1372385D03*
X86112Y1348187D03*
X98352D03*
X93992D03*
X86112Y1360099D03*
X98352D03*
X93992D03*
X86112Y1384297D03*
Y1372385D03*
X98352Y1384297D03*
Y1372385D03*
X93992D03*
Y1384297D03*
X86112Y1396583D03*
X93992D03*
X98352D03*
X86112Y1408495D03*
X93992D03*
X98352D03*
X110592Y1348187D03*
X106232D03*
X110592Y1360099D03*
X106232D03*
X110592Y1384297D03*
X106232D03*
Y1372385D03*
X110592D03*
Y1396583D03*
X106232D03*
X110592Y1408495D03*
X106232D03*
X118472Y1348187D03*
X122832D03*
X130712D03*
X118472Y1360099D03*
X122832D03*
X130712D03*
X118472Y1384297D03*
Y1372385D03*
X122832Y1384297D03*
Y1372385D03*
X130712Y1384297D03*
Y1372385D03*
X118472Y1396583D03*
X122832D03*
X130712D03*
X118472Y1408495D03*
X122832D03*
X130712D03*
X145078Y1187401D03*
X148818D03*
X141337Y1191142D03*
X145078Y1194881D03*
Y1202362D03*
X148818Y1194881D03*
Y1202362D03*
X141337Y1198622D03*
Y1206103D03*
X145078Y1209842D03*
Y1217322D03*
X148818Y1209842D03*
Y1217322D03*
X141337Y1213583D03*
Y1221063D03*
X148818Y1224803D03*
X145078Y1232283D03*
Y1236023D03*
X148818Y1232283D03*
Y1236023D03*
X145078Y1224803D03*
X141337Y1228542D03*
X148818Y1254724D03*
X145078Y1250984D03*
X148818Y1243503D03*
Y1250984D03*
X141336Y1247242D03*
Y1239762D03*
X145078Y1243503D03*
X135072Y1348187D03*
X142952D03*
X147312D03*
X135072Y1360099D03*
X147312D03*
X142952D03*
X135072Y1384297D03*
Y1372385D03*
X147312Y1384297D03*
Y1372385D03*
X142952Y1384297D03*
Y1372385D03*
X135072Y1396583D03*
X147312D03*
X142952D03*
X135072Y1408495D03*
X147312D03*
X142952D03*
X160039Y1187401D03*
Y1194881D03*
Y1202362D03*
X156299Y1198621D03*
X152559D03*
X163779D03*
X160039D03*
X152559Y1191141D03*
X156299D03*
X160039D03*
X163779D03*
X160039Y1206102D03*
X156299D03*
X152559D03*
X163779D03*
X160039Y1209842D03*
Y1217322D03*
X156299Y1213582D03*
X152559D03*
X160039Y1221062D03*
X156299D03*
X152559D03*
X163779Y1213582D03*
Y1221062D03*
X160039Y1213582D03*
Y1228543D03*
X152559D03*
X160039Y1224803D03*
X152559D03*
X156299Y1232283D03*
Y1236023D03*
X163779D03*
Y1232283D03*
X160039Y1239763D03*
X152559D03*
Y1243503D03*
X156299Y1250984D03*
X160039Y1247243D03*
Y1243503D03*
X152559Y1247243D03*
X156299Y1239763D03*
X163779Y1250984D03*
X156299Y1254724D03*
X163779D03*
Y1239763D03*
X152559Y1258465D03*
X160039D03*
X159552Y1348187D03*
X155192D03*
X159552Y1360099D03*
X155192D03*
X159552Y1372385D03*
Y1384297D03*
X155192D03*
Y1372385D03*
X159552Y1396583D03*
X155192D03*
X159552Y1408495D03*
X155192D03*
X171259Y1187401D03*
X174999D03*
X178740D03*
X182480D03*
X171259Y1202362D03*
X167519Y1198621D03*
X171259Y1194881D03*
X174999Y1202362D03*
Y1194881D03*
X167519Y1191141D03*
X178740D03*
Y1194881D03*
Y1198621D03*
Y1202362D03*
X182480Y1191141D03*
Y1198621D03*
Y1202362D03*
X171259Y1209842D03*
X174999Y1217322D03*
X171259Y1221062D03*
X174999D03*
X171259Y1217322D03*
X174999Y1209842D03*
X167519Y1213582D03*
Y1206102D03*
Y1221062D03*
X178740Y1206102D03*
Y1209842D03*
Y1213582D03*
Y1221062D03*
X182480D03*
X178740Y1217322D03*
X182480Y1206102D03*
Y1209842D03*
Y1213582D03*
Y1217322D03*
X178740Y1232283D03*
Y1236023D03*
X174999Y1228543D03*
X171259Y1232283D03*
X174999Y1224803D03*
X171259Y1236023D03*
X182480Y1228543D03*
Y1224803D03*
X167519Y1228543D03*
Y1224803D03*
X182480Y1239763D03*
Y1243503D03*
Y1247243D03*
X171259Y1250984D03*
X178740D03*
Y1239763D03*
X174999Y1243503D03*
Y1247243D03*
X178740Y1254724D03*
X171259D03*
X174999Y1239763D03*
X171259D03*
X167519D03*
Y1243503D03*
Y1247243D03*
X175000Y1258465D03*
X182480D03*
X167519D03*
X167432Y1348187D03*
X171792D03*
X179672D03*
X167432Y1360099D03*
X171792D03*
X179672D03*
X167432Y1384297D03*
Y1372385D03*
X171792Y1384297D03*
Y1372385D03*
X179672Y1384297D03*
Y1372385D03*
X171792Y1396583D03*
X179672D03*
X167432D03*
Y1408495D03*
X171792D03*
X179672D03*
X188090Y1181791D03*
X184350Y1178051D03*
X188090Y1193011D03*
Y1196751D03*
Y1200491D03*
Y1204232D03*
X191830D03*
Y1196751D03*
Y1200491D03*
X184350Y1193011D03*
Y1196751D03*
X186220Y1198621D03*
X191830Y1207972D03*
X189960Y1209842D03*
X191830Y1219192D03*
X186220Y1221062D03*
X189960D03*
X186220Y1206102D03*
Y1209842D03*
Y1213582D03*
X189960Y1228543D03*
X186220Y1232283D03*
X189960Y1224803D03*
X186220Y1236023D03*
X197440Y1239763D03*
X186220Y1254724D03*
Y1239763D03*
X189960D03*
X186220Y1250984D03*
X189960Y1247243D03*
Y1243503D03*
Y1258465D03*
X184032Y1348187D03*
X191912D03*
X196272D03*
X184032Y1360099D03*
X196272D03*
X191912D03*
X184032Y1384297D03*
Y1372385D03*
X196272Y1384297D03*
Y1372385D03*
X191912Y1384297D03*
Y1372385D03*
X184032Y1396583D03*
X191912D03*
X196272D03*
X184032Y1408495D03*
X191912D03*
X196272D03*
X206791Y1136909D03*
X203051D03*
X199311D03*
X214271D03*
X210531D03*
X206791Y1144389D03*
X203051D03*
X199311D03*
X214271D03*
X210531D03*
X214271Y1151870D03*
X210531D03*
X206791D03*
X203051D03*
X199311D03*
X203051Y1185531D03*
X199311D03*
X206791D03*
X214271D03*
X210531D03*
X206791Y1178051D03*
X203051D03*
X199311D03*
X214271D03*
X210531D03*
X212401Y1239763D03*
X204921D03*
X208661Y1243503D03*
X204921Y1250984D03*
X208661Y1247243D03*
X212401Y1254724D03*
X201181Y1243503D03*
X212401Y1250984D03*
X201181Y1247243D03*
X204921Y1254724D03*
X204152Y1348187D03*
Y1360099D03*
Y1384297D03*
Y1372385D03*
Y1396583D03*
Y1408495D03*
X213969Y1445013D03*
Y1453293D03*
Y1456013D03*
Y1464293D03*
X225492Y1136909D03*
X221751D03*
X218011D03*
X229232D03*
X225492Y1144389D03*
X221751D03*
X218011D03*
X229232D03*
Y1151870D03*
X221752D03*
X218011D03*
X225492D03*
Y1185531D03*
X218011D03*
X221751D03*
X229232D03*
X225492Y1178051D03*
X221751D03*
X218011D03*
X229232D03*
X231102Y1243503D03*
Y1247243D03*
X223622Y1243503D03*
X216141Y1247243D03*
X223622D03*
X216141Y1243503D03*
X219881Y1250984D03*
Y1254724D03*
X227362D03*
Y1250984D03*
X227249Y1445013D03*
Y1464293D03*
Y1456013D03*
Y1453293D03*
X234841Y1093897D03*
X246062Y1105117D03*
X242321Y1097637D03*
X234841D03*
X238582Y1101376D03*
X246062D03*
X238582Y1105117D03*
X242321Y1093897D03*
X240452Y1136909D03*
X236712D03*
X244192D03*
X240452Y1151869D03*
X236712D03*
X244192D03*
X240452Y1144389D03*
X236712D03*
X244192D03*
X236712Y1189271D03*
X240452Y1185531D03*
X236712D03*
X244192D03*
X240452Y1178051D03*
X236712D03*
X244192D03*
X236712Y1193011D03*
X238582Y1247243D03*
X246062Y1243503D03*
X242322Y1250984D03*
X234842D03*
X246062Y1247243D03*
X234842Y1254724D03*
X238582Y1243503D03*
X242322Y1254724D03*
X249802Y1097637D03*
X257282D03*
X249802Y1093897D03*
X253543Y1105117D03*
Y1101376D03*
X257282Y1093897D03*
X261023Y1105117D03*
Y1101376D03*
X255413Y1136909D03*
X251673D03*
X247933D03*
X259153D03*
X262893D03*
X251673Y1144389D03*
X247933D03*
X255413D03*
X259153Y1151869D03*
X262893D03*
X247933D03*
X255413D03*
X251673D03*
X262893Y1144389D03*
X259153D03*
X262893Y1170570D03*
Y1159350D03*
X247933Y1185531D03*
X255413D03*
X251673D03*
X259153D03*
X262893D03*
X251673Y1178051D03*
X247933D03*
X255413D03*
X259153D03*
X262893D03*
X249803Y1250984D03*
X257283D03*
X253543Y1247243D03*
X257283Y1254724D03*
X249803D03*
X253543Y1243503D03*
X264762Y1097637D03*
X268503Y1105117D03*
X272243Y1097637D03*
X275984Y1105117D03*
X279723Y1093897D03*
X272243D03*
X279723Y1097637D03*
X268503Y1101376D03*
X275984D03*
X264762Y1093897D03*
X266633Y1136909D03*
Y1151869D03*
Y1144389D03*
Y1170570D03*
X270373D03*
X266633Y1159350D03*
X270373D03*
Y1166830D03*
X266633D03*
Y1185531D03*
Y1178051D03*
X283464Y1101376D03*
X294684Y1093897D03*
X287203D03*
X294684Y1097637D03*
X283464Y1105117D03*
X290944Y1101376D03*
Y1105117D03*
X287203Y1097637D03*
X294684Y1123818D03*
Y1116338D03*
Y1131299D03*
X298425Y1105117D03*
Y1101376D03*
X309644Y1097637D03*
X302164D03*
X305905Y1105117D03*
X309644Y1093897D03*
X305905Y1101376D03*
X302164Y1093897D03*
X302165Y1120078D03*
X305905Y1112598D03*
X298425Y1116338D03*
X305905Y1120078D03*
X302165Y1112598D03*
X298425Y1123818D03*
X305905Y1127559D03*
Y1135039D03*
X302165D03*
Y1127559D03*
X298425Y1131299D03*
X320866Y1090157D03*
X324606D03*
X313385Y1101377D03*
X317125Y1093897D03*
X320866Y1101377D03*
X313385Y1105117D03*
X324606Y1101377D03*
X317125Y1097637D03*
X438162Y1348187D03*
Y1360099D03*
Y1384297D03*
Y1372385D03*
X450402Y1348187D03*
X458282D03*
X446042D03*
X450402Y1360099D03*
X458282D03*
X446042D03*
X458282Y1372385D03*
X446042D03*
X458282Y1384297D03*
X446042D03*
X450402D03*
Y1372385D03*
X458282Y1396583D03*
X450402D03*
X458282Y1408495D03*
X450402D03*
X462642Y1348187D03*
X474882D03*
X470522D03*
X462642Y1360099D03*
X474882D03*
X470522D03*
X462642Y1384297D03*
X470522D03*
X474882D03*
X462642Y1372385D03*
X470522D03*
X474882D03*
X470522Y1396583D03*
X474882D03*
X462642D03*
X470522Y1408495D03*
X474882D03*
X462642D03*
X482762Y1348187D03*
X487122D03*
X482762Y1360099D03*
X487122D03*
Y1372385D03*
Y1384297D03*
X482762D03*
Y1372385D03*
Y1396583D03*
X487122D03*
X482762Y1408495D03*
X487122D03*
X507242Y1348187D03*
X495002D03*
X499362D03*
X507242Y1360099D03*
X495002D03*
X499362D03*
Y1372385D03*
Y1384297D03*
X495002D03*
X507242D03*
X495002Y1372385D03*
X507242D03*
Y1396583D03*
X495002D03*
X499362D03*
X507242Y1408495D03*
X495002D03*
X499362D03*
X519482Y1348187D03*
X511602D03*
X519482Y1360099D03*
X511602D03*
X519482Y1384297D03*
Y1372385D03*
X511602D03*
Y1384297D03*
X519482Y1396583D03*
X511602D03*
X519482Y1408495D03*
X511602D03*
X536082Y1348187D03*
X523842D03*
X531722D03*
X536082Y1360099D03*
X523842D03*
X531722D03*
Y1384297D03*
Y1372385D03*
X523842Y1384297D03*
Y1372385D03*
X536082Y1384297D03*
Y1372385D03*
X531722Y1396583D03*
X536082D03*
X523842D03*
X531722Y1408495D03*
X536082D03*
X523842D03*
X543962Y1348187D03*
Y1360099D03*
Y1372385D03*
Y1384297D03*
X556202Y1396583D03*
X543962D03*
X548322D03*
X556202Y1408495D03*
X543962D03*
X548322D03*
X600295Y1084547D03*
Y1092027D03*
X604035Y1077066D03*
Y1080806D03*
Y1084547D03*
Y1092027D03*
Y1103247D03*
X600295D03*
Y1095767D03*
X604035D03*
X600295Y1110728D03*
X604035D03*
X597795Y1170570D03*
Y1178050D03*
X602165Y1191141D03*
Y1198621D03*
Y1221062D03*
Y1206102D03*
Y1213582D03*
Y1247243D03*
X611516Y1073326D03*
X618996D03*
Y1088287D03*
Y1092027D03*
X607775Y1077066D03*
X611516D03*
X615256Y1080807D03*
X607776D03*
X615256Y1084547D03*
X607776D03*
X615256Y1088287D03*
X611516D03*
X607776D03*
X611516Y1092027D03*
X618996Y1077066D03*
X611516Y1106988D03*
X607776D03*
X611516Y1095767D03*
X615256Y1099507D03*
X607776D03*
X615256Y1103247D03*
X607776D03*
X615256Y1106988D03*
X618996Y1095767D03*
Y1106988D03*
X613386Y1187401D03*
X609646D03*
X605905Y1191141D03*
X613386Y1194881D03*
X605905Y1198621D03*
X609646Y1194881D03*
Y1202362D03*
X613386D03*
Y1217322D03*
X605905Y1221062D03*
X609646Y1217322D03*
Y1209842D03*
X605905Y1206102D03*
Y1213582D03*
X613386Y1209842D03*
X605905Y1247243D03*
X617126Y1250984D03*
X620866Y1243503D03*
Y1247243D03*
X609646Y1254724D03*
X613386Y1247243D03*
X617126Y1254724D03*
X613386Y1243503D03*
X609646Y1250984D03*
X626476Y1073326D03*
X635827Y1075196D03*
X628346D03*
X632085Y1071455D03*
X626476Y1077066D03*
Y1088287D03*
Y1092027D03*
X622736Y1080807D03*
Y1084547D03*
Y1088287D03*
X635827Y1090157D03*
X628346Y1078936D03*
Y1090157D03*
X635827Y1078936D03*
X632086Y1090157D03*
Y1082677D03*
Y1086417D03*
X630216Y1099507D03*
X622736D03*
Y1103247D03*
X626476Y1106988D03*
X622736D03*
X626476Y1095767D03*
Y1099507D03*
X630216Y1103247D03*
X635827Y1093897D03*
X632086Y1101377D03*
Y1105117D03*
X628346Y1097637D03*
Y1093897D03*
X635827Y1097637D03*
X633957Y1151870D03*
Y1148129D03*
Y1144389D03*
Y1166830D03*
Y1159350D03*
Y1174310D03*
Y1178051D03*
Y1181791D03*
X628346Y1236023D03*
Y1232283D03*
X635827Y1236023D03*
Y1232283D03*
X632086Y1247243D03*
Y1243503D03*
X635827Y1239763D03*
X632086D03*
X628346D03*
X624606D03*
X635827Y1254724D03*
Y1250984D03*
X624606Y1254724D03*
Y1250984D03*
X632087Y1258465D03*
X643307Y1075196D03*
X650787D03*
X647046Y1071455D03*
X639566D03*
X650787Y1078936D03*
X643307Y1090157D03*
X639567D03*
X647047Y1082677D03*
Y1086417D03*
X643307Y1078936D03*
X650787Y1090157D03*
X647047D03*
X639567Y1086417D03*
Y1082677D03*
Y1101377D03*
Y1105117D03*
X647047D03*
Y1101377D03*
X650787Y1097637D03*
X643307D03*
Y1093897D03*
X650787D03*
X648917Y1136909D03*
X641437Y1144389D03*
Y1185531D03*
X648917Y1193011D03*
X643307Y1236023D03*
Y1232283D03*
X650787Y1236023D03*
Y1232283D03*
X639567Y1243503D03*
Y1239763D03*
Y1247243D03*
X647047Y1243503D03*
X650787Y1239763D03*
X647047D03*
X643307D03*
X650787Y1254724D03*
Y1250984D03*
X647047Y1247243D03*
X643307Y1254724D03*
Y1250984D03*
X647047Y1258465D03*
X639567D03*
X658268Y1075196D03*
X665748D03*
X669487Y1071455D03*
X662007D03*
X654526D03*
X669488Y1090157D03*
Y1086417D03*
X665748Y1078936D03*
X669488Y1082677D03*
X665748Y1090157D03*
X654527Y1082677D03*
Y1086417D03*
Y1090157D03*
X658268D03*
X662008Y1082677D03*
Y1086417D03*
Y1090157D03*
X658268Y1078936D03*
X662008Y1101377D03*
X665748Y1093897D03*
X658268D03*
X654527Y1105117D03*
Y1101377D03*
X662008Y1105117D03*
X658268Y1097637D03*
X669488Y1101377D03*
Y1105117D03*
X665748Y1097637D03*
X658268Y1236023D03*
Y1232283D03*
X665748Y1236023D03*
Y1232283D03*
X654527Y1239763D03*
Y1243503D03*
Y1247243D03*
X662008Y1239763D03*
X658268D03*
X669488D03*
X665748D03*
Y1250984D03*
Y1254724D03*
X669488Y1247243D03*
Y1243503D03*
X662008D03*
Y1247243D03*
X658268Y1254724D03*
Y1250984D03*
X662008Y1258465D03*
X669488D03*
X654528D03*
X680709Y1075196D03*
X673228D03*
X684448Y1071455D03*
X676967D03*
X680709Y1090157D03*
X676968D03*
X684449D03*
Y1082677D03*
Y1086417D03*
X673228Y1090157D03*
Y1078936D03*
X680709D03*
X676968Y1082677D03*
Y1086417D03*
Y1105117D03*
X684449Y1101377D03*
Y1105117D03*
X680709Y1093897D03*
X676968Y1101377D03*
X680709Y1097637D03*
X673228D03*
Y1093897D03*
Y1236023D03*
Y1232283D03*
X680709Y1236023D03*
Y1232283D03*
X673228Y1239763D03*
X676968D03*
X680709D03*
Y1254724D03*
Y1250984D03*
X676968Y1243503D03*
Y1247243D03*
X673228Y1254724D03*
Y1250984D03*
X684449Y1247243D03*
Y1243503D03*
Y1239763D03*
X684450Y1258465D03*
X676969D03*
X695669Y1101376D03*
X699408Y1097637D03*
X695669Y1105117D03*
X691928Y1093897D03*
Y1097637D03*
X699408Y1093897D03*
X688189Y1236023D03*
Y1232283D03*
X695669Y1236023D03*
Y1232283D03*
X688189Y1254724D03*
Y1250984D03*
Y1239763D03*
X699409Y1247243D03*
Y1243503D03*
Y1239763D03*
X695669D03*
X691929D03*
Y1243503D03*
Y1247243D03*
X695669Y1250984D03*
Y1254724D03*
X699409Y1258465D03*
X691929D03*
X693128Y1348187D03*
X697488D03*
X693128Y1360099D03*
X697488D03*
Y1372385D03*
X714369Y1097637D03*
X706889Y1093897D03*
X703149Y1105117D03*
X718110D03*
Y1101376D03*
X710630Y1105117D03*
X714369Y1093897D03*
X706889Y1097637D03*
X703149Y1101376D03*
X710630D03*
X703149Y1236023D03*
Y1232283D03*
X710630Y1236023D03*
X718110D03*
Y1232283D03*
X710630D03*
X703149Y1254724D03*
Y1250984D03*
Y1239763D03*
X714370D03*
X718110Y1250984D03*
Y1239763D03*
X714370Y1243503D03*
Y1247243D03*
X710630Y1254724D03*
Y1250984D03*
Y1239763D03*
X706890Y1247243D03*
Y1243503D03*
Y1239763D03*
X718110Y1254724D03*
X714370Y1258465D03*
X706890D03*
X705368Y1348187D03*
X717608D03*
X709728D03*
X705368Y1360099D03*
X717608D03*
X709728D03*
Y1384297D03*
Y1372385D03*
X705368D03*
X717608D03*
Y1384297D03*
Y1396583D03*
X705368D03*
X709728D03*
X717608Y1408495D03*
X705368D03*
X709728D03*
X725590Y1101376D03*
X733071Y1105117D03*
X725590D03*
X721849Y1097637D03*
Y1093897D03*
X729330Y1097637D03*
X733071Y1101376D03*
X729330Y1093897D03*
X731201Y1129429D03*
Y1136909D03*
Y1140649D03*
Y1144389D03*
X727460Y1181791D03*
X731201Y1189271D03*
Y1185531D03*
Y1200491D03*
Y1193011D03*
X733071Y1236023D03*
Y1232283D03*
X725590Y1236023D03*
Y1232283D03*
X733071Y1239763D03*
X729331Y1243503D03*
X721850D03*
X725590Y1239763D03*
X729331D03*
X721850D03*
X729331Y1247243D03*
X733071Y1250984D03*
Y1254724D03*
X725590D03*
Y1250984D03*
X721850Y1247243D03*
X729331Y1258465D03*
X721850D03*
X734208Y1348187D03*
X729848D03*
X721968D03*
X734208Y1360099D03*
X729848D03*
X721968D03*
X729848Y1372385D03*
Y1384297D03*
X721968D03*
Y1372385D03*
X734208D03*
Y1384297D03*
X729848Y1396489D03*
X721968D03*
X734208D03*
X729848Y1408401D03*
X721968D03*
X734208D03*
X736810Y1097637D03*
X748031Y1105117D03*
X744290Y1093897D03*
X740551Y1105117D03*
X744290Y1097637D03*
X736810Y1093897D03*
X740551Y1101376D03*
X748031D03*
X738681Y1181791D03*
X748031Y1236023D03*
Y1232283D03*
X740551Y1236023D03*
Y1232283D03*
X736811Y1243503D03*
Y1239763D03*
Y1247243D03*
X748031Y1239763D03*
X744291Y1243503D03*
Y1239763D03*
X740551D03*
X748031Y1254724D03*
Y1250984D03*
X744291Y1247243D03*
X740551Y1254724D03*
Y1250984D03*
X744291Y1258465D03*
X736811D03*
X746448Y1348187D03*
X742088D03*
X746448Y1360099D03*
X742088D03*
Y1384297D03*
Y1372385D03*
X746448D03*
Y1384297D03*
X742088Y1396489D03*
Y1408401D03*
X751771Y1097637D03*
X762992Y1101376D03*
Y1105117D03*
X755512D03*
X759251Y1097637D03*
Y1093897D03*
X766731Y1097637D03*
X755512Y1101376D03*
X766731Y1093897D03*
X751771D03*
X755512Y1123818D03*
X759252Y1112598D03*
X751771Y1123818D03*
X762992Y1112598D03*
X755512Y1116338D03*
X751771D03*
X759252Y1120078D03*
X762992D03*
X751771Y1131299D03*
X762992Y1135039D03*
X755512Y1131299D03*
X762992Y1127559D03*
X759252Y1135039D03*
Y1127559D03*
X764862Y1155610D03*
Y1148129D03*
X761122D03*
Y1155610D03*
X764862Y1159350D03*
Y1170570D03*
X761122D03*
X764862Y1185531D03*
Y1178051D03*
X761122D03*
Y1185531D03*
X764862Y1189271D03*
X766732Y1194881D03*
X762992Y1191141D03*
X766732Y1202362D03*
Y1198621D03*
X762992D03*
X766732Y1221062D03*
Y1217322D03*
X762992Y1221062D03*
Y1213582D03*
X766732D03*
Y1209842D03*
Y1206102D03*
X762992D03*
X759252Y1224803D03*
Y1228543D03*
X755512Y1232283D03*
Y1236023D03*
X766732Y1224803D03*
Y1228543D03*
X762992Y1232283D03*
Y1236023D03*
X751772Y1228543D03*
X755512Y1250984D03*
Y1254724D03*
X759252Y1247243D03*
Y1243503D03*
X762992Y1250984D03*
Y1254724D03*
X766732Y1247243D03*
Y1243503D03*
X755512Y1239763D03*
X759252D03*
X762992D03*
X766732D03*
X751772Y1247243D03*
Y1243503D03*
Y1239763D03*
X766732Y1258465D03*
X759252D03*
X751772D03*
X766568Y1348187D03*
X758688D03*
X754328D03*
X766568Y1360099D03*
X758688D03*
X754328D03*
Y1372385D03*
Y1384297D03*
X758688Y1372385D03*
X766568D03*
X758688Y1384297D03*
X766568D03*
X781693Y1090157D03*
X777953D03*
X770472Y1101377D03*
X781693D03*
X777953D03*
X774212Y1097637D03*
X770472Y1105117D03*
X774212Y1093897D03*
X783563Y1140649D03*
X776083D03*
X779823D03*
X783563Y1155610D03*
Y1148129D03*
X776083D03*
Y1151869D03*
X772342D03*
X776083Y1155610D03*
X772342Y1144389D03*
X768602Y1151869D03*
Y1144389D03*
X776083D03*
X779823Y1155610D03*
Y1148129D03*
X783563Y1170570D03*
Y1166830D03*
X776083D03*
Y1170570D03*
X772342Y1166830D03*
X768602Y1159350D03*
X776083D03*
X772342D03*
X768602Y1166830D03*
X779823D03*
Y1170570D03*
X776083Y1174310D03*
X772342D03*
X776083Y1178051D03*
Y1181791D03*
Y1185531D03*
X772342Y1181791D03*
X779823Y1185531D03*
Y1178051D03*
X783563Y1185531D03*
Y1178051D03*
X768602Y1181791D03*
Y1174310D03*
X772342Y1189271D03*
X783503Y1193011D03*
X776083Y1196751D03*
X772342D03*
X776083Y1193011D03*
X779823D03*
X781693Y1202362D03*
X777953D03*
X774212Y1198621D03*
X770472D03*
X781693Y1217322D03*
X777953D03*
X774212Y1221062D03*
X770472D03*
X781693Y1209842D03*
X777953D03*
X774212Y1213582D03*
X770472D03*
X774212Y1206102D03*
X770472D03*
X781693Y1224803D03*
X777953D03*
X774212D03*
Y1228543D03*
X770472Y1236023D03*
Y1232283D03*
X781693D03*
X777953D03*
Y1236023D03*
X781693D03*
X770472Y1250984D03*
Y1254724D03*
X781693Y1250984D03*
X777953D03*
X774212Y1247243D03*
Y1243503D03*
X777953D03*
X781693D03*
X770472Y1239763D03*
X774212D03*
X777953Y1254724D03*
X774212Y1258465D03*
X778808Y1348187D03*
X770928D03*
X778808Y1360099D03*
X770928D03*
X785434Y1198621D03*
Y1221062D03*
Y1213582D03*
Y1206102D03*
Y1228543D03*
Y1247243D03*
Y1239762D03*
X1054881Y1170570D03*
X1059251Y1187401D03*
Y1183661D03*
Y1194881D03*
Y1202362D03*
X1055510Y1198622D03*
Y1191142D03*
X1059251Y1209842D03*
Y1217322D03*
X1055510Y1221063D03*
Y1213583D03*
Y1206103D03*
X1059251Y1232283D03*
Y1236023D03*
Y1224803D03*
X1055510Y1228542D03*
X1059251Y1243503D03*
Y1250984D03*
X1055509Y1239762D03*
Y1247242D03*
X1052473Y1348187D03*
Y1360099D03*
Y1384297D03*
Y1372385D03*
X1072342Y1166830D03*
X1064861Y1170570D03*
X1068602D03*
X1064861Y1166830D03*
X1068602D03*
X1061122D03*
X1072342Y1181791D03*
Y1174310D03*
X1068602D03*
X1061120D03*
X1064861D03*
X1074212Y1187401D03*
X1062991D03*
Y1183661D03*
X1066732D03*
X1070472D03*
X1074212D03*
X1072342Y1178051D03*
X1068602D03*
X1074212Y1191141D03*
Y1198621D03*
Y1194881D03*
Y1202362D03*
X1070472Y1191141D03*
X1066732D03*
X1070472Y1198621D03*
X1066732D03*
X1062991Y1194881D03*
Y1202362D03*
X1074212Y1206102D03*
X1066732D03*
X1070472D03*
X1074212Y1217322D03*
Y1209842D03*
Y1213582D03*
X1070472D03*
X1066732D03*
X1062991Y1209842D03*
Y1217322D03*
X1074212Y1221062D03*
X1066732D03*
X1070472D03*
Y1236023D03*
Y1232283D03*
X1066732Y1228543D03*
Y1224803D03*
X1074212D03*
Y1228543D03*
X1062991Y1236023D03*
Y1232283D03*
Y1224803D03*
X1070472Y1250984D03*
Y1254724D03*
X1066732Y1247243D03*
X1074212D03*
X1066732Y1239763D03*
Y1243503D03*
X1070472Y1239763D03*
X1074212D03*
Y1243503D03*
X1062991Y1250984D03*
Y1254724D03*
Y1243503D03*
X1074212Y1258465D03*
X1066732D03*
X1072593Y1348187D03*
X1064713D03*
X1060353D03*
X1072593Y1360099D03*
X1064713D03*
X1060353D03*
X1072593Y1384297D03*
Y1372385D03*
X1064713D03*
Y1384297D03*
X1060353D03*
Y1372385D03*
X1072593Y1396583D03*
X1064713D03*
X1072593Y1408495D03*
X1064713D03*
X1087302Y1170570D03*
Y1166830D03*
X1079822Y1170570D03*
Y1166830D03*
X1091043Y1170570D03*
X1079822Y1174310D03*
Y1178050D03*
X1081692Y1179921D03*
X1083562Y1181791D03*
X1087302D03*
Y1178051D03*
Y1174310D03*
X1076082Y1181791D03*
Y1178051D03*
Y1174310D03*
X1077952Y1183661D03*
X1081692D03*
X1085432D03*
X1089172Y1187401D03*
X1085432D03*
X1091043Y1185531D03*
X1077952Y1191141D03*
Y1198621D03*
X1081692D03*
Y1191141D03*
X1085432Y1194881D03*
X1089172D03*
X1085432Y1202362D03*
X1089172D03*
X1077952Y1206102D03*
Y1213582D03*
X1081692Y1206102D03*
Y1213582D03*
X1085432Y1209842D03*
X1089172D03*
X1077952Y1221062D03*
X1089172Y1217322D03*
Y1221062D03*
X1081692D03*
X1085432D03*
Y1217322D03*
X1077952Y1232283D03*
Y1236023D03*
X1085432Y1232283D03*
Y1236023D03*
X1081692Y1228543D03*
Y1224803D03*
X1089172D03*
Y1228543D03*
X1077952Y1250984D03*
Y1254724D03*
Y1239763D03*
X1081692Y1247243D03*
X1085432Y1254724D03*
X1081692Y1239763D03*
Y1243503D03*
X1085432Y1250984D03*
Y1239763D03*
X1089172D03*
Y1243503D03*
Y1247243D03*
X1089173Y1258465D03*
X1081692D03*
X1089193Y1348187D03*
X1084833D03*
X1076953D03*
X1089193Y1360099D03*
X1084833D03*
X1076953D03*
X1089193Y1384297D03*
Y1372385D03*
X1084833Y1384297D03*
Y1372385D03*
X1076953Y1384297D03*
Y1372385D03*
X1089193Y1396583D03*
X1084833D03*
X1076953D03*
X1089193Y1408495D03*
X1084833D03*
X1076953D03*
X1102263Y1170570D03*
X1094783D03*
Y1166830D03*
X1106003D03*
X1102263Y1178051D03*
X1094783Y1181791D03*
X1102263Y1185531D03*
X1094783Y1174310D03*
Y1178051D03*
X1106003Y1181791D03*
Y1174310D03*
X1092913Y1187401D03*
X1098523Y1196751D03*
Y1193011D03*
X1106003Y1200491D03*
Y1196751D03*
Y1204232D03*
X1102263D03*
X1098523D03*
Y1200491D03*
X1102263D03*
Y1196751D03*
Y1193011D03*
X1092913Y1191141D03*
Y1194881D03*
Y1198621D03*
Y1202362D03*
X1098523Y1207972D03*
X1102263D03*
X1106003D03*
Y1211712D03*
X1102263D03*
X1098523D03*
Y1219192D03*
X1106003D03*
X1092913Y1206102D03*
Y1209842D03*
Y1213582D03*
Y1217322D03*
X1107873Y1221062D03*
X1104133D03*
X1100393D03*
X1096653D03*
X1092913D03*
Y1232283D03*
Y1236023D03*
X1107873Y1232283D03*
X1104133Y1224803D03*
Y1228543D03*
X1107873Y1236023D03*
X1100393Y1232283D03*
Y1236023D03*
X1096653Y1228543D03*
Y1224803D03*
X1092913Y1250984D03*
Y1254724D03*
Y1239763D03*
X1100393Y1250984D03*
Y1254724D03*
X1104133Y1247243D03*
X1107873Y1250984D03*
Y1254724D03*
X1100393Y1239763D03*
X1104133D03*
X1107873D03*
X1104133Y1243503D03*
X1096653Y1247243D03*
Y1239763D03*
Y1243503D03*
X1104133Y1258465D03*
X1096653D03*
X1101433Y1348187D03*
X1097073D03*
X1101433Y1360099D03*
X1097073D03*
X1101433Y1384297D03*
Y1372385D03*
X1097073D03*
Y1384297D03*
X1101433Y1396583D03*
X1097073D03*
X1101433Y1408495D03*
X1097073D03*
X1120964Y1129429D03*
X1113484D03*
X1117224D03*
X1124704D03*
X1117224Y1170570D03*
X1109743D03*
X1113484Y1166830D03*
X1120964D03*
X1124704Y1170570D03*
X1109743Y1189271D03*
X1113484D03*
X1117224D03*
X1120964D03*
X1113484Y1181791D03*
X1117224D03*
X1120964D03*
X1124704Y1189271D03*
Y1181791D03*
X1109743Y1178051D03*
X1120964Y1174310D03*
X1109743Y1185531D03*
X1113484Y1174310D03*
X1124704Y1196751D03*
X1109743Y1204232D03*
Y1193011D03*
Y1196751D03*
Y1200491D03*
X1113484Y1196751D03*
X1117224D03*
X1120964D03*
X1117224Y1200491D03*
X1120964D03*
X1113484D03*
X1124704D03*
X1109743Y1211712D03*
Y1207972D03*
X1122834Y1243503D03*
X1119094Y1250984D03*
Y1254724D03*
X1122834Y1247243D03*
X1115354Y1243503D03*
Y1247243D03*
X1113673Y1348187D03*
X1121553D03*
X1109313D03*
X1113673Y1360099D03*
X1121553D03*
X1109313D03*
X1113673Y1372385D03*
Y1384297D03*
X1121553Y1372385D03*
Y1384297D03*
X1109313D03*
Y1372385D03*
X1113673Y1396583D03*
X1121553D03*
X1109313D03*
X1113673Y1408495D03*
X1121553D03*
X1109313D03*
X1132184Y1129429D03*
X1128444D03*
X1135924D03*
X1139665D03*
Y1170570D03*
X1132184D03*
X1135925Y1166830D03*
X1128444D03*
X1135924Y1181791D03*
X1132184D03*
X1128444D03*
X1135924Y1189271D03*
X1132184D03*
X1128444D03*
Y1174310D03*
X1135924D03*
X1139665Y1181791D03*
Y1189271D03*
Y1196751D03*
X1135924D03*
X1132184D03*
X1128444D03*
X1132184Y1200491D03*
X1128444D03*
X1135924D03*
X1139665D03*
X1126574Y1254724D03*
X1137795Y1243503D03*
X1130314Y1247243D03*
X1126574Y1250984D03*
X1137795Y1247243D03*
X1130314Y1243503D03*
X1134054Y1250984D03*
Y1254724D03*
X1138153Y1348187D03*
X1133793D03*
X1125913D03*
X1138153Y1360099D03*
X1133793D03*
X1125913D03*
X1138153Y1384297D03*
Y1372385D03*
X1133793Y1384297D03*
Y1372385D03*
X1125913Y1384297D03*
Y1372385D03*
X1138153Y1396583D03*
X1133793D03*
X1125913D03*
X1138153Y1408495D03*
X1133793D03*
X1125913D03*
X1149014Y1097637D03*
X1156494Y1093897D03*
X1152755Y1101376D03*
X1156494Y1097637D03*
X1149014Y1093897D03*
X1152755Y1105117D03*
X1154625Y1129429D03*
X1150885D03*
X1143405D03*
Y1166830D03*
Y1181791D03*
Y1189271D03*
Y1174310D03*
X1150885Y1196751D03*
X1143405D03*
Y1200491D03*
X1154625D03*
X1150885D03*
X1143405Y1193011D03*
X1141535Y1254724D03*
Y1250984D03*
X1149015Y1254724D03*
X1145275Y1247243D03*
X1152755Y1243503D03*
X1156495Y1254724D03*
X1145275Y1243503D03*
X1152755Y1247243D03*
X1149015Y1250984D03*
X1156495D03*
X1150393Y1348187D03*
X1146033D03*
X1150393Y1360099D03*
X1146033D03*
X1150393Y1384297D03*
Y1372385D03*
X1146033D03*
Y1384297D03*
X1150393Y1396583D03*
X1146033D03*
X1150393Y1408495D03*
X1146033D03*
X1160235Y1105117D03*
Y1101376D03*
X1171455Y1093897D03*
X1167716Y1105117D03*
X1171455Y1097637D03*
X1163975Y1093897D03*
Y1097637D03*
X1167716Y1101376D03*
X1169586Y1129429D03*
X1165846D03*
X1162106D03*
X1158365D03*
X1173326D03*
Y1200491D03*
X1165846D03*
X1162106D03*
X1158365D03*
X1169586D03*
X1171456Y1250984D03*
X1167716Y1247243D03*
X1163976Y1250984D03*
X1160235Y1247243D03*
Y1243503D03*
X1167716D03*
X1171456Y1254724D03*
X1163976D03*
X1162633Y1348187D03*
X1170513D03*
X1158273D03*
X1162633Y1360099D03*
X1170513D03*
X1158273D03*
X1162633Y1372385D03*
Y1384297D03*
X1170513Y1372385D03*
Y1384297D03*
X1158273D03*
Y1372385D03*
X1162633Y1396583D03*
X1170513D03*
X1158273D03*
X1162633Y1408495D03*
X1170513D03*
X1158273D03*
X1178935Y1097637D03*
X1186416Y1093897D03*
X1182676Y1105117D03*
X1175196D03*
X1178935Y1093897D03*
X1182676Y1101376D03*
X1175196D03*
X1186416Y1097637D03*
X1180806Y1129429D03*
X1177066D03*
X1180806Y1200491D03*
X1177066D03*
X1178936Y1247243D03*
X1182676Y1250984D03*
Y1254724D03*
X1186417Y1247243D03*
X1178936Y1243503D03*
X1186417D03*
Y1258465D03*
X1182753Y1360099D03*
X1174873D03*
X1182753Y1384297D03*
Y1372385D03*
X1174873Y1384297D03*
Y1372385D03*
X1182753Y1396583D03*
X1174873D03*
X1182753Y1408495D03*
X1174873D03*
X1201376Y1093897D03*
X1193896Y1097637D03*
X1197637Y1105117D03*
X1205117D03*
X1197637Y1101376D03*
X1205117D03*
X1190157D03*
X1193896Y1093897D03*
X1201376Y1097637D03*
X1190157Y1105117D03*
X1199507Y1155610D03*
Y1170570D03*
Y1166830D03*
Y1159350D03*
Y1174310D03*
X1190157Y1254724D03*
Y1250984D03*
X1197637D03*
Y1254724D03*
X1201377Y1247243D03*
X1205117Y1250984D03*
Y1254724D03*
X1201377Y1243503D03*
X1193897Y1247243D03*
Y1243503D03*
X1201377Y1258465D03*
X1193897D03*
X1220078Y1105117D03*
X1216337Y1093897D03*
X1212598Y1101376D03*
Y1105117D03*
X1208857Y1093897D03*
X1216337Y1097637D03*
X1220078Y1101376D03*
X1208857Y1097637D03*
X1212598Y1123818D03*
X1208857Y1116338D03*
X1212598D03*
X1216338Y1120078D03*
Y1112598D03*
X1208857Y1123818D03*
X1220078Y1112598D03*
Y1120078D03*
X1216338Y1127559D03*
Y1135039D03*
X1212598Y1131299D03*
X1208857D03*
X1220078Y1135039D03*
Y1127559D03*
X1212598Y1250984D03*
Y1254724D03*
X1216338Y1247243D03*
Y1243503D03*
X1220078Y1250984D03*
Y1254724D03*
X1208858Y1247243D03*
Y1243503D03*
X1216338Y1258465D03*
X1208858D03*
X1235039Y1090157D03*
X1227558Y1101377D03*
X1231298Y1093897D03*
X1235039Y1101377D03*
X1227558Y1105117D03*
X1223817Y1093897D03*
Y1097637D03*
X1231298D03*
X1223818Y1247243D03*
Y1243503D03*
X1227558Y1250984D03*
Y1254724D03*
X1235039Y1250984D03*
X1231298Y1247243D03*
Y1243503D03*
X1235039D03*
Y1254724D03*
X1231298Y1258465D03*
X1223818D03*
X1238779Y1090157D03*
Y1101377D03*
Y1250984D03*
Y1243503D03*
X1242520Y1247243D03*
X1523819Y1187401D03*
X1527559D03*
X1516338Y1198621D03*
X1523819Y1194881D03*
X1520078Y1198621D03*
X1523819Y1202362D03*
X1516338Y1191141D03*
X1527559Y1202362D03*
Y1194881D03*
X1520078Y1191141D03*
Y1221062D03*
X1516338Y1213582D03*
Y1206102D03*
X1520078D03*
X1527559Y1217322D03*
X1523819Y1209842D03*
X1516338Y1221062D03*
X1527559Y1209842D03*
X1523819Y1217322D03*
X1520078Y1213582D03*
X1516338Y1232283D03*
Y1236023D03*
X1527559D03*
Y1232283D03*
X1520078Y1236023D03*
Y1232283D03*
X1523819Y1239763D03*
X1520078Y1247243D03*
X1516338D03*
X1527559Y1243503D03*
Y1247243D03*
X1523819Y1250984D03*
Y1254724D03*
X1528210Y1348187D03*
X1520330D03*
X1528210Y1360099D03*
X1520330D03*
X1528210Y1396583D03*
X1546258Y1071455D03*
X1546259Y1082677D03*
Y1086417D03*
Y1090157D03*
X1544389Y1099507D03*
Y1106988D03*
X1546259Y1101377D03*
Y1105117D03*
X1544389Y1110728D03*
X1535039Y1232283D03*
Y1236023D03*
X1542519Y1232283D03*
Y1236023D03*
X1531299Y1239763D03*
X1538779D03*
X1542519D03*
X1546259D03*
Y1243503D03*
Y1247243D03*
X1538779Y1250984D03*
Y1254724D03*
X1535039Y1243503D03*
X1531299Y1250984D03*
X1535039Y1247243D03*
X1531299Y1254724D03*
X1546260Y1258465D03*
X1544810Y1348187D03*
X1532570D03*
X1540450D03*
X1544810Y1360099D03*
X1532570D03*
X1540450D03*
X1544810Y1384297D03*
Y1372385D03*
X1532570Y1384297D03*
Y1372385D03*
X1540450Y1384297D03*
Y1372385D03*
X1544810Y1396583D03*
X1532570D03*
X1540450D03*
X1544810Y1408495D03*
X1532570D03*
X1540450D03*
X1557480Y1075196D03*
X1550000D03*
X1561219Y1071455D03*
X1553739D03*
X1561220Y1086417D03*
Y1090157D03*
Y1082677D03*
X1557480Y1078936D03*
Y1090157D03*
X1553740Y1082677D03*
Y1086417D03*
Y1090157D03*
X1550000Y1078936D03*
Y1090157D03*
X1561220Y1105117D03*
X1553740D03*
X1561220Y1101377D03*
X1557480Y1097637D03*
Y1093897D03*
X1553740Y1101377D03*
X1550000Y1093897D03*
Y1097637D03*
X1548130Y1110728D03*
X1561220Y1108858D03*
X1557480D03*
X1553740D03*
X1550000D03*
X1551870Y1110728D03*
X1563090Y1136909D03*
X1555610Y1144389D03*
X1548130Y1151870D03*
Y1148129D03*
Y1144389D03*
Y1166830D03*
Y1159350D03*
Y1174310D03*
Y1178051D03*
Y1181791D03*
X1555610Y1185531D03*
X1563090Y1193011D03*
X1550000Y1232283D03*
Y1236023D03*
X1557480Y1232283D03*
Y1236023D03*
X1550000Y1250984D03*
Y1254724D03*
Y1239763D03*
X1557480Y1250984D03*
Y1254724D03*
X1561220Y1247243D03*
X1557480Y1239763D03*
X1561220D03*
Y1243503D03*
X1553740Y1247243D03*
Y1239763D03*
Y1243503D03*
X1561220Y1258465D03*
X1553740D03*
X1557050Y1348187D03*
X1552690D03*
Y1360099D03*
X1557050D03*
Y1384297D03*
Y1372385D03*
X1552690D03*
Y1384297D03*
X1557050Y1396583D03*
X1552690D03*
X1557050Y1408495D03*
X1552690D03*
X1572441Y1075196D03*
X1564960D03*
X1576180Y1071455D03*
X1568699D03*
X1564960Y1090157D03*
Y1078936D03*
X1572441Y1090157D03*
Y1078936D03*
X1576181Y1082677D03*
Y1086417D03*
Y1090157D03*
X1568700Y1082677D03*
Y1086417D03*
Y1090157D03*
X1576181Y1105117D03*
X1568700D03*
X1564960Y1093897D03*
Y1097637D03*
X1572441Y1093897D03*
Y1097637D03*
X1576181Y1101377D03*
X1568700D03*
X1576181Y1108858D03*
X1572441D03*
X1568700D03*
X1564960D03*
Y1232283D03*
Y1236023D03*
X1572441Y1232283D03*
Y1236023D03*
X1564960Y1250984D03*
Y1254724D03*
Y1239763D03*
X1572441Y1250984D03*
Y1254724D03*
X1576181Y1247243D03*
Y1243503D03*
X1572441Y1239763D03*
X1576181D03*
X1568700Y1247243D03*
Y1243503D03*
Y1239763D03*
X1576181Y1258465D03*
X1568701D03*
X1564930Y1348187D03*
X1569290D03*
Y1360099D03*
X1564930D03*
X1569290Y1372385D03*
Y1384297D03*
X1564930D03*
Y1372385D03*
X1577170Y1396583D03*
X1569290D03*
X1564930D03*
X1577170Y1408495D03*
X1569290D03*
X1564930D03*
X1579921Y1075196D03*
X1587401D03*
X1594882D03*
X1591140Y1071455D03*
X1583660D03*
X1579921Y1090157D03*
X1583661D03*
Y1086417D03*
Y1082677D03*
X1579921Y1078936D03*
X1587401Y1090157D03*
Y1078936D03*
X1591141Y1082677D03*
Y1086417D03*
Y1090157D03*
X1594882D03*
Y1078936D03*
X1583661Y1105117D03*
X1591141D03*
X1579921Y1093897D03*
Y1097637D03*
X1583661Y1101377D03*
X1587401Y1097637D03*
Y1093897D03*
X1594882D03*
Y1097637D03*
X1591141Y1101377D03*
X1594882Y1108858D03*
X1591141D03*
X1587401D03*
X1583661D03*
X1579921D03*
Y1232283D03*
Y1236023D03*
X1594882Y1232283D03*
Y1236023D03*
X1587401Y1232283D03*
Y1236023D03*
X1583661Y1243503D03*
Y1247243D03*
X1579921Y1254724D03*
Y1250984D03*
Y1239763D03*
X1583661D03*
X1587401Y1250984D03*
Y1254724D03*
X1591141Y1247243D03*
Y1243503D03*
X1594882Y1250984D03*
Y1254724D03*
Y1239763D03*
X1591141D03*
X1587401D03*
X1591142Y1258465D03*
X1583661D03*
X1581530Y1396583D03*
Y1408495D03*
X1598621Y1071455D03*
X1598622Y1082677D03*
Y1086417D03*
Y1090157D03*
X1606101Y1093897D03*
X1598622Y1105117D03*
Y1101377D03*
X1609842Y1101376D03*
Y1105117D03*
X1606101Y1097637D03*
X1602362Y1108858D03*
X1598622D03*
X1609842Y1232283D03*
Y1236023D03*
X1602362Y1232283D03*
Y1236023D03*
X1598622Y1239763D03*
Y1243503D03*
Y1247243D03*
X1609842Y1254724D03*
Y1250984D03*
X1606102Y1247243D03*
Y1243503D03*
Y1239763D03*
X1609842D03*
X1602362D03*
Y1250984D03*
Y1254724D03*
X1606102Y1258465D03*
X1598623D03*
X1621062Y1093897D03*
X1617322Y1105117D03*
Y1101376D03*
X1613581Y1093897D03*
Y1097637D03*
X1624803Y1101376D03*
Y1105117D03*
X1621062Y1097637D03*
X1624803Y1232283D03*
Y1236023D03*
X1617322Y1232283D03*
Y1236023D03*
X1613582Y1239763D03*
Y1243503D03*
Y1247243D03*
X1621063Y1239763D03*
Y1243503D03*
Y1247243D03*
X1624803Y1239763D03*
Y1250984D03*
Y1254724D03*
X1617322Y1239763D03*
Y1250984D03*
Y1254724D03*
X1621063Y1258465D03*
X1613582D03*
X1639763Y1101376D03*
X1628542Y1093897D03*
X1636022D03*
X1639763Y1105117D03*
X1632283D03*
Y1101376D03*
X1636022Y1097637D03*
X1643503D03*
Y1093897D03*
X1628542Y1097637D03*
X1641633Y1181791D03*
X1632283Y1232283D03*
Y1236023D03*
X1639763Y1232283D03*
Y1236023D03*
X1632283Y1254724D03*
X1628543Y1247243D03*
Y1243503D03*
X1632283Y1239763D03*
Y1250984D03*
X1628543Y1239763D03*
X1636023Y1247243D03*
X1639763Y1250984D03*
Y1254724D03*
X1643504Y1247243D03*
X1636023Y1239763D03*
X1643504D03*
X1639763D03*
X1636023Y1243503D03*
X1643504D03*
Y1258465D03*
X1636023D03*
X1628543D03*
X1658463Y1097637D03*
X1647244Y1101376D03*
X1658463Y1093897D03*
X1654724Y1105117D03*
X1650983Y1093897D03*
X1647244Y1105117D03*
X1654724Y1101376D03*
X1650983Y1097637D03*
X1645374Y1129429D03*
Y1136909D03*
Y1140649D03*
Y1144389D03*
X1652854Y1181791D03*
X1645374Y1185531D03*
Y1189271D03*
Y1200491D03*
Y1193011D03*
X1647244Y1232283D03*
Y1236023D03*
X1654724Y1232283D03*
Y1236023D03*
X1647244Y1254724D03*
Y1250984D03*
Y1239763D03*
X1654724Y1250984D03*
Y1254724D03*
X1658464Y1247243D03*
X1654724Y1239763D03*
X1658464D03*
Y1243503D03*
X1650984Y1247243D03*
Y1239763D03*
Y1243503D03*
X1658464Y1258465D03*
X1650984D03*
X1665944Y1093897D03*
X1662204Y1105117D03*
X1669685D03*
X1673424Y1097637D03*
X1669685Y1101376D03*
X1673424Y1093897D03*
X1665944Y1097637D03*
X1662204Y1101376D03*
X1673425Y1112598D03*
X1665944Y1123818D03*
X1673425Y1120078D03*
X1669685Y1123818D03*
X1665944Y1116338D03*
X1669685D03*
X1665944Y1131299D03*
X1669685D03*
X1673425Y1127559D03*
Y1135039D03*
X1675295Y1155610D03*
Y1148129D03*
Y1170570D03*
Y1185531D03*
Y1178051D03*
Y1193011D03*
X1662204Y1232283D03*
Y1236023D03*
X1673425Y1224803D03*
Y1228543D03*
X1669685Y1232283D03*
Y1236023D03*
X1665945Y1247243D03*
Y1243503D03*
Y1239763D03*
X1662204Y1250984D03*
Y1254724D03*
Y1239763D03*
X1669685Y1250984D03*
Y1254724D03*
X1673425Y1247243D03*
Y1243503D03*
X1669685Y1239763D03*
X1673425D03*
Y1258465D03*
X1665945D03*
X1692126Y1090157D03*
Y1101377D03*
X1684645D03*
X1677165Y1105117D03*
X1680904Y1097637D03*
X1677165Y1101376D03*
X1688385Y1097637D03*
X1684645Y1105117D03*
X1680904Y1093897D03*
X1688385D03*
X1677165Y1120078D03*
Y1112598D03*
X1690256Y1140649D03*
X1677165Y1135039D03*
Y1127559D03*
X1690256Y1144389D03*
X1682775D03*
X1679035Y1148129D03*
X1682775Y1151869D03*
X1679035Y1155610D03*
X1686515Y1144389D03*
X1690256Y1155610D03*
X1686515Y1151869D03*
X1690256D03*
Y1148129D03*
X1682775Y1166830D03*
X1679035Y1170570D03*
X1686515Y1159350D03*
X1690256D03*
X1682775D03*
X1679035D03*
X1686515Y1166830D03*
X1690256Y1170570D03*
Y1166830D03*
Y1178051D03*
X1686515Y1174310D03*
X1690256D03*
X1682775D03*
X1679035Y1178051D03*
X1682775Y1181791D03*
X1679035Y1185531D03*
X1682775Y1189271D03*
X1686515Y1181791D03*
Y1189271D03*
X1690256D03*
Y1185531D03*
Y1181791D03*
X1680905Y1194881D03*
X1690256Y1193011D03*
X1679035D03*
X1692126Y1202362D03*
X1688385Y1198621D03*
X1684645D03*
X1680905Y1202362D03*
Y1198621D03*
X1677165D03*
X1692126Y1217322D03*
X1688385Y1221062D03*
X1684645D03*
X1692126Y1209842D03*
X1688385Y1213582D03*
X1684645D03*
X1680905Y1221062D03*
Y1217322D03*
X1677165Y1221062D03*
Y1213582D03*
X1680905D03*
Y1209842D03*
X1688385Y1206102D03*
X1684645D03*
X1680905D03*
X1677165D03*
X1692126Y1224803D03*
X1688385D03*
Y1228543D03*
X1684645Y1236023D03*
Y1232283D03*
X1692126D03*
Y1236023D03*
X1680905Y1224803D03*
Y1228543D03*
X1677165Y1232283D03*
Y1236023D03*
X1684645Y1250984D03*
Y1254724D03*
X1692126Y1250984D03*
X1688385Y1247243D03*
Y1243503D03*
X1692126D03*
X1684645Y1239763D03*
X1688385D03*
X1692126Y1254724D03*
X1677165Y1250984D03*
Y1254724D03*
X1680905Y1247243D03*
Y1243503D03*
X1677165Y1239763D03*
X1680905D03*
X1688385Y1258465D03*
X1680905D03*
X1695866Y1090157D03*
Y1101377D03*
X1697736Y1140649D03*
X1693996D03*
X1697736Y1148129D03*
X1693996D03*
X1697736Y1155610D03*
X1693996D03*
Y1170570D03*
Y1166830D03*
X1697736D03*
Y1170570D03*
Y1178051D03*
X1693996D03*
X1697736Y1185531D03*
X1693996D03*
Y1193011D03*
X1697676D03*
X1695866Y1202362D03*
X1699607Y1198621D03*
X1695866Y1217322D03*
Y1209842D03*
X1699607Y1221062D03*
Y1213582D03*
Y1206102D03*
X1695866Y1232283D03*
Y1236023D03*
Y1224803D03*
X1699607Y1228543D03*
X1695866Y1250984D03*
Y1243503D03*
X1699607Y1247243D03*
Y1239762D03*
G54D34*
G01X233527Y1068787D02*
Y1068899D01*
X233347Y1069079D01*
Y1094985D01*
X233754Y1095392D01*
X234391D01*
X234841Y1094942D01*
Y1093897D01*
G01X232417Y1068787D02*
Y1068899D01*
X232597Y1069079D01*
Y1095296D01*
X233443Y1096142D01*
X234391D01*
X234841Y1096592D01*
Y1097637D01*
G01X236157Y1069000D02*
Y1069112D01*
X236337Y1069292D01*
Y1102775D01*
X237184Y1103622D01*
X238132D01*
X238582Y1104072D01*
Y1105117D01*
G01Y1101376D02*
Y1102422D01*
X238132Y1102872D01*
X237495D01*
X237087Y1102464D01*
Y1069292D01*
X237267Y1069112D01*
Y1069000D01*
G01X239897Y1068787D02*
Y1068899D01*
X240077Y1069079D01*
Y1095296D01*
X240923Y1096142D01*
X241871D01*
X242321Y1096592D01*
Y1097637D01*
G01X243637Y1069000D02*
Y1069112D01*
X243817Y1069292D01*
Y1102775D01*
X244664Y1103622D01*
X245612D01*
X246062Y1104072D01*
Y1105117D01*
G01X244747Y1069000D02*
Y1069112D01*
X244567Y1069292D01*
Y1102464D01*
X244975Y1102872D01*
X245612D01*
X246062Y1102422D01*
Y1101376D01*
G01X242321Y1093897D02*
Y1094942D01*
X241871Y1095392D01*
X241234D01*
X240827Y1094985D01*
Y1069079D01*
X241007Y1068899D01*
Y1068787D01*
G01X247378D02*
Y1068899D01*
X247558Y1069079D01*
Y1095296D01*
X248404Y1096142D01*
X249352D01*
X249802Y1096592D01*
Y1097637D01*
G01Y1093897D02*
Y1094942D01*
X249352Y1095392D01*
X248715D01*
X248308Y1094985D01*
Y1069079D01*
X248488Y1068899D01*
Y1068787D01*
G01X251118Y1069000D02*
Y1069112D01*
X251298Y1069292D01*
Y1102775D01*
X252145Y1103622D01*
X253093D01*
X253543Y1104072D01*
Y1105117D01*
G01Y1101376D02*
Y1102422D01*
X253093Y1102872D01*
X252456D01*
X252048Y1102464D01*
Y1069292D01*
X252228Y1069112D01*
Y1069000D01*
G01X257282Y1097637D02*
Y1096592D01*
X256832Y1096142D01*
X255884D01*
X255038Y1095296D01*
Y1069079D01*
X254858Y1068899D01*
Y1068787D01*
G01X257282Y1093897D02*
Y1094942D01*
X256832Y1095392D01*
X256195D01*
X255788Y1094985D01*
Y1069079D01*
X255968Y1068899D01*
Y1068787D01*
G01X261023Y1105117D02*
Y1104072D01*
X260573Y1103622D01*
X259625D01*
X258778Y1102775D01*
Y1069292D01*
X258598Y1069112D01*
Y1069000D01*
G01X259708D02*
Y1069112D01*
X259528Y1069292D01*
Y1102464D01*
X259936Y1102872D01*
X260573D01*
X261023Y1102422D01*
Y1101376D01*
G01X264762Y1097637D02*
Y1096592D01*
X264312Y1096142D01*
X263364D01*
X262518Y1095296D01*
Y1069079D01*
X262338Y1068899D01*
Y1068787D01*
G01X264762Y1093897D02*
Y1094942D01*
X264312Y1095392D01*
X263675D01*
X263268Y1094985D01*
Y1069079D01*
X263448Y1068899D01*
Y1068787D01*
G01X266078Y1069000D02*
Y1069112D01*
X266258Y1069292D01*
Y1102775D01*
X267105Y1103622D01*
X268053D01*
X268503Y1104072D01*
Y1105117D01*
G01Y1101376D02*
Y1102422D01*
X268053Y1102872D01*
X267416D01*
X267008Y1102464D01*
Y1069292D01*
X267188Y1069112D01*
Y1069000D01*
G01X269819Y1068787D02*
Y1068899D01*
X269999Y1069079D01*
Y1095296D01*
X270845Y1096142D01*
X271793D01*
X272243Y1096592D01*
Y1097637D01*
G01X270929Y1068787D02*
Y1068899D01*
X270749Y1069079D01*
Y1094985D01*
X271156Y1095392D01*
X271793D01*
X272243Y1094942D01*
Y1093897D01*
G01X275984Y1105117D02*
Y1104072D01*
X275534Y1103622D01*
X274586D01*
X273739Y1102775D01*
Y1069292D01*
X273559Y1069112D01*
Y1069000D01*
G01X279723Y1093897D02*
Y1094942D01*
X279273Y1095392D01*
X278636D01*
X278229Y1094985D01*
Y1069079D01*
X278409Y1068899D01*
Y1068787D01*
G01X279723Y1097637D02*
Y1096592D01*
X279273Y1096142D01*
X278325D01*
X277479Y1095296D01*
Y1069079D01*
X277299Y1068899D01*
Y1068787D01*
G01X274669Y1069000D02*
Y1069112D01*
X274489Y1069292D01*
Y1102464D01*
X274897Y1102872D01*
X275534D01*
X275984Y1102422D01*
Y1101376D01*
G01X283464D02*
Y1102422D01*
X283014Y1102872D01*
X282377D01*
X281969Y1102464D01*
Y1069292D01*
X282149Y1069112D01*
Y1069000D01*
G01X283464Y1105117D02*
Y1104072D01*
X283014Y1103622D01*
X282066D01*
X281219Y1102775D01*
Y1069292D01*
X281039Y1069112D01*
Y1069000D01*
G01X287203Y1097637D02*
Y1096592D01*
X286753Y1096142D01*
X285805D01*
X284959Y1095296D01*
Y1069079D01*
X284779Y1068899D01*
Y1068787D01*
G01X285889D02*
Y1068899D01*
X285709Y1069079D01*
Y1094985D01*
X286116Y1095392D01*
X286753D01*
X287203Y1094942D01*
Y1093897D01*
G01X290944Y1101376D02*
Y1102422D01*
X290494Y1102872D01*
X289857D01*
X289449Y1102464D01*
Y1069292D01*
X289629Y1069112D01*
Y1069000D01*
G01X290944Y1105117D02*
Y1104072D01*
X290494Y1103622D01*
X289546D01*
X288699Y1102775D01*
Y1069292D01*
X288519Y1069112D01*
Y1069000D01*
G01X206236Y1259424D02*
Y1259312D01*
X206416Y1259132D01*
Y1246087D01*
X207505Y1244998D01*
X208311D01*
X208661Y1244648D01*
Y1243503D01*
G01X213716Y1259424D02*
Y1259312D01*
X213896Y1259132D01*
Y1246087D01*
X214985Y1244998D01*
X215791D01*
X216141Y1244648D01*
Y1243503D01*
G01X202496Y1259624D02*
Y1259512D01*
X202676Y1259332D01*
Y1253568D01*
X203765Y1252479D01*
X204571D01*
X204921Y1252129D01*
Y1250984D01*
G01X207346Y1259424D02*
Y1259312D01*
X207166Y1259132D01*
Y1246398D01*
X207816Y1245748D01*
X208311D01*
X208661Y1246098D01*
Y1247243D01*
G01X212401Y1254724D02*
Y1253579D01*
X212051Y1253229D01*
X211556D01*
X210906Y1253879D01*
Y1259132D01*
X211086Y1259312D01*
Y1259424D01*
G01X198756Y1259812D02*
Y1259700D01*
X198936Y1259520D01*
Y1246087D01*
X200025Y1244998D01*
X200831D01*
X201181Y1244648D01*
Y1243503D01*
G01X209976Y1259424D02*
Y1259312D01*
X210156Y1259132D01*
Y1253568D01*
X211245Y1252479D01*
X212051D01*
X212401Y1252129D01*
Y1250984D01*
G01X199866Y1259812D02*
Y1259700D01*
X199686Y1259520D01*
Y1246398D01*
X200336Y1245748D01*
X200831D01*
X201181Y1246098D01*
Y1247243D01*
G01X203606Y1259624D02*
Y1259512D01*
X203426Y1259332D01*
Y1253879D01*
X204076Y1253229D01*
X204571D01*
X204921Y1253579D01*
Y1254724D01*
G01X228677Y1259624D02*
Y1259512D01*
X228857Y1259332D01*
Y1246087D01*
X229946Y1244998D01*
X230752D01*
X231102Y1244648D01*
Y1243503D01*
G01X229787Y1259624D02*
Y1259512D01*
X229607Y1259332D01*
Y1246398D01*
X230257Y1245748D01*
X230752D01*
X231102Y1246098D01*
Y1247243D01*
G01X221197Y1259824D02*
Y1259712D01*
X221377Y1259532D01*
Y1246087D01*
X222466Y1244998D01*
X223272D01*
X223622Y1244648D01*
Y1243503D01*
G01X216141Y1247243D02*
Y1246098D01*
X215791Y1245748D01*
X215296D01*
X214646Y1246398D01*
Y1259132D01*
X214826Y1259312D01*
Y1259424D01*
G01X222307Y1259824D02*
Y1259712D01*
X222127Y1259532D01*
Y1246398D01*
X222777Y1245748D01*
X223272D01*
X223622Y1246098D01*
Y1247243D01*
G01X217456Y1259424D02*
Y1259312D01*
X217636Y1259132D01*
Y1253568D01*
X218725Y1252479D01*
X219531D01*
X219881Y1252129D01*
Y1250984D01*
G01X218566Y1259424D02*
Y1259312D01*
X218386Y1259132D01*
Y1253879D01*
X219036Y1253229D01*
X219531D01*
X219881Y1253579D01*
Y1254724D01*
G01X226047Y1259624D02*
Y1259512D01*
X225867Y1259332D01*
Y1253879D01*
X226517Y1253229D01*
X227012D01*
X227362Y1253579D01*
Y1254724D01*
G01X224937Y1259624D02*
Y1259512D01*
X225117Y1259332D01*
Y1253568D01*
X226206Y1252479D01*
X227012D01*
X227362Y1252129D01*
Y1250984D01*
G01X237267Y1259624D02*
Y1259512D01*
X237087Y1259332D01*
Y1246398D01*
X237737Y1245748D01*
X238232D01*
X238582Y1246098D01*
Y1247243D01*
G01X243637Y1259824D02*
Y1259712D01*
X243817Y1259532D01*
Y1246087D01*
X244906Y1244998D01*
X245712D01*
X246062Y1244648D01*
Y1243503D01*
G01X239897Y1259424D02*
Y1259312D01*
X240077Y1259132D01*
Y1253568D01*
X241166Y1252479D01*
X241972D01*
X242322Y1252129D01*
Y1250984D01*
G01X232417Y1259624D02*
Y1259512D01*
X232597Y1259332D01*
Y1253568D01*
X233686Y1252479D01*
X234492D01*
X234842Y1252129D01*
Y1250984D01*
G01X244747Y1259824D02*
Y1259712D01*
X244567Y1259532D01*
Y1246398D01*
X245217Y1245748D01*
X245712D01*
X246062Y1246098D01*
Y1247243D01*
G01X233527Y1259624D02*
Y1259512D01*
X233347Y1259332D01*
Y1253879D01*
X233997Y1253229D01*
X234492D01*
X234842Y1253579D01*
Y1254724D01*
G01X236157Y1259624D02*
Y1259512D01*
X236337Y1259332D01*
Y1246087D01*
X237426Y1244998D01*
X238232D01*
X238582Y1244648D01*
Y1243503D01*
G01X241007Y1259424D02*
Y1259312D01*
X240827Y1259132D01*
Y1253879D01*
X241477Y1253229D01*
X241972D01*
X242322Y1253579D01*
Y1254724D01*
G01X249803Y1250984D02*
Y1252129D01*
X249453Y1252479D01*
X248647D01*
X247558Y1253568D01*
Y1259520D01*
X247378Y1259700D01*
Y1259812D01*
G01X257283Y1250984D02*
Y1252129D01*
X256933Y1252479D01*
X256127D01*
X255038Y1253568D01*
Y1259354D01*
X256158Y1260474D01*
Y1260475D01*
X256159Y1260476D01*
Y1260729D01*
X256238Y1260808D01*
G01X253543Y1247243D02*
Y1246098D01*
X253193Y1245748D01*
X252698D01*
X252048Y1246398D01*
Y1259120D01*
X252228Y1259300D01*
Y1259412D01*
G01X257283Y1254724D02*
Y1253579D01*
X256933Y1253229D01*
X256438D01*
X255788Y1253879D01*
Y1259043D01*
X256727Y1259982D01*
X256983D01*
X257023Y1260022D01*
Y1260023D01*
G01X249803Y1254724D02*
Y1253579D01*
X249453Y1253229D01*
X248958D01*
X248308Y1253879D01*
Y1259520D01*
X248488Y1259700D01*
Y1259812D01*
G01X253543Y1243503D02*
Y1244648D01*
X253193Y1244998D01*
X252387D01*
X251298Y1246087D01*
Y1259120D01*
X251118Y1259300D01*
Y1259412D01*
G01X292260Y1068787D02*
Y1068899D01*
X292440Y1069079D01*
Y1095296D01*
X293286Y1096142D01*
X294234D01*
X294684Y1096592D01*
Y1097637D01*
G01X293370Y1068787D02*
Y1068899D01*
X293190Y1069079D01*
Y1094985D01*
X293597Y1095392D01*
X294234D01*
X294684Y1094942D01*
Y1093897D01*
G01X296000Y1069000D02*
Y1069112D01*
X296180Y1069292D01*
Y1102775D01*
X297027Y1103622D01*
X297975D01*
X298425Y1104072D01*
Y1105117D01*
G01X297110Y1069000D02*
Y1069112D01*
X296930Y1069292D01*
Y1102464D01*
X297338Y1102872D01*
X297975D01*
X298425Y1102422D01*
Y1101376D01*
G01X302164Y1097637D02*
Y1096592D01*
X301714Y1096142D01*
X300766D01*
X299920Y1095296D01*
Y1069079D01*
X299740Y1068899D01*
Y1068787D01*
G01X302164Y1093897D02*
Y1094942D01*
X301714Y1095392D01*
X301077D01*
X300670Y1094985D01*
Y1069079D01*
X300850Y1068899D01*
Y1068787D01*
G01X305905Y1105117D02*
Y1104072D01*
X305455Y1103622D01*
X304507D01*
X303660Y1102775D01*
Y1069292D01*
X303480Y1069112D01*
Y1069000D01*
G01X304590D02*
Y1069112D01*
X304410Y1069292D01*
Y1102464D01*
X304818Y1102872D01*
X305455D01*
X305905Y1102422D01*
Y1101376D01*
G01X330290Y1121392D02*
X330178D01*
X329998Y1121572D01*
X297027D01*
X296179Y1122420D01*
Y1123368D01*
X295729Y1123818D01*
X294684D01*
G01X330290Y1113912D02*
X330178D01*
X329998Y1114092D01*
X297027D01*
X296179Y1114940D01*
Y1115888D01*
X295729Y1116338D01*
X294684D01*
G01X330290Y1128873D02*
X330178D01*
X329998Y1129053D01*
X297027D01*
X296179Y1129901D01*
Y1130849D01*
X295729Y1131299D01*
X294684D01*
G01X307220Y1068787D02*
Y1068899D01*
X307400Y1069079D01*
Y1095296D01*
X308246Y1096142D01*
X309194D01*
X309644Y1096592D01*
Y1097637D01*
G01X308330Y1068787D02*
Y1068899D01*
X308150Y1069079D01*
Y1094985D01*
X308557Y1095392D01*
X309194D01*
X309644Y1094942D01*
Y1093897D01*
G01X310960Y1069000D02*
Y1069112D01*
X311140Y1069292D01*
Y1102775D01*
X311987Y1103622D01*
X312935D01*
X313385Y1104072D01*
Y1105117D01*
G01X312070Y1069000D02*
Y1069112D01*
X311890Y1069292D01*
Y1102464D01*
X312298Y1102872D01*
X312935D01*
X313385Y1102422D01*
Y1101377D01*
G01X315811Y1068787D02*
Y1068899D01*
X315631Y1069079D01*
Y1094985D01*
X316038Y1095392D01*
X316675D01*
X317125Y1094942D01*
Y1093897D01*
G01X314701Y1068787D02*
Y1068899D01*
X314881Y1069079D01*
Y1095296D01*
X315727Y1096142D01*
X316675D01*
X317125Y1096592D01*
Y1097637D01*
G01X325922Y1069988D02*
Y1070100D01*
X326102Y1070280D01*
Y1087337D01*
X325577Y1087862D01*
X323338D01*
X322361Y1088839D01*
Y1089707D01*
X321911Y1090157D01*
X320866D01*
G01X327032Y1069988D02*
Y1070100D01*
X326852Y1070280D01*
Y1087648D01*
X325888Y1088612D01*
X323649D01*
X323111Y1089150D01*
Y1089707D01*
X323561Y1090157D01*
X324606D01*
G01X330384Y1117653D02*
X330272D01*
X330092Y1117833D01*
X304507D01*
X303660Y1118680D01*
Y1119628D01*
X303210Y1120078D01*
X302165D01*
G01X330384Y1111283D02*
X330272D01*
X330092Y1111103D01*
X304818D01*
X304410Y1111511D01*
Y1112148D01*
X304860Y1112598D01*
X305905D01*
G01X330290Y1115022D02*
X330178D01*
X329998Y1114842D01*
X297338D01*
X296929Y1115251D01*
Y1115888D01*
X297379Y1116338D01*
X298425D01*
G01X330384Y1118763D02*
X330272D01*
X330092Y1118583D01*
X304818D01*
X304410Y1118991D01*
Y1119628D01*
X304860Y1120078D01*
X305905D01*
G01X330384Y1110173D02*
X330272D01*
X330092Y1110353D01*
X304507D01*
X303660Y1111200D01*
Y1112148D01*
X303210Y1112598D01*
X302165D01*
G01X330290Y1122502D02*
X330178D01*
X329998Y1122322D01*
X297338D01*
X296929Y1122731D01*
Y1123368D01*
X297379Y1123818D01*
X298425D01*
G01X330384Y1126244D02*
X330272D01*
X330092Y1126064D01*
X304818D01*
X304410Y1126472D01*
Y1127109D01*
X304860Y1127559D01*
X305905D01*
G01X330384Y1133724D02*
X330272D01*
X330092Y1133544D01*
X304818D01*
X304410Y1133952D01*
Y1134589D01*
X304860Y1135039D01*
X305905D01*
G01X330384Y1132614D02*
X330272D01*
X330092Y1132794D01*
X304507D01*
X303660Y1133641D01*
Y1134589D01*
X303210Y1135039D01*
X302165D01*
G01X330384Y1125134D02*
X330272D01*
X330092Y1125314D01*
X304507D01*
X303660Y1126161D01*
Y1127109D01*
X303210Y1127559D01*
X302165D01*
G01X330290Y1129983D02*
X330178D01*
X329998Y1129803D01*
X297338D01*
X296929Y1130212D01*
Y1130849D01*
X297379Y1131299D01*
X298425D01*
G01X326264Y1098206D02*
X326185Y1098285D01*
Y1098538D01*
X325598Y1099125D01*
X323235D01*
X322361Y1100001D01*
Y1100927D01*
X321911Y1101377D01*
X320866D01*
G01X327049Y1098991D02*
X327009Y1099031D01*
X326753D01*
X325909Y1099875D01*
X323547D01*
X323111Y1100312D01*
Y1100927D01*
X323561Y1101377D01*
X324606D01*
G01X689504Y1068787D02*
Y1068899D01*
X689684Y1069079D01*
Y1095296D01*
X690530Y1096142D01*
X691478D01*
X691928Y1096592D01*
Y1097637D01*
G01X690614Y1068787D02*
Y1068899D01*
X690434Y1069079D01*
Y1094985D01*
X690841Y1095392D01*
X691478D01*
X691928Y1094942D01*
Y1093897D01*
G01X600088Y1184976D02*
X600200D01*
X600380Y1185156D01*
X611009D01*
X611891Y1186038D01*
Y1187051D01*
X612241Y1187401D01*
X613386D01*
G01X597500Y1188716D02*
X597612D01*
X597792Y1188896D01*
X603468D01*
X604428Y1189856D01*
Y1190769D01*
X604800Y1191141D01*
X605905D01*
G01X600088Y1186086D02*
X600200D01*
X600380Y1185906D01*
X610698D01*
X611141Y1186349D01*
Y1187051D01*
X610791Y1187401D01*
X609646D01*
G01X597500Y1189826D02*
X597612D01*
X597792Y1189646D01*
X603157D01*
X603678Y1190167D01*
Y1190763D01*
X603300Y1191141D01*
X602165D01*
G01X597500Y1192456D02*
X597612D01*
X597792Y1192636D01*
X611009D01*
X611891Y1193518D01*
Y1194531D01*
X612241Y1194881D01*
X613386D01*
G01X597500Y1196196D02*
X597612D01*
X597792Y1196376D01*
X603468D01*
X604428Y1197336D01*
Y1198249D01*
X604800Y1198621D01*
X605905D01*
G01X597500Y1193566D02*
X597612D01*
X597792Y1193386D01*
X610698D01*
X611141Y1193829D01*
Y1194531D01*
X610791Y1194881D01*
X609646D01*
G01X597500Y1197306D02*
X597612D01*
X597792Y1197126D01*
X603157D01*
X603678Y1197647D01*
Y1198243D01*
X603300Y1198621D01*
X602165D01*
G01X695669Y1101376D02*
Y1102422D01*
X695219Y1102872D01*
X694582D01*
X694174Y1102464D01*
Y1069292D01*
X694354Y1069112D01*
Y1069000D01*
G01X693244D02*
Y1069112D01*
X693424Y1069292D01*
Y1102775D01*
X694271Y1103622D01*
X695219D01*
X695669Y1104072D01*
Y1105117D01*
G01X696984Y1068787D02*
Y1068899D01*
X697164Y1069079D01*
Y1095296D01*
X698010Y1096142D01*
X698958D01*
X699408Y1096592D01*
Y1097637D01*
G01X698094Y1068787D02*
Y1068899D01*
X697914Y1069079D01*
Y1094985D01*
X698321Y1095392D01*
X698958D01*
X699408Y1094942D01*
Y1093897D01*
G01X700724Y1069000D02*
Y1069112D01*
X700904Y1069292D01*
Y1102775D01*
X701751Y1103622D01*
X702699D01*
X703149Y1104072D01*
Y1105117D01*
G01X704465Y1068787D02*
Y1068899D01*
X704645Y1069079D01*
Y1095296D01*
X705491Y1096142D01*
X706439D01*
X706889Y1096592D01*
Y1097637D01*
G01X701834Y1069000D02*
Y1069112D01*
X701654Y1069292D01*
Y1102464D01*
X702062Y1102872D01*
X702699D01*
X703149Y1102422D01*
Y1101376D01*
G01X705575Y1068787D02*
Y1068899D01*
X705395Y1069079D01*
Y1094985D01*
X705802Y1095392D01*
X706439D01*
X706889Y1094942D01*
Y1093897D01*
G01X597500Y1201047D02*
X597612D01*
X597792Y1200867D01*
X610698D01*
X611141Y1201310D01*
Y1202012D01*
X610791Y1202362D01*
X609646D01*
G01X597500Y1199937D02*
X597612D01*
X597792Y1200117D01*
X611009D01*
X611891Y1200999D01*
Y1202012D01*
X612241Y1202362D01*
X613386D01*
G01X597500Y1208527D02*
X597612D01*
X597792Y1208347D01*
X610698D01*
X611141Y1208790D01*
Y1209492D01*
X610791Y1209842D01*
X609646D01*
G01X597500Y1203677D02*
X597612D01*
X597792Y1203857D01*
X603468D01*
X604428Y1204817D01*
Y1205730D01*
X604800Y1206102D01*
X605905D01*
G01X597500Y1207417D02*
X597612D01*
X597792Y1207597D01*
X611009D01*
X611891Y1208479D01*
Y1209492D01*
X612241Y1209842D01*
X613386D01*
G01X597500Y1204787D02*
X597612D01*
X597792Y1204607D01*
X603157D01*
X603678Y1205128D01*
Y1205724D01*
X603300Y1206102D01*
X602165D01*
G01X597500Y1211157D02*
X597612D01*
X597792Y1211337D01*
X603468D01*
X604428Y1212297D01*
Y1213210D01*
X604800Y1213582D01*
X605905D01*
G01X597500Y1212267D02*
X597612D01*
X597792Y1212087D01*
X603157D01*
X603678Y1212608D01*
Y1213204D01*
X603300Y1213582D01*
X602165D01*
G01X708205Y1069000D02*
Y1069112D01*
X708385Y1069292D01*
Y1102775D01*
X709232Y1103622D01*
X710180D01*
X710630Y1104072D01*
Y1105117D01*
G01X709315Y1069000D02*
Y1069112D01*
X709135Y1069292D01*
Y1102464D01*
X709543Y1102872D01*
X710180D01*
X710630Y1102422D01*
Y1101376D01*
G01X711945Y1068787D02*
Y1068899D01*
X712125Y1069079D01*
Y1095296D01*
X712971Y1096142D01*
X713919D01*
X714369Y1096592D01*
Y1097637D01*
G01X713055Y1068787D02*
Y1068899D01*
X712875Y1069079D01*
Y1094985D01*
X713282Y1095392D01*
X713919D01*
X714369Y1094942D01*
Y1093897D01*
G01X715685Y1069000D02*
Y1069112D01*
X715865Y1069292D01*
Y1102775D01*
X716712Y1103622D01*
X717660D01*
X718110Y1104072D01*
Y1105117D01*
G01X716795Y1069000D02*
Y1069112D01*
X716615Y1069292D01*
Y1102464D01*
X717023Y1102872D01*
X717660D01*
X718110Y1102422D01*
Y1101376D01*
G01X723165Y1069000D02*
Y1069112D01*
X723345Y1069292D01*
Y1102775D01*
X724192Y1103622D01*
X725140D01*
X725590Y1104072D01*
Y1105117D01*
G01X719425Y1068787D02*
Y1068899D01*
X719605Y1069079D01*
Y1095296D01*
X720451Y1096142D01*
X721399D01*
X721849Y1096592D01*
Y1097637D01*
G01X720535Y1068787D02*
Y1068899D01*
X720355Y1069079D01*
Y1094985D01*
X720762Y1095392D01*
X721399D01*
X721849Y1094942D01*
Y1093897D01*
G01X724275Y1069000D02*
Y1069112D01*
X724095Y1069292D01*
Y1102464D01*
X724503Y1102872D01*
X725140D01*
X725590Y1102422D01*
Y1101376D01*
G01X726906Y1068787D02*
Y1068899D01*
X727086Y1069079D01*
Y1095296D01*
X727932Y1096142D01*
X728880D01*
X729330Y1096592D01*
Y1097637D01*
G01X728016Y1068787D02*
Y1068899D01*
X727836Y1069079D01*
Y1094985D01*
X728243Y1095392D01*
X728880D01*
X729330Y1094942D01*
Y1093897D01*
G01X730646Y1069000D02*
Y1069112D01*
X730826Y1069292D01*
Y1102775D01*
X731673Y1103622D01*
X732621D01*
X733071Y1104072D01*
Y1105117D01*
G01X734386Y1068787D02*
Y1068899D01*
X734566Y1069079D01*
Y1095296D01*
X735412Y1096142D01*
X736360D01*
X736810Y1096592D01*
Y1097637D01*
G01X731756Y1069000D02*
Y1069112D01*
X731576Y1069292D01*
Y1102464D01*
X731984Y1102872D01*
X732621D01*
X733071Y1102422D01*
Y1101376D01*
G01X735496Y1068787D02*
Y1068899D01*
X735316Y1069079D01*
Y1094985D01*
X735723Y1095392D01*
X736360D01*
X736810Y1094942D01*
Y1093897D01*
G01X738126Y1069000D02*
Y1069112D01*
X738306Y1069292D01*
Y1102775D01*
X739153Y1103622D01*
X740101D01*
X740551Y1104072D01*
Y1105117D01*
G01X739236Y1069000D02*
Y1069112D01*
X739056Y1069292D01*
Y1102464D01*
X739464Y1102872D01*
X740101D01*
X740551Y1102422D01*
Y1101376D01*
G01X745606Y1069000D02*
Y1069112D01*
X745786Y1069292D01*
Y1102775D01*
X746633Y1103622D01*
X747581D01*
X748031Y1104072D01*
Y1105117D01*
G01X744290Y1093897D02*
Y1094941D01*
X743839Y1095392D01*
X743202D01*
X742795Y1094985D01*
Y1069079D01*
X742975Y1068899D01*
Y1068787D01*
G01X741865D02*
Y1068899D01*
X742045Y1069079D01*
Y1095296D01*
X742891Y1096142D01*
X743839D01*
X744290Y1096593D01*
Y1097637D01*
G01X746716Y1069000D02*
Y1069112D01*
X746536Y1069292D01*
Y1102464D01*
X746944Y1102872D01*
X747581D01*
X748031Y1102422D01*
Y1101376D01*
G01X613386Y1217322D02*
X612241D01*
X611891Y1216972D01*
Y1216039D01*
X610929Y1215077D01*
X597738D01*
X597558Y1214897D01*
X597446D01*
G01X602165Y1221062D02*
X603310D01*
X603660Y1221412D01*
Y1221907D01*
X603010Y1222557D01*
X600826D01*
X599976Y1223407D01*
X599724Y1223406D01*
X599645Y1223485D01*
G01X609646Y1217322D02*
X610791D01*
X611141Y1216972D01*
Y1216350D01*
X610618Y1215827D01*
X597738D01*
X597558Y1216007D01*
X597446D01*
G01X605905Y1221062D02*
X604760D01*
X604410Y1221412D01*
Y1222218D01*
X603321Y1223307D01*
X601137D01*
X600509Y1223935D01*
Y1224191D01*
X600430Y1224270D01*
G01X603480Y1255712D02*
Y1255600D01*
X603660Y1255420D01*
Y1247593D01*
X603310Y1247243D01*
X602165D01*
G01X604590Y1255712D02*
Y1255600D01*
X604410Y1255420D01*
Y1247593D01*
X604760Y1247243D01*
X605905D01*
G01X614701Y1259412D02*
Y1259300D01*
X614881Y1259120D01*
Y1253422D01*
X615824Y1252479D01*
X616776D01*
X617126Y1252129D01*
Y1250984D01*
G01X618442Y1259412D02*
Y1259300D01*
X618622Y1259120D01*
Y1246007D01*
X619631Y1244998D01*
X620517D01*
X620867Y1244648D01*
Y1243504D01*
X620866Y1243503D01*
G01Y1247243D02*
X620867Y1247242D01*
Y1246098D01*
X620517Y1245748D01*
X619942D01*
X619372Y1246318D01*
Y1259120D01*
X619552Y1259300D01*
Y1259412D01*
G01X609646Y1254724D02*
Y1253579D01*
X609296Y1253229D01*
X608653D01*
X608151Y1253731D01*
Y1259120D01*
X608331Y1259300D01*
Y1259412D01*
G01X612072Y1259612D02*
Y1259500D01*
X611892Y1259320D01*
Y1246333D01*
X612477Y1245748D01*
X613036D01*
X613386Y1246098D01*
Y1247243D01*
G01X617126Y1254724D02*
Y1253579D01*
X616776Y1253229D01*
X616135D01*
X615631Y1253733D01*
Y1259120D01*
X615811Y1259300D01*
Y1259412D01*
G01X610962Y1259612D02*
Y1259500D01*
X611142Y1259320D01*
Y1246022D01*
X612166Y1244998D01*
X613036D01*
X613386Y1244648D01*
Y1243503D01*
G01X607221Y1259412D02*
Y1259300D01*
X607401Y1259120D01*
Y1253420D01*
X608342Y1252479D01*
X609296D01*
X609646Y1252129D01*
Y1250984D01*
G01X624606Y1254724D02*
Y1253579D01*
X624256Y1253229D01*
X623761D01*
X623111Y1253879D01*
Y1259020D01*
X623291Y1259200D01*
Y1259312D01*
G01X622181D02*
Y1259200D01*
X622361Y1259020D01*
Y1253568D01*
X623450Y1252479D01*
X624256D01*
X624606Y1252129D01*
Y1250984D01*
G01X749347Y1068787D02*
Y1068899D01*
X749527Y1069079D01*
Y1095296D01*
X750373Y1096142D01*
X751321D01*
X751771Y1096592D01*
Y1097637D01*
G01X750457Y1068787D02*
Y1068899D01*
X750277Y1069079D01*
Y1094985D01*
X750684Y1095392D01*
X751321D01*
X751771Y1094942D01*
Y1093897D01*
G01X753087Y1069000D02*
Y1069112D01*
X753267Y1069292D01*
Y1102775D01*
X754114Y1103622D01*
X755062D01*
X755512Y1104072D01*
Y1105117D01*
G01X754197Y1069000D02*
Y1069112D01*
X754017Y1069292D01*
Y1102464D01*
X754425Y1102872D01*
X755062D01*
X755512Y1102422D01*
Y1101376D01*
G01X756827Y1068787D02*
Y1068899D01*
X757007Y1069079D01*
Y1095296D01*
X757853Y1096142D01*
X758801D01*
X759251Y1096592D01*
Y1097637D01*
G01X757937Y1068787D02*
Y1068899D01*
X757757Y1069079D01*
Y1094985D01*
X758164Y1095392D01*
X758801D01*
X759251Y1094942D01*
Y1093897D01*
G01X760567Y1069000D02*
Y1069112D01*
X760747Y1069292D01*
Y1102775D01*
X761594Y1103622D01*
X762542D01*
X762992Y1104072D01*
Y1105117D01*
G01X761677Y1069000D02*
Y1069112D01*
X761497Y1069292D01*
Y1102464D01*
X761905Y1102872D01*
X762542D01*
X762992Y1102422D01*
Y1101376D01*
G01X764307Y1068787D02*
Y1068899D01*
X764487Y1069079D01*
Y1095296D01*
X765333Y1096142D01*
X766281D01*
X766731Y1096592D01*
Y1097637D01*
G01X765417Y1068787D02*
Y1068899D01*
X765237Y1069079D01*
Y1094985D01*
X765644Y1095392D01*
X766281D01*
X766731Y1094942D01*
Y1093897D01*
G01X768047Y1069000D02*
Y1069112D01*
X768227Y1069292D01*
Y1102775D01*
X769074Y1103622D01*
X770022D01*
X770472Y1104072D01*
Y1105117D01*
G01X769157Y1069000D02*
Y1069112D01*
X768977Y1069292D01*
Y1102464D01*
X769385Y1102872D01*
X770022D01*
X770472Y1102422D01*
Y1101377D01*
G01X771788Y1068787D02*
Y1068899D01*
X771968Y1069079D01*
Y1095296D01*
X772814Y1096142D01*
X773762D01*
X774212Y1096592D01*
Y1097637D01*
G01X772898Y1068787D02*
Y1068899D01*
X772718Y1069079D01*
Y1094985D01*
X773125Y1095392D01*
X773762D01*
X774212Y1094942D01*
Y1093897D01*
G01X783009Y1069988D02*
Y1070100D01*
X783189Y1070280D01*
Y1087337D01*
X782664Y1087862D01*
X780425D01*
X779448Y1088839D01*
Y1089707D01*
X778998Y1090157D01*
X777953D01*
G01X787377Y1122502D02*
X787265D01*
X787085Y1122322D01*
X754425D01*
X754016Y1122731D01*
Y1123368D01*
X754466Y1123818D01*
X755512D01*
G01X787471Y1110173D02*
X787359D01*
X787179Y1110353D01*
X761594D01*
X760747Y1111200D01*
Y1112148D01*
X760297Y1112598D01*
X759252D01*
G01X787377Y1121392D02*
X787265D01*
X787085Y1121572D01*
X754114D01*
X753266Y1122420D01*
Y1123368D01*
X752816Y1123818D01*
X751771D01*
G01X787471Y1111283D02*
X787359D01*
X787179Y1111103D01*
X761905D01*
X761497Y1111511D01*
Y1112148D01*
X761947Y1112598D01*
X762992D01*
G01X787377Y1115022D02*
X787265D01*
X787085Y1114842D01*
X754425D01*
X754016Y1115251D01*
Y1115888D01*
X754466Y1116338D01*
X755512D01*
G01X787377Y1113912D02*
X787265D01*
X787085Y1114092D01*
X754114D01*
X753266Y1114940D01*
Y1115888D01*
X752816Y1116338D01*
X751771D01*
G01X787471Y1117653D02*
X787359D01*
X787179Y1117833D01*
X761594D01*
X760747Y1118680D01*
Y1119628D01*
X760297Y1120078D01*
X759252D01*
G01X787471Y1118763D02*
X787359D01*
X787179Y1118583D01*
X761905D01*
X761497Y1118991D01*
Y1119628D01*
X761947Y1120078D01*
X762992D01*
G01X787377Y1128873D02*
X787265D01*
X787085Y1129053D01*
X754114D01*
X753266Y1129901D01*
Y1130849D01*
X752816Y1131299D01*
X751771D01*
G01X787471Y1133724D02*
X787359D01*
X787179Y1133544D01*
X761905D01*
X761497Y1133952D01*
Y1134589D01*
X761947Y1135039D01*
X762992D01*
G01X787377Y1129983D02*
X787265D01*
X787085Y1129803D01*
X754425D01*
X754016Y1130212D01*
Y1130849D01*
X754466Y1131299D01*
X755512D01*
G01X787471Y1126244D02*
X787359D01*
X787179Y1126064D01*
X761905D01*
X761497Y1126472D01*
Y1127109D01*
X761947Y1127559D01*
X762992D01*
G01X787471Y1132614D02*
X787359D01*
X787179Y1132794D01*
X761594D01*
X760747Y1133641D01*
Y1134589D01*
X760297Y1135039D01*
X759252D01*
G01X787471Y1125134D02*
X787359D01*
X787179Y1125314D01*
X761594D01*
X760747Y1126161D01*
Y1127109D01*
X760297Y1127559D01*
X759252D01*
G01X784119Y1069988D02*
Y1070100D01*
X783939Y1070280D01*
Y1087648D01*
X782975Y1088612D01*
X780736D01*
X780198Y1089150D01*
Y1089707D01*
X780648Y1090157D01*
X781693D01*
G01X783351Y1098206D02*
X783272Y1098285D01*
Y1098538D01*
X782685Y1099125D01*
X780322D01*
X779448Y1100001D01*
Y1100927D01*
X778998Y1101377D01*
X777953D01*
G01X784136Y1098991D02*
X784096Y1099031D01*
X783840D01*
X782996Y1099875D01*
X780634D01*
X780198Y1100312D01*
Y1100927D01*
X780648Y1101377D01*
X781693D01*
G01X1146590Y1068787D02*
Y1068899D01*
X1146770Y1069079D01*
Y1095296D01*
X1147616Y1096142D01*
X1148564D01*
X1149014Y1096592D01*
Y1097637D01*
G01X1147700Y1068787D02*
Y1068899D01*
X1147520Y1069079D01*
Y1094985D01*
X1147927Y1095392D01*
X1148564D01*
X1149014Y1094942D01*
Y1093897D01*
G01X1150330Y1069000D02*
Y1069112D01*
X1150510Y1069292D01*
Y1102775D01*
X1151357Y1103622D01*
X1152305D01*
X1152755Y1104072D01*
Y1105117D01*
G01X1156494Y1093897D02*
Y1094942D01*
X1156044Y1095392D01*
X1155407D01*
X1155000Y1094985D01*
Y1069079D01*
X1155180Y1068899D01*
Y1068787D01*
G01X1152755Y1101376D02*
Y1102422D01*
X1152305Y1102872D01*
X1151668D01*
X1151260Y1102464D01*
Y1069292D01*
X1151440Y1069112D01*
Y1069000D01*
G01X1154070Y1068787D02*
Y1068899D01*
X1154250Y1069079D01*
Y1095296D01*
X1155096Y1096142D01*
X1156044D01*
X1156494Y1096592D01*
Y1097637D01*
G01X1157810Y1069000D02*
Y1069112D01*
X1157990Y1069292D01*
Y1102775D01*
X1158837Y1103622D01*
X1159785D01*
X1160235Y1104072D01*
Y1105117D01*
G01X1158920Y1069000D02*
Y1069112D01*
X1158740Y1069292D01*
Y1102464D01*
X1159148Y1102872D01*
X1159785D01*
X1160235Y1102422D01*
Y1101376D01*
G01X1163975Y1093897D02*
Y1094942D01*
X1163525Y1095392D01*
X1162888D01*
X1162481Y1094985D01*
Y1069079D01*
X1162661Y1068899D01*
Y1068787D01*
G01X1161551D02*
Y1068899D01*
X1161731Y1069079D01*
Y1095296D01*
X1162577Y1096142D01*
X1163525D01*
X1163975Y1096592D01*
Y1097637D01*
G01X1165291Y1069000D02*
Y1069112D01*
X1165471Y1069292D01*
Y1102775D01*
X1166318Y1103622D01*
X1167266D01*
X1167716Y1104072D01*
Y1105117D01*
G01X1171455Y1093897D02*
Y1094942D01*
X1171005Y1095392D01*
X1170368D01*
X1169961Y1094985D01*
Y1069079D01*
X1170141Y1068899D01*
Y1068787D01*
G01X1171455Y1097637D02*
Y1096592D01*
X1171005Y1096142D01*
X1170057D01*
X1169211Y1095296D01*
Y1069079D01*
X1169031Y1068899D01*
Y1068787D01*
G01X1167716Y1101376D02*
Y1102422D01*
X1167266Y1102872D01*
X1166629D01*
X1166221Y1102464D01*
Y1069292D01*
X1166401Y1069112D01*
Y1069000D01*
G01X1175196Y1105117D02*
Y1104072D01*
X1174746Y1103622D01*
X1173798D01*
X1172951Y1102775D01*
Y1069292D01*
X1172771Y1069112D01*
Y1069000D01*
G01X1173881D02*
Y1069112D01*
X1173701Y1069292D01*
Y1102464D01*
X1174109Y1102872D01*
X1174746D01*
X1175196Y1102422D01*
Y1101376D01*
G01X1178935Y1097637D02*
Y1096592D01*
X1178485Y1096142D01*
X1177537D01*
X1176691Y1095296D01*
Y1069079D01*
X1176511Y1068899D01*
Y1068787D01*
G01X1178935Y1093897D02*
Y1094942D01*
X1178485Y1095392D01*
X1177848D01*
X1177441Y1094985D01*
Y1069079D01*
X1177621Y1068899D01*
Y1068787D01*
G01X1180251Y1069000D02*
Y1069112D01*
X1180431Y1069292D01*
Y1102775D01*
X1181278Y1103622D01*
X1182226D01*
X1182676Y1104072D01*
Y1105117D01*
G01Y1101376D02*
Y1102422D01*
X1182226Y1102872D01*
X1181589D01*
X1181181Y1102464D01*
Y1069292D01*
X1181361Y1069112D01*
Y1069000D01*
G01X1185102Y1068787D02*
Y1068899D01*
X1184922Y1069079D01*
Y1094985D01*
X1185329Y1095392D01*
X1185966D01*
X1186416Y1094942D01*
Y1093897D01*
G01X1183992Y1068787D02*
Y1068899D01*
X1184172Y1069079D01*
Y1095296D01*
X1185018Y1096142D01*
X1185966D01*
X1186416Y1096592D01*
Y1097637D01*
G01X1193896D02*
Y1096592D01*
X1193446Y1096142D01*
X1192498D01*
X1191652Y1095296D01*
Y1069079D01*
X1191472Y1068899D01*
Y1068787D01*
G01X1188842Y1069000D02*
Y1069112D01*
X1188662Y1069292D01*
Y1102464D01*
X1189070Y1102872D01*
X1189707D01*
X1190157Y1102422D01*
Y1101376D01*
G01Y1105117D02*
Y1104072D01*
X1189707Y1103622D01*
X1188759D01*
X1187912Y1102775D01*
Y1069292D01*
X1187732Y1069112D01*
Y1069000D01*
G01X1193896Y1093897D02*
Y1094942D01*
X1193446Y1095392D01*
X1192809D01*
X1192402Y1094985D01*
Y1069079D01*
X1192582Y1068899D01*
Y1068787D01*
G01X1197637Y1105117D02*
Y1104072D01*
X1197187Y1103622D01*
X1196239D01*
X1195392Y1102775D01*
Y1069292D01*
X1195212Y1069112D01*
Y1069000D01*
G01X1197637Y1101376D02*
Y1102422D01*
X1197187Y1102872D01*
X1196550D01*
X1196142Y1102464D01*
Y1069292D01*
X1196322Y1069112D01*
Y1069000D01*
G01X1200062Y1068787D02*
Y1068899D01*
X1199882Y1069079D01*
Y1094985D01*
X1200289Y1095392D01*
X1200926D01*
X1201376Y1094942D01*
Y1093897D01*
G01X1205117Y1105117D02*
Y1104072D01*
X1204667Y1103622D01*
X1203719D01*
X1202872Y1102775D01*
Y1069292D01*
X1202692Y1069112D01*
Y1069000D01*
G01X1205117Y1101376D02*
Y1102422D01*
X1204667Y1102872D01*
X1204030D01*
X1203622Y1102464D01*
Y1069292D01*
X1203802Y1069112D01*
Y1069000D01*
G01X1201376Y1097637D02*
Y1096592D01*
X1200926Y1096142D01*
X1199978D01*
X1199132Y1095296D01*
Y1069079D01*
X1198952Y1068899D01*
Y1068787D01*
G01X1120409Y1259512D02*
Y1259400D01*
X1120589Y1259220D01*
Y1245886D01*
X1121477Y1244998D01*
X1122484D01*
X1122834Y1244648D01*
Y1243503D01*
G01X1116668Y1259512D02*
Y1259400D01*
X1116848Y1259220D01*
Y1253367D01*
X1117736Y1252479D01*
X1118743D01*
X1119094Y1252128D01*
Y1250984D01*
G01X1117778Y1259512D02*
Y1259400D01*
X1117598Y1259220D01*
Y1253678D01*
X1118047Y1253229D01*
X1118743D01*
X1119094Y1253580D01*
Y1254724D01*
G01X1121519Y1259512D02*
Y1259400D01*
X1121339Y1259220D01*
Y1246197D01*
X1121788Y1245748D01*
X1122484D01*
X1122834Y1246098D01*
Y1247243D01*
G01X1112929Y1259512D02*
Y1259400D01*
X1113109Y1259220D01*
Y1245886D01*
X1113997Y1244998D01*
X1115004D01*
X1115354Y1244648D01*
Y1243503D01*
G01X1114039Y1259512D02*
Y1259400D01*
X1113859Y1259220D01*
Y1246197D01*
X1114308Y1245748D01*
X1115004D01*
X1115354Y1246098D01*
Y1247243D01*
G01X1125258Y1259512D02*
Y1259400D01*
X1125078Y1259220D01*
Y1253678D01*
X1125527Y1253229D01*
X1126223D01*
X1126574Y1253580D01*
Y1254724D01*
G01X1140220Y1259512D02*
Y1259400D01*
X1140040Y1259220D01*
Y1253678D01*
X1140489Y1253229D01*
X1141185D01*
X1141535Y1253579D01*
Y1254724D01*
G01X1135370Y1259512D02*
Y1259400D01*
X1135550Y1259220D01*
Y1245886D01*
X1136438Y1244998D01*
X1137445D01*
X1137795Y1244648D01*
Y1243503D01*
G01X1128999Y1259512D02*
Y1259400D01*
X1128819Y1259220D01*
Y1246197D01*
X1129268Y1245748D01*
X1129964D01*
X1130314Y1246098D01*
Y1247243D01*
G01X1139110Y1259512D02*
Y1259400D01*
X1139290Y1259220D01*
Y1253367D01*
X1140178Y1252479D01*
X1141185D01*
X1141535Y1252129D01*
Y1250984D01*
G01X1124148Y1259512D02*
Y1259400D01*
X1124328Y1259220D01*
Y1253367D01*
X1125216Y1252479D01*
X1126223D01*
X1126574Y1252128D01*
Y1250984D01*
G01X1136480Y1259512D02*
Y1259400D01*
X1136300Y1259220D01*
Y1246197D01*
X1136749Y1245748D01*
X1137445D01*
X1137795Y1246098D01*
Y1247243D01*
G01X1127889Y1259512D02*
Y1259400D01*
X1128069Y1259220D01*
Y1245886D01*
X1128957Y1244998D01*
X1129964D01*
X1130314Y1244648D01*
Y1243503D01*
G01X1131629Y1259512D02*
Y1259400D01*
X1131809Y1259220D01*
Y1253367D01*
X1132697Y1252479D01*
X1133704D01*
X1134054Y1252129D01*
Y1250984D01*
G01X1132739Y1259512D02*
Y1259400D01*
X1132559Y1259220D01*
Y1253678D01*
X1133008Y1253229D01*
X1133704D01*
X1134054Y1253579D01*
Y1254724D01*
G01X1147700Y1259512D02*
Y1259400D01*
X1147520Y1259220D01*
Y1253678D01*
X1147969Y1253229D01*
X1148665D01*
X1149015Y1253579D01*
Y1254724D01*
G01X1143960Y1259512D02*
Y1259400D01*
X1143780Y1259220D01*
Y1246197D01*
X1144229Y1245748D01*
X1144925D01*
X1145275Y1246098D01*
Y1247243D01*
G01X1150330Y1259512D02*
Y1259400D01*
X1150510Y1259220D01*
Y1245886D01*
X1151398Y1244998D01*
X1152405D01*
X1152755Y1244648D01*
Y1243503D01*
G01X1156495Y1254724D02*
Y1253579D01*
X1156145Y1253229D01*
X1155449D01*
X1155000Y1253678D01*
Y1259220D01*
X1155180Y1259400D01*
Y1259512D01*
G01X1142850D02*
Y1259400D01*
X1143030Y1259220D01*
Y1245886D01*
X1143918Y1244998D01*
X1144925D01*
X1145275Y1244648D01*
Y1243503D01*
G01X1151440Y1259512D02*
Y1259400D01*
X1151260Y1259220D01*
Y1246197D01*
X1151709Y1245748D01*
X1152405D01*
X1152755Y1246098D01*
Y1247243D01*
G01X1146590Y1259512D02*
Y1259400D01*
X1146770Y1259220D01*
Y1253367D01*
X1147658Y1252479D01*
X1148515D01*
X1149015Y1251979D01*
Y1250984D01*
G01X1154070Y1259512D02*
Y1259400D01*
X1154250Y1259220D01*
Y1253367D01*
X1155138Y1252479D01*
X1156145D01*
X1156495Y1252129D01*
Y1250984D01*
G01X1171456D02*
Y1252129D01*
X1171106Y1252479D01*
X1170099D01*
X1169208Y1253370D01*
Y1259369D01*
X1170569Y1260730D01*
X1173620D01*
X1173800Y1260910D01*
X1173912D01*
G01X1167716Y1247243D02*
Y1246197D01*
X1167715D01*
X1167266Y1245748D01*
X1166629D01*
X1166179Y1246198D01*
Y1258479D01*
X1169531Y1261831D01*
X1169783D01*
Y1261830D01*
X1169863Y1261910D01*
G01X1163976Y1250984D02*
Y1252129D01*
X1163626Y1252479D01*
X1162619D01*
X1161731Y1253367D01*
Y1259020D01*
X1161551Y1259200D01*
Y1259312D01*
G01X1158920Y1259512D02*
Y1259400D01*
X1158740Y1259220D01*
Y1246197D01*
X1159189Y1245748D01*
X1159885D01*
X1160235Y1246098D01*
Y1247243D01*
G01X1157810Y1259512D02*
Y1259400D01*
X1157990Y1259220D01*
Y1245886D01*
X1158878Y1244998D01*
X1159885D01*
X1160235Y1244648D01*
Y1243503D01*
G01X1167716D02*
Y1244498D01*
X1167216Y1244998D01*
X1166318D01*
X1165429Y1245887D01*
Y1258790D01*
X1168999Y1262360D01*
Y1262616D01*
X1169078Y1262695D01*
G01X1171456Y1254724D02*
Y1253579D01*
X1171106Y1253229D01*
X1170410D01*
X1169958Y1253681D01*
Y1259058D01*
X1170880Y1259980D01*
X1173620D01*
X1173800Y1259800D01*
X1173912D01*
G01X1162661Y1259312D02*
Y1259200D01*
X1162481Y1259020D01*
Y1253678D01*
X1162930Y1253229D01*
X1163626D01*
X1163976Y1253579D01*
Y1254724D01*
G01X1206433Y1068787D02*
Y1068899D01*
X1206613Y1069079D01*
Y1095296D01*
X1207459Y1096142D01*
X1208407D01*
X1208857Y1096592D01*
Y1097637D01*
G01X1207543Y1068787D02*
Y1068899D01*
X1207363Y1069079D01*
Y1094985D01*
X1207770Y1095392D01*
X1208407D01*
X1208857Y1094942D01*
Y1093897D01*
G01X1210173Y1069000D02*
Y1069112D01*
X1210353Y1069292D01*
Y1102775D01*
X1211200Y1103622D01*
X1212148D01*
X1212598Y1104072D01*
Y1105117D01*
G01X1211283Y1069000D02*
Y1069112D01*
X1211103Y1069292D01*
Y1102464D01*
X1211511Y1102872D01*
X1212148D01*
X1212598Y1102422D01*
Y1101376D01*
G01X1216337Y1097637D02*
Y1096592D01*
X1215887Y1096142D01*
X1214939D01*
X1214093Y1095296D01*
Y1069079D01*
X1213913Y1068899D01*
Y1068787D01*
G01X1216337Y1093897D02*
Y1094942D01*
X1215887Y1095392D01*
X1215250D01*
X1214843Y1094985D01*
Y1069079D01*
X1215023Y1068899D01*
Y1068787D01*
G01X1220078Y1105117D02*
Y1104072D01*
X1219628Y1103622D01*
X1218680D01*
X1217833Y1102775D01*
Y1069292D01*
X1217653Y1069112D01*
Y1069000D01*
G01X1218763D02*
Y1069112D01*
X1218583Y1069292D01*
Y1102464D01*
X1218991Y1102872D01*
X1219628D01*
X1220078Y1102422D01*
Y1101376D01*
G01X1223817Y1097637D02*
Y1096592D01*
X1223367Y1096142D01*
X1222419D01*
X1221573Y1095296D01*
Y1069079D01*
X1221393Y1068899D01*
Y1068787D01*
G01X1222503D02*
Y1068899D01*
X1222323Y1069079D01*
Y1094985D01*
X1222730Y1095392D01*
X1223367D01*
X1223817Y1094942D01*
Y1093897D01*
G01X1225133Y1069000D02*
Y1069112D01*
X1225313Y1069292D01*
Y1102775D01*
X1226160Y1103622D01*
X1227108D01*
X1227558Y1104072D01*
Y1105117D01*
G01X1226243Y1069000D02*
Y1069112D01*
X1226063Y1069292D01*
Y1102464D01*
X1226471Y1102872D01*
X1227108D01*
X1227558Y1102422D01*
Y1101377D01*
G01X1228874Y1068787D02*
Y1068899D01*
X1229054Y1069079D01*
Y1095296D01*
X1229900Y1096142D01*
X1230848D01*
X1231298Y1096592D01*
Y1097637D01*
G01X1229984Y1068787D02*
Y1068899D01*
X1229804Y1069079D01*
Y1094985D01*
X1230211Y1095392D01*
X1230848D01*
X1231298Y1094942D01*
Y1093897D01*
G01X1244463Y1122502D02*
X1244351D01*
X1244171Y1122322D01*
X1211511D01*
X1211102Y1122731D01*
Y1123368D01*
X1211552Y1123818D01*
X1212598D01*
G01X1244463Y1113912D02*
X1244351D01*
X1244171Y1114092D01*
X1211200D01*
X1210352Y1114940D01*
Y1115888D01*
X1209902Y1116338D01*
X1208857D01*
G01X1244463Y1115022D02*
X1244351D01*
X1244171Y1114842D01*
X1211511D01*
X1211102Y1115251D01*
Y1115888D01*
X1211552Y1116338D01*
X1212598D01*
G01X1244557Y1117653D02*
X1244445D01*
X1244265Y1117833D01*
X1218680D01*
X1217833Y1118680D01*
Y1119628D01*
X1217383Y1120078D01*
X1216338D01*
G01X1244557Y1110173D02*
X1244445D01*
X1244265Y1110353D01*
X1218680D01*
X1217833Y1111200D01*
Y1112148D01*
X1217383Y1112598D01*
X1216338D01*
G01X1244463Y1121392D02*
X1244351D01*
X1244171Y1121572D01*
X1211200D01*
X1210352Y1122420D01*
Y1123368D01*
X1209902Y1123818D01*
X1208857D01*
G01X1244557Y1111283D02*
X1244445D01*
X1244265Y1111103D01*
X1218991D01*
X1218583Y1111511D01*
Y1112148D01*
X1219033Y1112598D01*
X1220078D01*
G01X1244557Y1118763D02*
X1244445D01*
X1244265Y1118583D01*
X1218991D01*
X1218583Y1118991D01*
Y1119628D01*
X1219033Y1120078D01*
X1220078D01*
G01X1244557Y1125134D02*
X1244445D01*
X1244265Y1125314D01*
X1218680D01*
X1217833Y1126161D01*
Y1127109D01*
X1217383Y1127559D01*
X1216338D01*
G01X1244557Y1132614D02*
X1244445D01*
X1244265Y1132794D01*
X1218680D01*
X1217833Y1133641D01*
Y1134589D01*
X1217383Y1135039D01*
X1216338D01*
G01X1244463Y1129983D02*
X1244351D01*
X1244171Y1129803D01*
X1211511D01*
X1211102Y1130212D01*
Y1130849D01*
X1211552Y1131299D01*
X1212598D01*
G01X1244463Y1128873D02*
X1244351D01*
X1244171Y1129053D01*
X1211200D01*
X1210352Y1129901D01*
Y1130849D01*
X1209902Y1131299D01*
X1208857D01*
G01X1244557Y1133724D02*
X1244445D01*
X1244265Y1133544D01*
X1218991D01*
X1218583Y1133952D01*
Y1134589D01*
X1219033Y1135039D01*
X1220078D01*
G01X1244557Y1126244D02*
X1244445D01*
X1244265Y1126064D01*
X1218991D01*
X1218583Y1126472D01*
Y1127109D01*
X1219033Y1127559D01*
X1220078D01*
G01X1240095Y1069988D02*
Y1070100D01*
X1240275Y1070280D01*
Y1087337D01*
X1239750Y1087862D01*
X1237511D01*
X1236534Y1088839D01*
Y1089707D01*
X1236084Y1090157D01*
X1235039D01*
G01X1241205Y1069988D02*
Y1070100D01*
X1241025Y1070280D01*
Y1087648D01*
X1240061Y1088612D01*
X1237822D01*
X1237284Y1089150D01*
Y1089707D01*
X1237734Y1090157D01*
X1238779D01*
G01X1240437Y1098206D02*
X1240358Y1098285D01*
Y1098538D01*
X1239771Y1099125D01*
X1237408D01*
X1236534Y1100001D01*
Y1100927D01*
X1236084Y1101377D01*
X1235039D01*
G01X1241222Y1098991D02*
X1241182Y1099031D01*
X1240926D01*
X1240082Y1099875D01*
X1237720D01*
X1237284Y1100312D01*
Y1100927D01*
X1237734Y1101377D01*
X1238779D01*
G01X1514488Y1186086D02*
X1514600D01*
X1514780Y1185906D01*
X1524811D01*
X1525332Y1186427D01*
Y1187023D01*
X1524954Y1187401D01*
X1523819D01*
G01X1514488Y1184976D02*
X1514600D01*
X1514780Y1185156D01*
X1525122D01*
X1526082Y1186116D01*
Y1187029D01*
X1526454Y1187401D01*
X1527559D01*
G01X1511388Y1189826D02*
X1511500D01*
X1511680Y1189646D01*
X1517330D01*
X1517851Y1190167D01*
Y1190763D01*
X1517473Y1191141D01*
X1516338D01*
G01X1511388Y1192456D02*
X1511500D01*
X1511680Y1192636D01*
X1525122D01*
X1526082Y1193596D01*
Y1194509D01*
X1526454Y1194881D01*
X1527559D01*
G01X1511388Y1188716D02*
X1511500D01*
X1511680Y1188896D01*
X1517641D01*
X1518601Y1189856D01*
Y1190769D01*
X1518973Y1191141D01*
X1520078D01*
G01X1511388Y1193566D02*
X1511500D01*
X1511680Y1193386D01*
X1524811D01*
X1525332Y1193907D01*
Y1194503D01*
X1524954Y1194881D01*
X1523819D01*
G01X1604787Y1068787D02*
Y1068899D01*
X1604607Y1069079D01*
Y1094985D01*
X1605014Y1095392D01*
X1605651D01*
X1606101Y1094942D01*
Y1093897D01*
G01X1603677Y1068787D02*
Y1068899D01*
X1603857Y1069079D01*
Y1095296D01*
X1604703Y1096142D01*
X1605651D01*
X1606101Y1096592D01*
Y1097637D01*
G01X1609842Y1101376D02*
Y1102422D01*
X1609392Y1102872D01*
X1608755D01*
X1608347Y1102464D01*
Y1069292D01*
X1608527Y1069112D01*
Y1069000D01*
G01X1607417D02*
Y1069112D01*
X1607597Y1069292D01*
Y1102775D01*
X1608444Y1103622D01*
X1609392D01*
X1609842Y1104072D01*
Y1105117D01*
G01X1613581Y1093897D02*
Y1094942D01*
X1613131Y1095392D01*
X1612494D01*
X1612087Y1094985D01*
Y1069079D01*
X1612267Y1068899D01*
Y1068787D01*
G01X1611157D02*
Y1068899D01*
X1611337Y1069079D01*
Y1095296D01*
X1612183Y1096142D01*
X1613131D01*
X1613581Y1096592D01*
Y1097637D01*
G01X1614897Y1069000D02*
Y1069112D01*
X1615077Y1069292D01*
Y1102775D01*
X1615924Y1103622D01*
X1616872D01*
X1617322Y1104072D01*
Y1105117D01*
G01X1616007Y1069000D02*
Y1069112D01*
X1615827Y1069292D01*
Y1102464D01*
X1616235Y1102872D01*
X1616872D01*
X1617322Y1102422D01*
Y1101376D01*
G01X1511388Y1197306D02*
X1511500D01*
X1511680Y1197126D01*
X1517330D01*
X1517851Y1197647D01*
Y1198243D01*
X1517473Y1198621D01*
X1516338D01*
G01X1511388Y1196196D02*
X1511500D01*
X1511680Y1196376D01*
X1517641D01*
X1518601Y1197336D01*
Y1198249D01*
X1518973Y1198621D01*
X1520078D01*
G01X1511388Y1199937D02*
X1511500D01*
X1511680Y1200117D01*
X1525122D01*
X1526082Y1201077D01*
Y1201990D01*
X1526454Y1202362D01*
X1527559D01*
G01X1511388Y1201047D02*
X1511500D01*
X1511680Y1200867D01*
X1524811D01*
X1525332Y1201388D01*
Y1201984D01*
X1524954Y1202362D01*
X1523819D01*
G01X1516338Y1206102D02*
X1517473D01*
X1517851Y1205724D01*
Y1205128D01*
X1517330Y1204607D01*
X1511680D01*
X1511500Y1204787D01*
X1511388D01*
G01Y1203677D02*
X1511500D01*
X1511680Y1203857D01*
X1517641D01*
X1518601Y1204817D01*
Y1205730D01*
X1518973Y1206102D01*
X1520078D01*
G01X1511388Y1208527D02*
X1511500D01*
X1511680Y1208347D01*
X1524811D01*
X1525332Y1208868D01*
Y1209464D01*
X1524954Y1209842D01*
X1523819D01*
G01X1511388Y1207417D02*
X1511500D01*
X1511680Y1207597D01*
X1525122D01*
X1526082Y1208557D01*
Y1209470D01*
X1526454Y1209842D01*
X1527559D01*
G01X1621062Y1093897D02*
Y1094942D01*
X1620612Y1095392D01*
X1619975D01*
X1619568Y1094985D01*
Y1069079D01*
X1619748Y1068899D01*
Y1068787D01*
G01X1618638D02*
Y1068899D01*
X1618818Y1069079D01*
Y1095296D01*
X1619664Y1096142D01*
X1620612D01*
X1621062Y1096592D01*
Y1097637D01*
G01X1624803Y1101376D02*
Y1102422D01*
X1624353Y1102872D01*
X1623716D01*
X1623308Y1102464D01*
Y1069292D01*
X1623488Y1069112D01*
Y1069000D01*
G01X1622378D02*
Y1069112D01*
X1622558Y1069292D01*
Y1102775D01*
X1623405Y1103622D01*
X1624353D01*
X1624803Y1104072D01*
Y1105117D01*
G01X1627228Y1068787D02*
Y1068899D01*
X1627048Y1069079D01*
Y1094985D01*
X1627455Y1095392D01*
X1628092D01*
X1628542Y1094942D01*
Y1093897D01*
G01X1632283Y1105117D02*
Y1104072D01*
X1631833Y1103622D01*
X1630885D01*
X1630038Y1102775D01*
Y1069292D01*
X1629858Y1069112D01*
Y1069000D01*
G01X1628542Y1097637D02*
Y1096592D01*
X1628092Y1096142D01*
X1627144D01*
X1626298Y1095296D01*
Y1069079D01*
X1626118Y1068899D01*
Y1068787D01*
G01X1630968Y1069000D02*
Y1069112D01*
X1630788Y1069292D01*
Y1102464D01*
X1631196Y1102872D01*
X1631833D01*
X1632283Y1102422D01*
Y1101376D01*
G01X1636022Y1097637D02*
Y1096592D01*
X1635572Y1096142D01*
X1634624D01*
X1633778Y1095296D01*
Y1069079D01*
X1633598Y1068899D01*
Y1068787D01*
G01X1520078Y1213582D02*
X1518973D01*
X1518601Y1213210D01*
Y1212297D01*
X1517641Y1211337D01*
X1511680D01*
X1511500Y1211157D01*
X1511388D01*
G01X1516338Y1213582D02*
X1517473D01*
X1517851Y1213204D01*
Y1212608D01*
X1517330Y1212087D01*
X1511680D01*
X1511500Y1212267D01*
X1511388D01*
G01X1636022Y1093897D02*
Y1094942D01*
X1635572Y1095392D01*
X1634935D01*
X1634528Y1094985D01*
Y1069079D01*
X1634708Y1068899D01*
Y1068787D01*
G01X1639763Y1101376D02*
Y1102422D01*
X1639313Y1102872D01*
X1638676D01*
X1638268Y1102464D01*
Y1069292D01*
X1638448Y1069112D01*
Y1069000D01*
G01X1637338D02*
Y1069112D01*
X1637518Y1069292D01*
Y1102775D01*
X1638365Y1103622D01*
X1639313D01*
X1639763Y1104072D01*
Y1105117D01*
G01X1641079Y1068787D02*
Y1068899D01*
X1641259Y1069079D01*
Y1095296D01*
X1642105Y1096142D01*
X1643053D01*
X1643503Y1096592D01*
Y1097637D01*
G01X1642189Y1068787D02*
Y1068899D01*
X1642009Y1069079D01*
Y1094985D01*
X1642416Y1095392D01*
X1643053D01*
X1643503Y1094942D01*
Y1093897D01*
G01X1645929Y1069000D02*
Y1069112D01*
X1645749Y1069292D01*
Y1102464D01*
X1646157Y1102872D01*
X1646794D01*
X1647244Y1102422D01*
Y1101376D01*
G01Y1105117D02*
Y1104072D01*
X1646794Y1103622D01*
X1645846D01*
X1644999Y1102775D01*
Y1069292D01*
X1644819Y1069112D01*
Y1069000D01*
G01X1650983Y1097637D02*
Y1096592D01*
X1650533Y1096142D01*
X1649585D01*
X1648739Y1095296D01*
Y1069079D01*
X1648559Y1068899D01*
Y1068787D01*
G01X1654724Y1105117D02*
Y1104072D01*
X1654274Y1103622D01*
X1653326D01*
X1652479Y1102775D01*
Y1069292D01*
X1652299Y1069112D01*
Y1069000D01*
G01X1650983Y1093897D02*
Y1094942D01*
X1650533Y1095392D01*
X1649896D01*
X1649489Y1094985D01*
Y1069079D01*
X1649669Y1068899D01*
Y1068787D01*
G01X1654724Y1101376D02*
Y1102422D01*
X1654274Y1102872D01*
X1653637D01*
X1653229Y1102464D01*
Y1069292D01*
X1653409Y1069112D01*
Y1069000D01*
G01X1658463Y1097637D02*
Y1096592D01*
X1658013Y1096142D01*
X1657065D01*
X1656219Y1095296D01*
Y1069079D01*
X1656039Y1068899D01*
Y1068787D01*
G01X1657149D02*
Y1068899D01*
X1656969Y1069079D01*
Y1094985D01*
X1657376Y1095392D01*
X1658013D01*
X1658463Y1094942D01*
Y1093897D01*
G01X1527559Y1217322D02*
X1526454D01*
X1526082Y1216950D01*
Y1216037D01*
X1525122Y1215077D01*
X1511580D01*
X1511400Y1214897D01*
X1511288D01*
G01Y1216007D02*
X1511400D01*
X1511580Y1215827D01*
X1524811D01*
X1525332Y1216348D01*
Y1216944D01*
X1524954Y1217322D01*
X1523819D01*
G01X1520078Y1221062D02*
X1518933D01*
X1518583Y1221412D01*
Y1222218D01*
X1517494Y1223307D01*
X1515054D01*
X1514496Y1223865D01*
Y1224121D01*
X1514417Y1224200D01*
G01X1516338Y1221062D02*
X1517483D01*
X1517833Y1221412D01*
Y1221907D01*
X1517183Y1222557D01*
X1514743D01*
X1513963Y1223337D01*
X1513711Y1223336D01*
X1513632Y1223415D01*
G01X1662204Y1105117D02*
Y1104072D01*
X1661754Y1103622D01*
X1660806D01*
X1659959Y1102775D01*
Y1069292D01*
X1659779Y1069112D01*
Y1069000D01*
G01X1662204Y1101376D02*
Y1102422D01*
X1661754Y1102872D01*
X1661117D01*
X1660709Y1102464D01*
Y1069292D01*
X1660889Y1069112D01*
Y1069000D01*
G01X1518763Y1255712D02*
Y1255600D01*
X1518583Y1255420D01*
Y1247593D01*
X1518933Y1247243D01*
X1520078D01*
G01X1517653Y1255712D02*
Y1255600D01*
X1517833Y1255420D01*
Y1247593D01*
X1517483Y1247243D01*
X1516338D01*
G01X1528874Y1259424D02*
Y1259312D01*
X1529054Y1259132D01*
Y1253420D01*
X1529995Y1252479D01*
X1530949D01*
X1531299Y1252129D01*
Y1250984D01*
G01X1525135Y1259424D02*
Y1259312D01*
X1525315Y1259132D01*
Y1246087D01*
X1526404Y1244998D01*
X1527210D01*
X1527560Y1244648D01*
Y1243504D01*
X1527559Y1243503D01*
G01X1526245Y1259424D02*
Y1259312D01*
X1526065Y1259132D01*
Y1246398D01*
X1526715Y1245748D01*
X1527210D01*
X1527560Y1246098D01*
Y1247242D01*
X1527559Y1247243D01*
G01X1529984Y1259424D02*
Y1259312D01*
X1529804Y1259132D01*
Y1253731D01*
X1530306Y1253229D01*
X1530949D01*
X1531299Y1253579D01*
Y1254724D01*
G01X1521394Y1259424D02*
Y1259312D01*
X1521574Y1259132D01*
Y1253420D01*
X1522515Y1252479D01*
X1523469D01*
X1523819Y1252129D01*
Y1250984D01*
G01X1522504Y1259424D02*
Y1259312D01*
X1522324Y1259132D01*
Y1253731D01*
X1522826Y1253229D01*
X1523469D01*
X1523819Y1253579D01*
Y1254724D01*
G01X1536354Y1259424D02*
Y1259312D01*
X1536534Y1259132D01*
Y1253420D01*
X1537475Y1252479D01*
X1538429D01*
X1538779Y1252129D01*
Y1250984D01*
G01X1537464Y1259424D02*
Y1259312D01*
X1537284Y1259132D01*
Y1253731D01*
X1537786Y1253229D01*
X1538429D01*
X1538779Y1253579D01*
Y1254724D01*
G01X1532615Y1259424D02*
Y1259312D01*
X1532795Y1259132D01*
Y1246087D01*
X1533884Y1244998D01*
X1534690D01*
X1535040Y1244648D01*
Y1243504D01*
X1535039Y1243503D01*
G01X1533725Y1259424D02*
Y1259312D01*
X1533545Y1259132D01*
Y1246398D01*
X1534195Y1245748D01*
X1534690D01*
X1535040Y1246098D01*
Y1247242D01*
X1535039Y1247243D01*
G01X1663520Y1068787D02*
Y1068899D01*
X1663700Y1069079D01*
Y1095296D01*
X1664546Y1096142D01*
X1665494D01*
X1665944Y1096592D01*
Y1097637D01*
G01X1664630Y1068787D02*
Y1068899D01*
X1664450Y1069079D01*
Y1094985D01*
X1664857Y1095392D01*
X1665494D01*
X1665944Y1094942D01*
Y1093897D01*
G01X1669685Y1105117D02*
Y1104072D01*
X1669235Y1103622D01*
X1668287D01*
X1667440Y1102775D01*
Y1069292D01*
X1667260Y1069112D01*
Y1069000D01*
G01X1668370D02*
Y1069112D01*
X1668190Y1069292D01*
Y1102464D01*
X1668598Y1102872D01*
X1669235D01*
X1669685Y1102422D01*
Y1101376D01*
G01X1673424Y1097637D02*
Y1096592D01*
X1672974Y1096142D01*
X1672026D01*
X1671180Y1095296D01*
Y1069079D01*
X1671000Y1068899D01*
Y1068787D01*
G01X1673424Y1093897D02*
Y1094942D01*
X1672974Y1095392D01*
X1672337D01*
X1671930Y1094985D01*
Y1069079D01*
X1672110Y1068899D01*
Y1068787D01*
G01X1677165Y1105117D02*
Y1104072D01*
X1676715Y1103622D01*
X1675767D01*
X1674920Y1102775D01*
Y1069292D01*
X1674740Y1069112D01*
Y1069000D01*
G01X1675850D02*
Y1069112D01*
X1675670Y1069292D01*
Y1102464D01*
X1676078Y1102872D01*
X1676715D01*
X1677165Y1102422D01*
Y1101376D01*
G01X1680904Y1097637D02*
Y1096592D01*
X1680454Y1096142D01*
X1679506D01*
X1678660Y1095296D01*
Y1069079D01*
X1678480Y1068899D01*
Y1068787D01*
G01X1679590D02*
Y1068899D01*
X1679410Y1069079D01*
Y1094985D01*
X1679817Y1095392D01*
X1680454D01*
X1680904Y1094942D01*
Y1093897D01*
G01X1683330Y1069000D02*
Y1069112D01*
X1683150Y1069292D01*
Y1102464D01*
X1683558Y1102872D01*
X1684195D01*
X1684645Y1102422D01*
Y1101377D01*
G01X1682220Y1069000D02*
Y1069112D01*
X1682400Y1069292D01*
Y1102775D01*
X1683247Y1103622D01*
X1684195D01*
X1684645Y1104072D01*
Y1105117D01*
G01X1701644Y1110173D02*
X1701532D01*
X1701352Y1110353D01*
X1675767D01*
X1674920Y1111200D01*
Y1112148D01*
X1674470Y1112598D01*
X1673425D01*
G01X1701550Y1121392D02*
X1701438D01*
X1701258Y1121572D01*
X1668287D01*
X1667439Y1122420D01*
Y1123368D01*
X1666989Y1123818D01*
X1665944D01*
G01X1701644Y1118763D02*
X1701532D01*
X1701352Y1118583D01*
X1676078D01*
X1675670Y1118991D01*
Y1119628D01*
X1676120Y1120078D01*
X1677165D01*
G01X1701644Y1111283D02*
X1701532D01*
X1701352Y1111103D01*
X1676078D01*
X1675670Y1111511D01*
Y1112148D01*
X1676120Y1112598D01*
X1677165D01*
G01X1673425Y1120078D02*
X1674470D01*
X1674920Y1119628D01*
Y1118680D01*
X1675767Y1117833D01*
X1701352D01*
X1701532Y1117653D01*
X1701644D01*
G01X1701550Y1122502D02*
X1701438D01*
X1701258Y1122322D01*
X1668598D01*
X1668189Y1122731D01*
Y1123368D01*
X1668639Y1123818D01*
X1669685D01*
G01X1701550Y1113912D02*
X1701438D01*
X1701258Y1114092D01*
X1668287D01*
X1667439Y1114940D01*
Y1115888D01*
X1666989Y1116338D01*
X1665944D01*
G01X1701550Y1115022D02*
X1701438D01*
X1701258Y1114842D01*
X1668598D01*
X1668189Y1115251D01*
Y1115888D01*
X1668639Y1116338D01*
X1669685D01*
G01X1701550Y1128873D02*
X1701438D01*
X1701258Y1129053D01*
X1668287D01*
X1667439Y1129901D01*
Y1130849D01*
X1666989Y1131299D01*
X1665944D01*
G01X1701644Y1133724D02*
X1701532D01*
X1701352Y1133544D01*
X1676078D01*
X1675670Y1133952D01*
Y1134589D01*
X1676120Y1135039D01*
X1677165D01*
G01X1701550Y1129983D02*
X1701438D01*
X1701258Y1129803D01*
X1668598D01*
X1668189Y1130212D01*
Y1130849D01*
X1668639Y1131299D01*
X1669685D01*
G01X1701644Y1125134D02*
X1701532D01*
X1701352Y1125314D01*
X1675767D01*
X1674920Y1126161D01*
Y1127109D01*
X1674470Y1127559D01*
X1673425D01*
G01X1701644Y1126244D02*
X1701532D01*
X1701352Y1126064D01*
X1676078D01*
X1675670Y1126472D01*
Y1127109D01*
X1676120Y1127559D01*
X1677165D01*
G01X1701644Y1132614D02*
X1701532D01*
X1701352Y1132794D01*
X1675767D01*
X1674920Y1133641D01*
Y1134589D01*
X1674470Y1135039D01*
X1673425D01*
G01X1698292Y1069988D02*
Y1070100D01*
X1698112Y1070280D01*
Y1087648D01*
X1697148Y1088612D01*
X1694909D01*
X1694371Y1089150D01*
Y1089707D01*
X1694821Y1090157D01*
X1695866D01*
G01X1697182Y1069988D02*
Y1070100D01*
X1697362Y1070280D01*
Y1087337D01*
X1696837Y1087862D01*
X1694598D01*
X1693621Y1088839D01*
Y1089707D01*
X1693171Y1090157D01*
X1692126D01*
G01X1685961Y1068787D02*
Y1068899D01*
X1686141Y1069079D01*
Y1095296D01*
X1686987Y1096142D01*
X1687935D01*
X1688385Y1096592D01*
Y1097637D01*
G01X1687071Y1068787D02*
Y1068899D01*
X1686891Y1069079D01*
Y1094985D01*
X1687298Y1095392D01*
X1687935D01*
X1688385Y1094942D01*
Y1093897D01*
G01X1697524Y1098206D02*
X1697445Y1098285D01*
Y1098538D01*
X1696858Y1099125D01*
X1694495D01*
X1693621Y1100001D01*
Y1100927D01*
X1693171Y1101377D01*
X1692126D01*
G01X1698309Y1098991D02*
X1698269Y1099031D01*
X1698013D01*
X1697169Y1099875D01*
X1694807D01*
X1694371Y1100312D01*
Y1100927D01*
X1694821Y1101377D01*
X1695866D01*
G54D25*
X895384Y228740D03*
Y276772D03*
X923336Y278740D03*
G54D16*
X116731Y1249086D03*
X106619Y1253274D03*
X102431Y1263386D03*
X106619Y1273498D03*
X116731Y1277686D03*
X126843Y1253274D03*
X131031Y1263386D03*
X126843Y1273498D03*
X563706Y1056423D03*
X559518Y1066535D03*
X563706Y1076647D03*
X583930Y1056423D03*
X573818Y1052235D03*
X583930Y1076647D03*
X588118Y1066535D03*
X573818Y1080835D03*
X799926Y1253274D03*
X795738Y1263386D03*
X799926Y1273498D03*
X810040Y378544D03*
X805881Y388583D03*
X810040Y398622D03*
X810038Y1249086D03*
Y1277686D03*
X820079Y374385D03*
X830118Y378544D03*
X820079Y402781D03*
X830118Y398622D03*
X820150Y1253274D03*
X824338Y1263386D03*
X820150Y1273498D03*
X834277Y388583D03*
X1010827Y378544D03*
X1006668Y388583D03*
X1010827Y398622D03*
X1020866Y374385D03*
Y402781D03*
X1020793Y1253274D03*
X1016605Y1263386D03*
X1020793Y1273498D03*
X1030905Y378544D03*
X1035064Y388583D03*
X1030905Y398622D03*
X1041017Y1253274D03*
X1030905Y1249086D03*
Y1277686D03*
X1041017Y1273498D03*
X1045205Y1263386D03*
X1252825D03*
X1267125Y1249086D03*
X1257013Y1253274D03*
Y1273498D03*
X1267125Y1277686D03*
X1277237Y1253274D03*
X1281425Y1263386D03*
X1277237Y1273498D03*
G54D35*
G01X1053436Y1183141D02*
X994023Y1242554D01*
Y1255940D01*
X953817Y1296146D01*
Y1305456D01*
X932504Y1326769D01*
X925700D01*
X924650Y1327819D01*
G01X1052516Y1182222D02*
X1036483Y1198255D01*
X1035493D01*
X1034431Y1199317D01*
Y1200307D01*
X1032117Y1202621D01*
X1031127D01*
X1030065Y1203683D01*
Y1204673D01*
X1028797Y1205941D01*
X1027807D01*
X1026745Y1207003D01*
Y1207993D01*
X992723Y1242015D01*
Y1255401D01*
X952517Y1295607D01*
Y1304917D01*
X931965Y1325469D01*
X925700D01*
X924650Y1324419D01*
G01X1169329Y1728990D02*
Y1732826D01*
X1168815Y1733340D01*
X1154936D01*
X1154436Y1732840D01*
Y1725023D01*
X1153175Y1723762D01*
X1146587D01*
X1145326Y1725023D01*
Y1735854D01*
X1144826Y1736354D01*
X1139316D01*
X1138816Y1735854D01*
Y1725023D01*
X1137555Y1723762D01*
X1130967D01*
X1129706Y1725023D01*
Y1735854D01*
X1129206Y1736354D01*
X1123696D01*
X1123196Y1735854D01*
Y1725023D01*
X1121935Y1723762D01*
X1115347D01*
X1114086Y1725023D01*
Y1735854D01*
X1113586Y1736354D01*
X1108076D01*
X1107576Y1735854D01*
Y1725023D01*
X1106315Y1723762D01*
X1099727D01*
X1098466Y1725023D01*
Y1735854D01*
X1097966Y1736354D01*
X1092456D01*
X1091956Y1735854D01*
Y1725023D01*
X1090695Y1723762D01*
X1084107D01*
X1082846Y1725023D01*
Y1735854D01*
X1082346Y1736354D01*
X1076836D01*
X1076336Y1735854D01*
Y1725023D01*
X1075075Y1723762D01*
X1068487D01*
X1067226Y1725023D01*
Y1735854D01*
X1066726Y1736354D01*
X1061216D01*
X1060716Y1735854D01*
Y1725023D01*
X1059455Y1723762D01*
X1052867D01*
X1051606Y1725023D01*
Y1735854D01*
X1051106Y1736354D01*
X1045596D01*
X1045096Y1735854D01*
Y1725023D01*
X1043835Y1723762D01*
X1037247D01*
X1035986Y1725023D01*
Y1735854D01*
X1035486Y1736354D01*
X1029976D01*
X1029476Y1735854D01*
Y1725023D01*
X1028215Y1723762D01*
X1021627D01*
X1020366Y1725023D01*
Y1735854D01*
X1019866Y1736354D01*
X1014356D01*
X1013856Y1735854D01*
Y1725023D01*
X1012595Y1723762D01*
X1006007D01*
X1004746Y1725023D01*
Y1735854D01*
X1004246Y1736354D01*
X998736D01*
X998236Y1735854D01*
Y1725023D01*
X996975Y1723762D01*
X990387D01*
X989126Y1725023D01*
Y1735854D01*
X988626Y1736354D01*
X983116D01*
X982616Y1735854D01*
Y1725023D01*
X981355Y1723762D01*
X974767D01*
X973506Y1725023D01*
Y1735854D01*
X973006Y1736354D01*
X967496D01*
X966996Y1735854D01*
Y1725023D01*
X965735Y1723762D01*
X959147D01*
X957886Y1725023D01*
Y1735854D01*
X957386Y1736354D01*
X951876D01*
X951376Y1735854D01*
Y1725023D01*
X950115Y1723762D01*
X943527D01*
X942266Y1725023D01*
Y1735716D01*
X941766Y1736216D01*
X936256D01*
X935756Y1735716D01*
Y1725023D01*
X934495Y1723762D01*
X927907D01*
X926646Y1725023D01*
Y1732840D01*
X926146Y1733340D01*
X917779D01*
X917279Y1732840D01*
Y1728990D01*
G01X1169329Y1738990D02*
Y1735062D01*
X1168907Y1734640D01*
X1154397D01*
X1153136Y1733379D01*
Y1725562D01*
X1152636Y1725062D01*
X1147126D01*
X1146626Y1725562D01*
Y1736393D01*
X1145365Y1737654D01*
X1138777D01*
X1137516Y1736393D01*
Y1725562D01*
X1137016Y1725062D01*
X1131506D01*
X1131006Y1725562D01*
Y1736393D01*
X1129745Y1737654D01*
X1123157D01*
X1121896Y1736393D01*
Y1725562D01*
X1121396Y1725062D01*
X1115886D01*
X1115386Y1725562D01*
Y1736393D01*
X1114125Y1737654D01*
X1107537D01*
X1106276Y1736393D01*
Y1725562D01*
X1105776Y1725062D01*
X1100266D01*
X1099766Y1725562D01*
Y1736393D01*
X1098505Y1737654D01*
X1091917D01*
X1090656Y1736393D01*
Y1725562D01*
X1090156Y1725062D01*
X1084646D01*
X1084146Y1725562D01*
Y1736393D01*
X1082885Y1737654D01*
X1076297D01*
X1075036Y1736393D01*
Y1725562D01*
X1074536Y1725062D01*
X1069026D01*
X1068526Y1725562D01*
Y1736393D01*
X1067265Y1737654D01*
X1060677D01*
X1059416Y1736393D01*
Y1725562D01*
X1058916Y1725062D01*
X1053406D01*
X1052906Y1725562D01*
Y1736393D01*
X1051645Y1737654D01*
X1045057D01*
X1043796Y1736393D01*
Y1725562D01*
X1043296Y1725062D01*
X1037786D01*
X1037286Y1725562D01*
Y1736393D01*
X1036025Y1737654D01*
X1029437D01*
X1028176Y1736393D01*
Y1725562D01*
X1027676Y1725062D01*
X1022166D01*
X1021666Y1725562D01*
Y1736393D01*
X1020405Y1737654D01*
X1013817D01*
X1012556Y1736393D01*
Y1725562D01*
X1012056Y1725062D01*
X1006546D01*
X1006046Y1725562D01*
Y1736393D01*
X1004785Y1737654D01*
X998197D01*
X996936Y1736393D01*
Y1725562D01*
X996436Y1725062D01*
X990926D01*
X990426Y1725562D01*
Y1736393D01*
X989165Y1737654D01*
X982577D01*
X981316Y1736393D01*
Y1725562D01*
X980816Y1725062D01*
X975306D01*
X974806Y1725562D01*
Y1736393D01*
X973545Y1737654D01*
X966957D01*
X965696Y1736393D01*
Y1725562D01*
X965196Y1725062D01*
X959686D01*
X959186Y1725562D01*
Y1736393D01*
X957925Y1737654D01*
X951337D01*
X950076Y1736393D01*
Y1725562D01*
X949576Y1725062D01*
X944066D01*
X943566Y1725562D01*
Y1736255D01*
X942305Y1737516D01*
X935717D01*
X934456Y1736255D01*
Y1725562D01*
X933956Y1725062D01*
X928446D01*
X927946Y1725562D01*
Y1733379D01*
X926685Y1734640D01*
X917779D01*
X917279Y1735140D01*
Y1738990D01*
G54D17*
X109882Y1453504D03*
Y1468859D03*
Y1484213D03*
Y1499567D03*
Y1514922D03*
Y1555867D03*
Y1571221D03*
Y1586575D03*
Y1601930D03*
Y1617284D03*
X127205Y1453504D03*
X118543Y1457835D03*
X127205Y1468859D03*
X118543Y1473189D03*
X127205Y1484213D03*
X118543Y1488544D03*
X127205Y1499567D03*
Y1514922D03*
X118543Y1503898D03*
Y1519252D03*
X127205Y1555867D03*
X118543Y1560197D03*
X127205Y1571221D03*
X118543Y1575552D03*
X127205Y1586575D03*
X118543Y1590906D03*
X127205Y1601930D03*
X118543Y1606260D03*
X127205Y1617284D03*
X118543Y1621615D03*
X144528Y1453504D03*
X135866Y1457835D03*
X144528Y1468859D03*
X135866Y1473189D03*
X144528Y1484213D03*
X135866Y1488544D03*
X144528Y1499567D03*
Y1514922D03*
X135866Y1503898D03*
Y1519252D03*
X144528Y1555867D03*
X135866Y1560197D03*
X144528Y1571221D03*
X135866Y1575552D03*
X144528Y1586575D03*
X135866Y1590906D03*
X144528Y1601930D03*
X135866Y1606260D03*
X144528Y1617284D03*
X135866Y1621615D03*
X161850Y1453504D03*
X153189Y1457835D03*
X161850Y1468859D03*
X153189Y1473189D03*
X161850Y1484213D03*
X153189Y1488544D03*
X161850Y1499567D03*
Y1514922D03*
X153189Y1503898D03*
Y1519252D03*
X161850Y1555867D03*
X153189Y1560197D03*
X161850Y1571221D03*
X153189Y1575552D03*
X161850Y1586575D03*
X153189Y1590906D03*
X161850Y1601930D03*
X153189Y1606260D03*
X161850Y1617284D03*
X153189Y1621615D03*
X179173Y1453504D03*
X170512Y1457835D03*
X179173Y1468859D03*
X170512Y1473189D03*
X179173Y1484213D03*
X170512Y1488544D03*
X179173Y1499567D03*
Y1514922D03*
X170512Y1503898D03*
Y1519252D03*
X179173Y1555867D03*
X170512Y1560197D03*
X179173Y1571221D03*
X170512Y1575552D03*
X179173Y1586575D03*
X170512Y1590906D03*
X179173Y1601930D03*
X170512Y1606260D03*
X179173Y1617284D03*
X170512Y1621615D03*
X187835Y1457835D03*
Y1473189D03*
Y1488544D03*
Y1503898D03*
Y1519252D03*
Y1560197D03*
Y1575552D03*
X456339Y1453504D03*
Y1468859D03*
Y1484213D03*
Y1499567D03*
Y1514922D03*
Y1555867D03*
Y1571221D03*
Y1586575D03*
Y1601930D03*
Y1617284D03*
X473662Y1453504D03*
X465000Y1457835D03*
X473662Y1468859D03*
X465000Y1473189D03*
X473662Y1484213D03*
X465000Y1488544D03*
X473662Y1499567D03*
Y1514922D03*
X465000Y1503898D03*
Y1519252D03*
X473662Y1555867D03*
X465000Y1560197D03*
X473662Y1571221D03*
X465000Y1575552D03*
X473662Y1586575D03*
X465000Y1590906D03*
X473662Y1601930D03*
X465000Y1606260D03*
X473662Y1617284D03*
X465000Y1621615D03*
X490985Y1453504D03*
X482323Y1457835D03*
X490985Y1468859D03*
X482323Y1473189D03*
X490985Y1484213D03*
X482323Y1488544D03*
X490985Y1499567D03*
Y1514922D03*
X482323Y1503898D03*
Y1519252D03*
X490985Y1555867D03*
X482323Y1560197D03*
X490985Y1571221D03*
X482323Y1575552D03*
X490985Y1586575D03*
X482323Y1590906D03*
X490985Y1601930D03*
X482323Y1606260D03*
X490985Y1617284D03*
X482323Y1621615D03*
X508307Y1453504D03*
X499646Y1457835D03*
X508307Y1468859D03*
X499646Y1473189D03*
X508307Y1484213D03*
X499646Y1488544D03*
X508307Y1499567D03*
Y1514922D03*
X499646Y1503898D03*
Y1519252D03*
X508307Y1555867D03*
X499646Y1560197D03*
X508307Y1571221D03*
X499646Y1575552D03*
X508307Y1586575D03*
X499646Y1590906D03*
X508307Y1601930D03*
X499646Y1606260D03*
X508307Y1617284D03*
X499646Y1621615D03*
X516969Y1457835D03*
Y1473189D03*
Y1488544D03*
Y1503898D03*
Y1519252D03*
Y1560197D03*
Y1575552D03*
Y1590906D03*
Y1606260D03*
Y1621615D03*
X525630Y1453504D03*
X534292Y1457835D03*
X525630Y1468859D03*
X534292Y1473189D03*
X525630Y1484213D03*
X534292Y1488544D03*
X525630Y1499567D03*
X534292Y1503898D03*
X525630Y1514922D03*
X534292Y1519252D03*
X525630Y1555867D03*
X534292Y1560197D03*
X525630Y1571221D03*
X534292Y1575552D03*
X525630Y1586575D03*
X534292Y1590906D03*
X525630Y1601930D03*
X534292Y1606260D03*
X525630Y1617284D03*
X534292Y1621615D03*
X707520Y1457835D03*
Y1473189D03*
Y1488544D03*
Y1503898D03*
Y1519252D03*
Y1560197D03*
Y1575552D03*
Y1590906D03*
Y1606260D03*
Y1621615D03*
X1131850Y1453504D03*
X1140511Y1457835D03*
X1131850Y1468859D03*
X1140511Y1473189D03*
X1131850Y1484213D03*
X1140511Y1488544D03*
X1131850Y1499567D03*
X1140511Y1503898D03*
X1131850Y1514922D03*
X1140511Y1519252D03*
X1131850Y1555867D03*
X1140511Y1560197D03*
X1131850Y1571221D03*
X1140511Y1575552D03*
X1131850Y1586575D03*
X1140511Y1590906D03*
X1131850Y1601930D03*
X1140511Y1606260D03*
X1131850Y1617284D03*
X1140511Y1621615D03*
X1149173Y1453504D03*
X1157834Y1457835D03*
X1149173Y1468859D03*
X1157834Y1473189D03*
X1149173Y1484213D03*
X1157834Y1488544D03*
X1149173Y1499567D03*
X1157834Y1503898D03*
X1149173Y1514922D03*
X1157834Y1519252D03*
X1149173Y1555867D03*
X1157834Y1560197D03*
X1149173Y1571221D03*
X1157834Y1575552D03*
X1149173Y1586575D03*
X1157834Y1590906D03*
X1149173Y1601930D03*
X1157834Y1606260D03*
X1149173Y1617284D03*
X1157834Y1621615D03*
X1166496Y1453504D03*
Y1468859D03*
Y1484213D03*
Y1499567D03*
Y1514922D03*
Y1555867D03*
Y1571221D03*
Y1586575D03*
Y1601930D03*
Y1617284D03*
X1183818Y1453504D03*
X1175157Y1457835D03*
X1183818Y1468859D03*
X1175157Y1473189D03*
X1183818Y1484213D03*
X1175157Y1488544D03*
X1183818Y1499567D03*
Y1514922D03*
X1175157Y1503898D03*
Y1519252D03*
X1183818Y1555867D03*
X1175157Y1560197D03*
X1183818Y1571221D03*
X1175157Y1575552D03*
X1183818Y1586575D03*
X1175157Y1590906D03*
X1183818Y1601930D03*
X1175157Y1606260D03*
X1183818Y1617284D03*
X1175157Y1621615D03*
X1201141Y1453504D03*
X1192480Y1457835D03*
X1201141Y1468859D03*
X1192480Y1473189D03*
X1201141Y1484213D03*
X1192480Y1488544D03*
X1201141Y1499567D03*
Y1514922D03*
X1192480Y1503898D03*
Y1519252D03*
X1201141Y1555867D03*
X1192480Y1560197D03*
X1201141Y1571221D03*
X1192480Y1575552D03*
X1201141Y1586575D03*
X1192480Y1590906D03*
X1201141Y1601930D03*
X1192480Y1606260D03*
X1201141Y1617284D03*
X1192480Y1621615D03*
X1209803Y1457835D03*
Y1473189D03*
Y1488544D03*
Y1503898D03*
Y1519252D03*
Y1560197D03*
Y1575552D03*
Y1590906D03*
Y1606260D03*
Y1621615D03*
X1305079Y1484213D03*
X1313740Y1488544D03*
X1305079Y1499567D03*
X1313740Y1503898D03*
X1305079Y1514922D03*
X1313740Y1519252D03*
X1305079Y1571221D03*
X1313740Y1575552D03*
X1305079Y1586575D03*
X1313740Y1590906D03*
X1305079Y1601930D03*
X1313740Y1606260D03*
X1305079Y1617284D03*
X1313740Y1621615D03*
X1322402Y1484213D03*
X1331063Y1488544D03*
X1322402Y1499567D03*
X1331063Y1503898D03*
X1322402Y1514922D03*
X1331063Y1519252D03*
X1322402Y1571221D03*
X1331063Y1575552D03*
X1322402Y1586575D03*
X1331063Y1590906D03*
X1322402Y1601930D03*
X1331063Y1606260D03*
X1322402Y1617284D03*
X1331063Y1621615D03*
X1339725Y1484213D03*
X1348386Y1488544D03*
X1339725Y1499567D03*
X1348386Y1503898D03*
X1339725Y1514922D03*
X1348386Y1519252D03*
X1339725Y1571221D03*
X1348386Y1575552D03*
X1339725Y1586575D03*
X1348386Y1590906D03*
X1339725Y1601930D03*
X1348386Y1606260D03*
X1339725Y1617284D03*
X1348386Y1621615D03*
X1357047Y1484213D03*
X1365709Y1488544D03*
X1357047Y1499567D03*
X1365709Y1503898D03*
X1357047Y1514922D03*
Y1571221D03*
X1365709Y1575552D03*
X1357047Y1586575D03*
X1365709Y1590906D03*
X1357047Y1601930D03*
X1365709Y1606260D03*
X1357047Y1617284D03*
X1365709Y1621615D03*
X1374370Y1484213D03*
X1383032Y1560197D03*
X1374370Y1571221D03*
X1383032Y1575552D03*
X1374370Y1586575D03*
X1383032Y1590906D03*
X1374370Y1601930D03*
X1383032Y1606260D03*
X1374370Y1617284D03*
X1383032Y1621615D03*
X1478307Y1453504D03*
Y1468859D03*
Y1484213D03*
Y1499567D03*
Y1514922D03*
Y1555867D03*
Y1571221D03*
Y1586575D03*
Y1601930D03*
Y1617284D03*
X1495630Y1453504D03*
X1486968Y1457835D03*
X1495630Y1468859D03*
X1486968Y1473189D03*
X1495630Y1484213D03*
X1486968Y1488544D03*
X1495630Y1499567D03*
Y1514922D03*
X1486968Y1503898D03*
Y1519252D03*
X1495630Y1555867D03*
X1486968Y1560197D03*
X1495630Y1571221D03*
X1486968Y1575552D03*
X1495630Y1586575D03*
X1486968Y1590906D03*
X1495630Y1601930D03*
X1486968Y1606260D03*
X1495630Y1617284D03*
X1486968Y1621615D03*
X1512953Y1453504D03*
X1504291Y1457835D03*
X1512953Y1468859D03*
X1504291Y1473189D03*
X1512953Y1484213D03*
X1504291Y1488544D03*
X1512953Y1499567D03*
Y1514922D03*
X1504291Y1503898D03*
Y1519252D03*
X1512953Y1555867D03*
X1504291Y1560197D03*
X1512953Y1571221D03*
X1504291Y1575552D03*
X1512953Y1586575D03*
X1504291Y1590906D03*
X1512953Y1601930D03*
X1504291Y1606260D03*
X1512953Y1617284D03*
X1504291Y1621615D03*
X1530275Y1453504D03*
X1521614Y1457835D03*
X1530275Y1468859D03*
X1521614Y1473189D03*
X1530275Y1484213D03*
X1521614Y1488544D03*
X1530275Y1499567D03*
Y1514922D03*
X1521614Y1503898D03*
Y1519252D03*
X1530275Y1555867D03*
X1521614Y1560197D03*
X1530275Y1571221D03*
X1521614Y1575552D03*
X1530275Y1586575D03*
X1521614Y1590906D03*
X1530275Y1601930D03*
X1521614Y1606260D03*
X1530275Y1617284D03*
X1521614Y1621615D03*
X1547598Y1453504D03*
X1538937Y1457835D03*
X1547598Y1468859D03*
X1538937Y1473189D03*
X1547598Y1484213D03*
X1538937Y1488544D03*
X1547598Y1499567D03*
Y1514922D03*
X1538937Y1503898D03*
Y1519252D03*
Y1560197D03*
Y1575552D03*
Y1590906D03*
Y1606260D03*
Y1621615D03*
X1556260Y1457835D03*
Y1473189D03*
Y1488544D03*
Y1503898D03*
Y1519252D03*
X1729488Y1457835D03*
Y1473189D03*
Y1488544D03*
Y1503898D03*
Y1519252D03*
G54D26*
X1030635Y764546D03*
G54D36*
G01X7983Y1529035D02*
X9090Y1527928D01*
X13911D01*
X16088Y1525751D01*
X22808D01*
X28896Y1519663D01*
Y1499753D01*
X54703Y1473946D01*
Y1463663D01*
X50887Y1459847D01*
X39379D01*
X36985Y1462241D01*
Y1463685D01*
X35825Y1464845D01*
G01X7983Y1525635D02*
X9196Y1526848D01*
X13463D01*
X15640Y1524671D01*
X22360D01*
X24357Y1522674D01*
Y1521981D01*
X25582Y1520756D01*
X26275D01*
X27816Y1519215D01*
Y1516965D01*
X27326Y1516475D01*
Y1514745D01*
X27816Y1514255D01*
Y1512525D01*
X27326Y1512035D01*
Y1510305D01*
X27816Y1509815D01*
Y1507329D01*
X27326Y1506839D01*
Y1505109D01*
X27816Y1504619D01*
Y1499305D01*
X29039Y1498082D01*
Y1497389D01*
X30263Y1496165D01*
X30956D01*
X32179Y1494942D01*
Y1494249D01*
X33403Y1493025D01*
X34096D01*
X35319Y1491802D01*
Y1491109D01*
X36543Y1489885D01*
X37236D01*
X38459Y1488662D01*
Y1487969D01*
X39683Y1486745D01*
X40376D01*
X41599Y1485522D01*
Y1484829D01*
X42823Y1483605D01*
X43516D01*
X44739Y1482382D01*
Y1481689D01*
X45963Y1480465D01*
X46656D01*
X47879Y1479242D01*
Y1478549D01*
X49103Y1477325D01*
X49796D01*
X53623Y1473498D01*
Y1470609D01*
X53133Y1470119D01*
Y1468389D01*
X53623Y1467899D01*
Y1464111D01*
X50439Y1460927D01*
X47769D01*
X47279Y1461417D01*
X45549D01*
X45059Y1460927D01*
X39827D01*
X38065Y1462689D01*
Y1463685D01*
X39225Y1464845D01*
G01X148692Y394401D02*
X147547Y393256D01*
X142969D01*
X141209Y393984D01*
X140966Y394573D01*
X139209Y395300D01*
X138621Y395056D01*
X133608Y397132D01*
X131380Y399360D01*
Y399996D01*
X130036Y401340D01*
X129400D01*
X128057Y402683D01*
Y403319D01*
X126712Y404664D01*
X126076D01*
X124733Y406007D01*
Y406643D01*
X123388Y407988D01*
X122752D01*
X121409Y409331D01*
Y409967D01*
X120064Y411312D01*
X119428D01*
X118085Y412655D01*
Y413291D01*
X116740Y414636D01*
X116104D01*
X111922Y418818D01*
X109403Y424900D01*
X109647Y425488D01*
X108901Y427290D01*
X108312Y427534D01*
X107566Y429335D01*
X107810Y429923D01*
X107064Y431726D01*
X106475Y431969D01*
X103891Y438208D01*
X80658Y514790D01*
Y547590D01*
X90885Y572280D01*
X93684Y629296D01*
X95877Y640321D01*
X233527Y1046998D01*
Y1068787D01*
G01X148692Y391001D02*
X147547Y392146D01*
X142743D01*
X132979Y396191D01*
X110981Y418189D01*
X102844Y437833D01*
X79548Y514625D01*
Y547811D01*
X89785Y572527D01*
X92579Y629432D01*
X94802Y640608D01*
X232417Y1047181D01*
Y1068787D01*
G01X140690Y398113D02*
X139545Y399258D01*
X137562D01*
X134745Y400425D01*
X114590Y420580D01*
Y420700D01*
X104826Y444270D01*
X83358Y515040D01*
Y546772D01*
X93543Y571364D01*
X96359Y628652D01*
X98612Y639981D01*
X236157Y1046343D01*
Y1069000D01*
G01X237267D02*
Y1046160D01*
X99687Y639694D01*
X97464Y628516D01*
X94643Y571117D01*
X84468Y546551D01*
Y515205D01*
X105873Y444645D01*
X107761Y440087D01*
X108283Y439870D01*
X109031Y438068D01*
X108814Y437545D01*
X109560Y435744D01*
X110082Y435527D01*
X110830Y433725D01*
X110613Y433202D01*
X111359Y431401D01*
X111881Y431184D01*
X112629Y429382D01*
X112412Y428859D01*
X113158Y427058D01*
Y427057D01*
X113681Y426841D01*
X114428Y425038D01*
X114211Y424516D01*
X115616Y421124D01*
X118416Y418324D01*
X118982D01*
X120362Y416944D01*
Y416378D01*
X121740Y415000D01*
X122306D01*
X123686Y413620D01*
Y413054D01*
X125064Y411676D01*
X125630D01*
X127010Y410296D01*
Y409730D01*
X128388Y408352D01*
X128882D01*
X130227Y407008D01*
Y406513D01*
X131570Y405170D01*
X132065D01*
X133410Y403825D01*
Y403330D01*
X135374Y401366D01*
X137783Y400368D01*
X139545D01*
X140690Y401513D01*
G01X148692Y405174D02*
X147547Y406319D01*
X140357D01*
X135914Y408159D01*
X135915D01*
X132154Y409717D01*
X117933Y423938D01*
X106816Y450778D01*
X87168Y515547D01*
Y546038D01*
X97309Y570522D01*
X99420Y613445D01*
X100126Y627807D01*
X102423Y639355D01*
X239897Y1045504D01*
Y1068787D01*
G01X138290Y412287D02*
X137145Y413432D01*
X134538D01*
X121883Y426087D01*
X121881D01*
X108300Y458882D01*
X90978Y515982D01*
Y545170D01*
X101066Y569524D01*
X102472Y598173D01*
Y598172D01*
X103174Y612461D01*
X103879Y626823D01*
X106267Y638828D01*
X243637Y1044666D01*
Y1069000D01*
G01X138290Y415687D02*
X137145Y414542D01*
X134998D01*
X133620Y415920D01*
Y416557D01*
X132240Y417937D01*
X131603D01*
X130225Y419315D01*
Y419952D01*
X128845Y421332D01*
X128208D01*
X126830Y422710D01*
Y423276D01*
X125450Y424656D01*
X124884D01*
X122824Y426716D01*
X122823D01*
X121437Y430062D01*
X121681Y430650D01*
X120935Y432453D01*
X120346Y432696D01*
X119600Y434497D01*
X119844Y435085D01*
X119098Y436888D01*
X118509Y437131D01*
X118510D01*
X117764Y438932D01*
X117763D01*
X118007Y439520D01*
X117261Y441323D01*
X116672Y441566D01*
X116673D01*
X115927Y443367D01*
X116171Y443955D01*
X115425Y445758D01*
X114836Y446001D01*
X114090Y447802D01*
X114334Y448390D01*
X113588Y450193D01*
X112999Y450436D01*
X113000D01*
X109347Y459257D01*
X92088Y516147D01*
Y544949D01*
X102166Y569277D01*
X104984Y626687D01*
X107342Y638541D01*
X244747Y1044483D01*
Y1069000D01*
G01X241007Y1068787D02*
Y1045321D01*
X103498Y639068D01*
X101231Y627671D01*
X98409Y570275D01*
X88278Y545817D01*
Y515712D01*
X107863Y451153D01*
X112736Y439386D01*
X113325Y439143D01*
X114071Y437340D01*
X113827Y436752D01*
X114573Y434951D01*
X115162Y434708D01*
X115908Y432905D01*
X115664Y432317D01*
X116410Y430516D01*
X116999Y430272D01*
X117745Y428470D01*
X117501Y427882D01*
X118874Y424567D01*
X122811Y420630D01*
X123447D01*
X124792Y419285D01*
Y418649D01*
X126135Y417306D01*
X126771D01*
X128116Y415961D01*
Y415325D01*
X129459Y413982D01*
X130095D01*
X131440Y412637D01*
Y412001D01*
X132783Y410658D01*
X135915Y409361D01*
X136503Y409604D01*
X138259Y408877D01*
X138503Y408288D01*
Y408290D01*
X140578Y407429D01*
X142151D01*
X142601Y407879D01*
X144501D01*
X144951Y407429D01*
X147547D01*
X148692Y408574D01*
G01Y419347D02*
X147547Y420492D01*
X140018D01*
X131585Y423985D01*
X124308Y431262D01*
X110531Y464523D01*
X94788Y516427D01*
Y544307D01*
X104955Y568853D01*
X107807Y626857D01*
X110043Y638099D01*
X247378Y1043830D01*
Y1068787D01*
G01X248488D02*
Y1043647D01*
X111118Y637812D01*
X108912Y626721D01*
X106055Y568606D01*
X95898Y544086D01*
Y516592D01*
X111578Y464898D01*
X113764Y459619D01*
X114353Y459375D01*
X115080Y457619D01*
X114836Y457031D01*
X115924Y454404D01*
X116513Y454160D01*
X117240Y452404D01*
X116996Y451816D01*
X117723Y450061D01*
X118312Y449817D01*
X119039Y448061D01*
X118795Y447473D01*
X119522Y445718D01*
X120110Y445475D01*
X120838Y443719D01*
X120594Y443131D01*
X121332Y441348D01*
X121921Y441104D01*
X122648Y439348D01*
X122404Y438760D01*
X123131Y437005D01*
X123720Y436761D01*
X124447Y435005D01*
X124203Y434417D01*
X125249Y431891D01*
X128890Y428250D01*
X129526D01*
X130871Y426905D01*
Y426269D01*
X132214Y424926D01*
X140239Y421602D01*
X142140D01*
X142590Y422052D01*
X144490D01*
X144940Y421602D01*
X147547D01*
X148692Y422747D01*
G01X138290Y426460D02*
X137145Y427605D01*
X134064D01*
X127832Y433837D01*
X112676Y470424D01*
X98598Y516838D01*
Y543414D01*
X108711Y567830D01*
X110852Y611407D01*
X111569Y625988D01*
X113853Y637471D01*
X251118Y1042992D01*
Y1069000D01*
G01X252228D02*
Y1060475D01*
X252628Y1060075D01*
Y1058125D01*
X252228Y1057725D01*
Y1042809D01*
X114928Y637184D01*
X112674Y625852D01*
X109811Y567583D01*
X99708Y543193D01*
Y517003D01*
X113723Y470799D01*
X116180Y464867D01*
X116702Y464650D01*
X117450Y462848D01*
X117233Y462325D01*
X117979Y460524D01*
X118501Y460307D01*
X119249Y458505D01*
X119032Y457982D01*
X119778Y456181D01*
X120300Y455964D01*
X121048Y454162D01*
X120831Y453639D01*
X121577Y451838D01*
X122099Y451621D01*
X122847Y449819D01*
X122630Y449296D01*
X123376Y447495D01*
X123898Y447278D01*
X124646Y445476D01*
X124429Y444953D01*
X125175Y443152D01*
X125697Y442935D01*
X126445Y441133D01*
X126228Y440610D01*
X126974Y438809D01*
X127496Y438592D01*
X128244Y436790D01*
X128027Y436267D01*
X128773Y434466D01*
X131370Y431869D01*
X131836D01*
X133181Y430525D01*
Y430058D01*
X134524Y428715D01*
X137145D01*
X138290Y429860D01*
G01X254858Y1068787D02*
Y1042154D01*
X117661Y636841D01*
X115407Y625508D01*
X114686Y610837D01*
X112534Y566991D01*
X102408Y542546D01*
Y517525D01*
X115117Y475633D01*
X130302Y438968D01*
X131489Y437781D01*
X134886Y436373D01*
X134887D01*
X139008Y434666D01*
X147547D01*
X148692Y433521D01*
G01X255968Y1068787D02*
Y1041971D01*
X118736Y636554D01*
X116512Y625372D01*
X115079Y596195D01*
Y596194D01*
X113634Y566744D01*
X103518Y542325D01*
Y517690D01*
X116164Y476008D01*
X120450Y465659D01*
Y465657D01*
X121039Y465413D01*
X121766Y463657D01*
X121523Y463069D01*
X122249Y461314D01*
X122838Y461070D01*
X123565Y459314D01*
X123321Y458726D01*
X124048Y456971D01*
X124047D01*
X124636Y456727D01*
X125363Y454971D01*
X125120Y454383D01*
X125846Y452628D01*
X126435Y452384D01*
X127162Y450628D01*
X126919Y450040D01*
X127645Y448285D01*
Y448284D01*
X128234Y448040D01*
X128961Y446284D01*
X128718Y445696D01*
X129444Y443941D01*
Y443940D01*
X130033Y443696D01*
X130760Y441940D01*
X130517Y441352D01*
X131243Y439597D01*
X132118Y438722D01*
X134886Y437575D01*
X135474Y437819D01*
X137231Y437092D01*
X137474Y436503D01*
X139229Y435776D01*
X142440D01*
X142890Y436226D01*
X144790D01*
X145240Y435776D01*
X147547D01*
X148692Y436921D01*
G01X258598Y1069000D02*
Y1041317D01*
X121473Y636215D01*
X119173Y624651D01*
X117736Y595413D01*
Y595414D01*
X116300Y566178D01*
X106218Y541838D01*
Y518152D01*
X117341Y481484D01*
X133362Y442807D01*
X134391Y441778D01*
X137145D01*
X138290Y440633D01*
G01Y444033D02*
X137145Y442888D01*
X134851D01*
X134303Y443436D01*
X133321Y445807D01*
X133565Y446395D01*
X132819Y448198D01*
X132230Y448441D01*
X131484Y450242D01*
X131728Y450830D01*
X130982Y452633D01*
X130393Y452876D01*
X129647Y454677D01*
X129891Y455265D01*
X129145Y457068D01*
X128556Y457311D01*
X127810Y459112D01*
X128054Y459700D01*
X127308Y461503D01*
X126719Y461746D01*
X125973Y463547D01*
X126217Y464135D01*
X125471Y465938D01*
X124882Y466181D01*
X124136Y467982D01*
X124380Y468570D01*
X123634Y470373D01*
X123045Y470616D01*
X122299Y472417D01*
X122543Y473005D01*
X121797Y474808D01*
X121208Y475051D01*
X120462Y476852D01*
X120706Y477440D01*
X119960Y479243D01*
X119371Y479486D01*
X118388Y481859D01*
X107328Y518317D01*
Y541617D01*
X117400Y565931D01*
X120278Y624515D01*
X122548Y635928D01*
X259708Y1041134D01*
Y1069000D01*
G01X262338Y1068787D02*
Y1040479D01*
X125283Y635587D01*
X122975Y623985D01*
X120097Y565461D01*
X110028Y541152D01*
Y519159D01*
X127335Y477377D01*
X134180Y470532D01*
X137145D01*
X138290Y469387D01*
G01X263448Y1068787D02*
Y1040296D01*
X126358Y635300D01*
X124080Y623849D01*
X122645Y594668D01*
X121197Y565214D01*
X111138Y540931D01*
Y519380D01*
X113885Y512749D01*
X114408Y512533D01*
X115136Y510776D01*
X114919Y510254D01*
X115736Y508281D01*
X115735D01*
X116259Y508065D01*
X116986Y506308D01*
X116769Y505786D01*
X117496Y504031D01*
Y504030D01*
X118020Y503814D01*
X118747Y502057D01*
X118530Y501535D01*
X119257Y499780D01*
Y499779D01*
X119781Y499563D01*
X120508Y497806D01*
X120291Y497284D01*
X121018Y495529D01*
X121017D01*
X121541Y495313D01*
X122268Y493556D01*
X122051Y493034D01*
X122778Y491279D01*
X123302Y491063D01*
X124029Y489306D01*
X123812Y488784D01*
X124539Y487029D01*
X124538D01*
X125062Y486813D01*
X125789Y485056D01*
X125572Y484534D01*
X126299Y482779D01*
X126822Y482563D01*
X127549Y480806D01*
X127333Y480284D01*
X128276Y478006D01*
X130421Y475861D01*
X131057D01*
X132401Y474517D01*
Y473881D01*
X134640Y471642D01*
X137145D01*
X138290Y472787D01*
G01X148692Y476499D02*
X147547Y477644D01*
X135186D01*
X129377Y483453D01*
X113838Y520968D01*
Y540359D01*
X123854Y564540D01*
X126727Y622993D01*
X129128Y635063D01*
X266078Y1039639D01*
Y1069000D01*
G01X267188D02*
Y1039456D01*
X130203Y634776D01*
X127832Y622857D01*
X124954Y564293D01*
X114948Y540138D01*
Y521189D01*
X117354Y515381D01*
Y515380D01*
X117811Y515191D01*
X118559Y513388D01*
X118369Y512931D01*
X119115Y511130D01*
X119114D01*
X119571Y510941D01*
X120319Y509138D01*
X120129Y508681D01*
X120875Y506880D01*
Y506879D01*
X121332Y506690D01*
X122080Y504887D01*
X121890Y504430D01*
X122636Y502629D01*
Y502628D01*
X123093Y502439D01*
X123841Y500636D01*
X123651Y500179D01*
X124397Y498378D01*
X124396D01*
X124853Y498189D01*
X125601Y496386D01*
X125411Y495929D01*
X126157Y494128D01*
Y494127D01*
X126614Y493938D01*
X127362Y492135D01*
X127172Y491678D01*
X127918Y489877D01*
Y489876D01*
X128375Y489687D01*
X129122Y487885D01*
X128933Y487427D01*
X130318Y484082D01*
X131777Y482623D01*
X132343D01*
X133723Y481243D01*
Y480677D01*
X135646Y478754D01*
X138290D01*
X138640Y479104D01*
X140240D01*
X140590Y478754D01*
X142190D01*
X142540Y479104D01*
X144140D01*
X144490Y478754D01*
X147547D01*
X148692Y479899D01*
G01X138290Y483560D02*
X137145Y484705D01*
X134180D01*
X132755Y486130D01*
X117648Y522603D01*
Y539438D01*
X127771Y563877D01*
X130650Y622383D01*
X133203Y635219D01*
X269819Y1038803D01*
Y1068787D01*
G01X138290Y486960D02*
X137145Y485815D01*
X134640D01*
X133696Y486759D01*
X132761Y489017D01*
X133005Y489605D01*
X132278Y491361D01*
X131689Y491605D01*
X130962Y493360D01*
X131206Y493948D01*
X130479Y495704D01*
X129890Y495948D01*
X129163Y497703D01*
X129407Y498291D01*
X128680Y500047D01*
X128091Y500291D01*
Y500292D01*
X127364Y502047D01*
X127608Y502635D01*
X126881Y504391D01*
X126292Y504635D01*
X125565Y506390D01*
X125809Y506978D01*
X125082Y508734D01*
X124493Y508978D01*
X123766Y510733D01*
X124010Y511321D01*
X123283Y513077D01*
X122694Y513321D01*
Y513322D01*
X121673Y515788D01*
X121917Y516376D01*
X121189Y518132D01*
X120600Y518375D01*
X120601D01*
X119680Y520599D01*
X119681D01*
X118758Y522824D01*
Y539217D01*
X128871Y563630D01*
X131755Y622247D01*
X132817Y627587D01*
X133288Y627902D01*
X133659Y629766D01*
X133344Y630236D01*
X134278Y634931D01*
X270929Y1038620D01*
Y1068787D01*
G01X273559Y1069000D02*
Y1037965D01*
X137865Y637107D01*
X134381Y619589D01*
X131607Y563204D01*
X121458Y538703D01*
Y527833D01*
X124730Y519932D01*
X140826Y495844D01*
X144852Y491818D01*
X147547D01*
X148692Y490673D01*
G01X278409Y1068787D02*
Y1036944D01*
X142714Y636088D01*
X141601Y630491D01*
X140489Y624895D01*
X140843Y624366D01*
X140472Y622502D01*
X139942Y622148D01*
X139943D01*
X139572Y620285D01*
X136613Y560121D01*
X135373Y557127D01*
X135616Y556539D01*
X134889Y554783D01*
X134300Y554539D01*
X133574Y552784D01*
X133817Y552196D01*
X133090Y550439D01*
X132502Y550196D01*
X131775Y548441D01*
X132019Y547853D01*
X131292Y546096D01*
X130703Y545853D01*
X129976Y544098D01*
X130220Y543510D01*
X129493Y541753D01*
X128904Y541510D01*
X128177Y539755D01*
X128421Y539167D01*
X127694Y537410D01*
X127105Y537167D01*
X126378Y535412D01*
Y528723D01*
X127338Y526406D01*
X129206Y523610D01*
X129830Y523485D01*
X130886Y521905D01*
X130762Y521280D01*
X131817Y519701D01*
X132441Y519577D01*
X133498Y517996D01*
X133374Y517372D01*
X134193Y516146D01*
X134885Y515776D01*
X137145D01*
X138290Y516921D01*
G01X277299Y1068787D02*
Y1037127D01*
X141639Y636375D01*
X138467Y620421D01*
X135513Y560368D01*
X125268Y535633D01*
Y528502D01*
X126354Y525880D01*
X129261Y521527D01*
X129262D01*
X132450Y516755D01*
X132451D01*
X133424Y515298D01*
X134606Y514666D01*
X137145D01*
X138290Y513521D01*
G01X148692Y494073D02*
X147547Y492928D01*
X145312D01*
X141688Y496552D01*
X138898Y500728D01*
X138994Y501214D01*
X138049Y502628D01*
X137563Y502725D01*
X136509Y504303D01*
X136606Y504788D01*
X135660Y506203D01*
X135175Y506299D01*
X134092Y507920D01*
X134216Y508544D01*
X133132Y510166D01*
X132508Y510291D01*
X131425Y511912D01*
X131549Y512536D01*
X130465Y514158D01*
X129841Y514282D01*
X128758Y515903D01*
X128882Y516527D01*
X127798Y518149D01*
X127174Y518273D01*
X125714Y520458D01*
X122568Y528054D01*
Y538482D01*
X123976Y541881D01*
X124565Y542125D01*
X125311Y543927D01*
X125068Y544515D01*
X125814Y546316D01*
X126403Y546560D01*
X127149Y548362D01*
X126905Y548950D01*
X127651Y550751D01*
X128240Y550995D01*
X128986Y552797D01*
X128742Y553385D01*
X129488Y555186D01*
X129945Y555375D01*
X130692Y557178D01*
X130503Y557635D01*
X132707Y562957D01*
X134103Y591341D01*
X135486Y619453D01*
X138940Y636820D01*
X274669Y1037782D01*
Y1069000D01*
G01X282149D02*
Y1036106D01*
X147593Y638615D01*
X143249Y616779D01*
X141727Y585821D01*
X142155Y585349D01*
X142059Y583401D01*
X141586Y582973D01*
X141491Y581026D01*
X141919Y580554D01*
X141823Y578606D01*
X141350Y578178D01*
X141255Y576231D01*
X141683Y575759D01*
X141587Y573810D01*
X141114Y573383D01*
X141019Y571436D01*
X141447Y570965D01*
X141351Y569016D01*
X140878Y568589D01*
X140778Y566538D01*
X141206Y566067D01*
X141110Y564118D01*
X140637Y563691D01*
X140359Y558026D01*
X137864Y552002D01*
X138107Y551414D01*
X137361Y549612D01*
X136772Y549368D01*
X136026Y547567D01*
X136269Y546979D01*
X135523Y545176D01*
X134934Y544933D01*
X130140Y533361D01*
Y530707D01*
X131015Y528595D01*
X135157Y524453D01*
X138935Y522888D01*
X141140D01*
X141590Y523338D01*
X143490D01*
X143940Y522888D01*
X147547D01*
X148692Y524033D01*
G01X281039Y1069000D02*
Y1036289D01*
X146518Y638902D01*
X142144Y616915D01*
X139259Y558273D01*
X129030Y533582D01*
Y530486D01*
X130074Y527966D01*
X134528Y523512D01*
X138714Y521778D01*
X147547D01*
X148692Y520633D01*
G01X284779Y1068787D02*
Y1035407D01*
X178538Y721559D01*
X144697Y551223D01*
X143307Y547867D01*
X136118Y540678D01*
X132840Y532768D01*
Y531324D01*
X133325Y530154D01*
X134640Y528839D01*
X137145D01*
X138290Y527694D01*
G01Y531094D02*
X137145Y529949D01*
X135100D01*
X134266Y530783D01*
X133950Y531545D01*
Y532547D01*
X134677Y534299D01*
Y534300D01*
X135266Y534543D01*
X135993Y536300D01*
X135749Y536888D01*
X137059Y540049D01*
X138402Y541392D01*
X139038D01*
X140383Y542737D01*
Y543373D01*
X144248Y547238D01*
X145765Y550899D01*
X146144Y552811D01*
X146675Y553165D01*
X147055Y555078D01*
X146701Y555607D01*
X147080Y557519D01*
X147611Y557873D01*
X147991Y559786D01*
X147637Y560315D01*
X148016Y562227D01*
X148547Y562581D01*
X148926Y564494D01*
X148573Y565023D01*
X148952Y566935D01*
X149483Y567289D01*
X149862Y569202D01*
X149509Y569731D01*
X149888Y571643D01*
X150419Y571997D01*
X150798Y573910D01*
X150445Y574440D01*
X150824Y576352D01*
X151354Y576706D01*
X151734Y578619D01*
X151381Y579149D01*
X179613Y721272D01*
X285889Y1035224D01*
Y1068787D01*
G01X289629Y1069000D02*
Y1033717D01*
X186604Y729372D01*
X158116Y585917D01*
X158470Y585388D01*
X158090Y583474D01*
X157560Y583120D01*
X157181Y581208D01*
X157495Y580738D01*
X157116Y578825D01*
X156644Y578510D01*
X156265Y576598D01*
X156579Y576128D01*
X156200Y574215D01*
X155728Y573900D01*
X155349Y571988D01*
X155663Y571518D01*
X155284Y569605D01*
X154812Y569290D01*
X154433Y567378D01*
X154747Y566908D01*
X154368Y564995D01*
X153896Y564680D01*
X153517Y562768D01*
X153831Y562298D01*
X153452Y560385D01*
X152980Y560070D01*
X152601Y558158D01*
X152915Y557688D01*
X152536Y555775D01*
X152064Y555460D01*
X151685Y553548D01*
X151999Y553078D01*
X151629Y551213D01*
X151158Y550899D01*
X150751Y548848D01*
X148956Y544516D01*
X147613Y543173D01*
Y542607D01*
X146268Y541263D01*
X145703D01*
X144250Y539810D01*
Y537959D01*
X145148Y537061D01*
X147547D01*
X148692Y538206D01*
G01X288519Y1069000D02*
Y1033900D01*
X185529Y729659D01*
X149683Y549172D01*
X148015Y545145D01*
X143140Y540270D01*
Y537499D01*
X144688Y535951D01*
X147547D01*
X148692Y534806D01*
G01X300433Y1473977D02*
Y1475481D01*
X300933Y1475981D01*
X302473D01*
X303946Y1474508D01*
Y1454829D01*
X301891Y1449868D01*
X288039Y1440612D01*
X287414Y1440736D01*
X285792Y1439652D01*
X285668Y1439028D01*
X284047Y1437945D01*
X283423Y1438069D01*
X281801Y1436985D01*
X281677Y1436361D01*
X280056Y1435278D01*
X279432Y1435402D01*
X277810Y1434318D01*
X277685Y1433694D01*
X263012Y1423889D01*
X250873Y1418861D01*
X246577Y1414565D01*
X237976Y1393802D01*
X231695Y1362225D01*
X206236Y1278297D01*
Y1259424D01*
G01X317756Y1473977D02*
Y1475481D01*
X318256Y1475981D01*
X319796D01*
X321269Y1474508D01*
Y1454019D01*
X320153Y1451324D01*
X317584Y1448755D01*
X297384Y1435258D01*
X296761Y1435383D01*
X295138Y1434298D01*
X295014Y1433674D01*
X293393Y1432591D01*
X292769Y1432715D01*
X291147Y1431631D01*
X291022Y1431007D01*
X289401Y1429924D01*
X288777Y1430048D01*
X287155Y1428964D01*
X287030Y1428340D01*
X271288Y1417821D01*
X264566Y1415036D01*
X262654Y1413124D01*
X261128Y1409440D01*
Y1343416D01*
X239727Y1311387D01*
X217079Y1283790D01*
X213716Y1275671D01*
Y1259424D01*
G01X291771Y1478308D02*
Y1479812D01*
X292271Y1480312D01*
X294019D01*
X295285Y1479046D01*
Y1454340D01*
X293575Y1450213D01*
X284637Y1444241D01*
X284012Y1444365D01*
X282390Y1443280D01*
X282266Y1442656D01*
X256631Y1425527D01*
X249103Y1422409D01*
X243305Y1416611D01*
X234394Y1395100D01*
X228245Y1364189D01*
X202496Y1279308D01*
Y1259624D01*
G01X300433Y1479095D02*
Y1477591D01*
X300933Y1477091D01*
X302933D01*
X305056Y1474968D01*
Y1454608D01*
X302788Y1449132D01*
X263538Y1422905D01*
X251502Y1417920D01*
X247518Y1413936D01*
X239044Y1393478D01*
X232774Y1361955D01*
X207346Y1278132D01*
Y1259424D01*
G01X211086D02*
Y1277055D01*
X214370Y1284983D01*
X246378Y1332885D01*
X249998Y1344820D01*
Y1409288D01*
X251278Y1412378D01*
X253029Y1414129D01*
X270483Y1421359D01*
X308985Y1447085D01*
X312505Y1450605D01*
X313718Y1453533D01*
Y1479506D01*
X311802Y1481422D01*
X309594D01*
X309094Y1481922D01*
Y1483426D01*
G01X283110Y1473977D02*
Y1475481D01*
X283610Y1475981D01*
X285150D01*
X286623Y1474508D01*
Y1454032D01*
X285131Y1450431D01*
X277624Y1445415D01*
X276999Y1445539D01*
X275377Y1444455D01*
X275253Y1443830D01*
X273632Y1442747D01*
X273008Y1442871D01*
X271386Y1441787D01*
X271261Y1441163D01*
X269640Y1440080D01*
X269016Y1440204D01*
X267394Y1439120D01*
X267269Y1438496D01*
X251223Y1427774D01*
X247683Y1426307D01*
X239842Y1418466D01*
X230586Y1396121D01*
X224403Y1365035D01*
X198756Y1280486D01*
Y1259812D01*
G01X309094Y1478308D02*
Y1479812D01*
X309594Y1480312D01*
X311342D01*
X312608Y1479046D01*
Y1453754D01*
X311564Y1451234D01*
X308277Y1447947D01*
X293394Y1438003D01*
X292770Y1438127D01*
X291148Y1437043D01*
X291024Y1436419D01*
X269957Y1422343D01*
X252400Y1415070D01*
X250337Y1413007D01*
X248888Y1409509D01*
Y1344985D01*
X245363Y1333365D01*
X213386Y1285509D01*
X209976Y1277276D01*
Y1259424D01*
G01X283110Y1479095D02*
Y1477591D01*
X283610Y1477091D01*
X285610D01*
X287733Y1474968D01*
Y1453811D01*
X286028Y1449695D01*
X251749Y1426790D01*
X248312Y1425366D01*
X240783Y1417837D01*
X231654Y1395797D01*
X225482Y1364765D01*
X199866Y1280321D01*
Y1259812D01*
G01X291771Y1483426D02*
Y1481922D01*
X292271Y1481422D01*
X294479D01*
X296395Y1479506D01*
Y1454119D01*
X294472Y1449477D01*
X257157Y1424543D01*
X249732Y1421468D01*
X244246Y1415982D01*
X235462Y1394776D01*
X229324Y1363919D01*
X203606Y1279143D01*
Y1259624D01*
G01X283110Y1560985D02*
Y1562489D01*
X283610Y1562989D01*
X285142D01*
X286790Y1561341D01*
Y1552940D01*
X290828Y1548902D01*
Y1548407D01*
X292207Y1547028D01*
X292702D01*
X294080Y1545650D01*
Y1545155D01*
X295460Y1543775D01*
X295955D01*
X307080Y1532650D01*
X362353Y1521656D01*
X363273Y1520736D01*
X363672Y1519772D01*
Y1517383D01*
X364935Y1460668D01*
X363126Y1451570D01*
X362168Y1449255D01*
X320939Y1421707D01*
X316465Y1418036D01*
X310088Y1411658D01*
Y1346989D01*
X307733Y1341303D01*
X277418Y1310988D01*
X250873Y1293251D01*
X232098Y1274476D01*
X228677Y1266217D01*
Y1259624D01*
G01X283110Y1566103D02*
Y1564599D01*
X283610Y1564099D01*
X285602D01*
X287900Y1561801D01*
Y1553400D01*
X307627Y1533673D01*
X362901Y1522680D01*
X364215Y1521364D01*
X364782Y1519993D01*
Y1517396D01*
X366048Y1460571D01*
X364194Y1451246D01*
X363065Y1448519D01*
X321601Y1420814D01*
X317212Y1417212D01*
X311198Y1411198D01*
Y1346768D01*
X308674Y1340674D01*
X278126Y1310126D01*
X251581Y1292389D01*
X233039Y1273847D01*
X229787Y1265996D01*
Y1259624D01*
G01X335078Y1473977D02*
Y1475481D01*
X335578Y1475981D01*
X337118D01*
X338591Y1474508D01*
Y1452700D01*
X336433Y1447492D01*
X312927Y1431785D01*
X312302Y1431909D01*
X310680Y1430825D01*
X310556Y1430201D01*
X308935Y1429118D01*
X308311Y1429242D01*
X306689Y1428158D01*
X306564Y1427534D01*
X304943Y1426451D01*
X304319Y1426575D01*
X302697Y1425491D01*
X302573Y1424867D01*
X291493Y1417463D01*
X287337Y1413307D01*
X285608Y1409132D01*
Y1346686D01*
X281784Y1337454D01*
X224009Y1279679D01*
X221177Y1272844D01*
X221197Y1272824D01*
Y1259824D01*
G01X214826Y1259424D02*
Y1275450D01*
X218042Y1283213D01*
X240620Y1310725D01*
X262238Y1343079D01*
Y1409219D01*
X263595Y1412495D01*
X265195Y1414095D01*
X271814Y1416837D01*
X318292Y1447893D01*
X321094Y1450695D01*
X322379Y1453798D01*
Y1474968D01*
X320256Y1477091D01*
X318256D01*
X317756Y1477591D01*
Y1479095D01*
G01X335078D02*
Y1477691D01*
X335678Y1477091D01*
X337578D01*
X339701Y1474968D01*
Y1452479D01*
X337330Y1446756D01*
X292201Y1416601D01*
X288278Y1412678D01*
X286718Y1408911D01*
Y1346465D01*
X282725Y1336825D01*
X224950Y1279050D01*
X222287Y1272623D01*
X222307Y1272603D01*
Y1259824D01*
G01X326417Y1478308D02*
Y1479812D01*
X326917Y1480312D01*
X328665D01*
X329930Y1479047D01*
Y1455089D01*
X327334Y1448824D01*
X302350Y1432130D01*
X301726Y1432254D01*
X300104Y1431170D01*
X299980Y1430546D01*
X299979D01*
X277667Y1415637D01*
X274695Y1412665D01*
X273368Y1409461D01*
Y1346041D01*
X272771Y1344077D01*
X263007Y1329463D01*
X255221Y1319975D01*
X220338Y1281488D01*
X217456Y1274532D01*
Y1259424D01*
G01X326417Y1483426D02*
Y1481922D01*
X326917Y1481422D01*
X329125D01*
X331040Y1479507D01*
Y1454868D01*
X328231Y1448088D01*
X278375Y1414775D01*
X275636Y1412036D01*
X274478Y1409240D01*
Y1345876D01*
X273786Y1343596D01*
X263900Y1328801D01*
X256062Y1319250D01*
X221290Y1280885D01*
X218566Y1274311D01*
Y1259424D01*
G01X343740Y1483426D02*
Y1481922D01*
X344240Y1481422D01*
X346448D01*
X348364Y1479506D01*
Y1450752D01*
X346009Y1445066D01*
X305402Y1417932D01*
X298958Y1411488D01*
Y1344589D01*
X297027Y1339927D01*
X268828Y1311728D01*
X252282Y1300672D01*
X228054Y1276444D01*
X226047Y1271599D01*
Y1259624D01*
G01X343740Y1478308D02*
Y1479812D01*
X344240Y1480312D01*
X345988D01*
X347254Y1479046D01*
Y1450973D01*
X345112Y1445802D01*
X324898Y1432295D01*
X324273Y1432419D01*
X322651Y1431334D01*
X322527Y1430710D01*
X322526D01*
X304694Y1418794D01*
X297848Y1411948D01*
Y1344810D01*
X296086Y1340556D01*
X268120Y1312590D01*
X251574Y1301534D01*
X227113Y1277073D01*
X224937Y1271820D01*
Y1259624D01*
G01X300433Y1566103D02*
Y1564599D01*
X300933Y1564099D01*
X302925D01*
X305223Y1561801D01*
Y1553447D01*
X319735Y1538935D01*
X365099Y1529913D01*
X367159Y1529059D01*
X370659Y1525559D01*
X372479Y1521165D01*
Y1517481D01*
X373710Y1462309D01*
Y1460537D01*
X371303Y1448429D01*
X369669Y1444487D01*
X335678Y1410496D01*
Y1347220D01*
X333881Y1342881D01*
X314274Y1323274D01*
X250467Y1280639D01*
X240137Y1270309D01*
X237267Y1263381D01*
Y1259624D01*
G01X317756Y1560985D02*
Y1562489D01*
X318256Y1562989D01*
X319788D01*
X321436Y1561341D01*
Y1553464D01*
X323908Y1550992D01*
Y1550568D01*
X325288Y1549188D01*
X325712D01*
X327090Y1547810D01*
Y1547385D01*
X328470Y1546006D01*
X328894D01*
X331830Y1543070D01*
X366960Y1536082D01*
X370791Y1534495D01*
X376467Y1528819D01*
X378930Y1522872D01*
Y1517558D01*
X380200Y1460738D01*
Y1459646D01*
X376605Y1441570D01*
X373979Y1432912D01*
X359969Y1411945D01*
X359048Y1408908D01*
Y1345845D01*
X355040Y1338348D01*
X268431Y1280477D01*
X252963Y1274069D01*
X245775Y1266881D01*
X243637Y1261720D01*
Y1259824D01*
G01X309094Y1565315D02*
Y1566819D01*
X309594Y1567319D01*
X310933D01*
X312608Y1565644D01*
Y1553922D01*
X315528Y1551002D01*
Y1550578D01*
X316908Y1549198D01*
X317332D01*
X318710Y1547820D01*
Y1547395D01*
X320090Y1546016D01*
X320514D01*
X326168Y1540362D01*
X365868Y1532463D01*
X368659Y1531308D01*
X373122Y1526845D01*
X375130Y1521995D01*
Y1517511D01*
X376400Y1460625D01*
Y1460472D01*
X374734Y1452095D01*
X373863Y1447077D01*
X372207Y1442451D01*
X348035Y1412998D01*
X346808Y1409566D01*
Y1346813D01*
X345440Y1343510D01*
X336509Y1334579D01*
X251058Y1277482D01*
X242569Y1268993D01*
X239897Y1262546D01*
Y1259424D01*
G01X291771Y1565315D02*
Y1566819D01*
X292271Y1567319D01*
X293610D01*
X295285Y1565644D01*
Y1553915D01*
X300258Y1548942D01*
Y1548518D01*
X301638Y1547138D01*
X302062D01*
X303440Y1545760D01*
Y1545335D01*
X304820Y1543956D01*
X305244D01*
X314113Y1535087D01*
X363678Y1525228D01*
X364400Y1524929D01*
X366461Y1522868D01*
X367468Y1520437D01*
Y1517426D01*
X368700Y1462189D01*
Y1460314D01*
X366635Y1449932D01*
X365512Y1447218D01*
X361285Y1442991D01*
X353298Y1437654D01*
X328685Y1417456D01*
X323666Y1412436D01*
X322328Y1409206D01*
Y1346702D01*
X320981Y1343451D01*
X292071Y1314541D01*
X248101Y1285161D01*
X235533Y1272593D01*
X232417Y1265071D01*
Y1259624D01*
G01X317756Y1566103D02*
Y1564599D01*
X318256Y1564099D01*
X320248D01*
X322546Y1561801D01*
Y1553924D01*
X332377Y1544093D01*
X367284Y1537150D01*
X371420Y1535436D01*
X377408Y1529448D01*
X380040Y1523093D01*
Y1517571D01*
X381310Y1460751D01*
Y1459536D01*
X377684Y1441300D01*
X374994Y1432432D01*
X360984Y1411465D01*
X360158Y1408743D01*
Y1345566D01*
X355889Y1337579D01*
X268957Y1279493D01*
X253592Y1273128D01*
X246716Y1266252D01*
X244747Y1261499D01*
Y1259824D01*
G01X291771Y1570434D02*
Y1568929D01*
X292271Y1568429D01*
X294070D01*
X296395Y1566104D01*
Y1554375D01*
X314660Y1536110D01*
X364002Y1526296D01*
X365029Y1525870D01*
X367402Y1523497D01*
X368578Y1520658D01*
Y1517439D01*
X369810Y1462202D01*
Y1460204D01*
X367703Y1449608D01*
X366453Y1446589D01*
X361993Y1442129D01*
X353960Y1436761D01*
X329432Y1416632D01*
X324607Y1411807D01*
X323438Y1408985D01*
Y1346481D01*
X321922Y1342822D01*
X292779Y1313679D01*
X248809Y1284299D01*
X236474Y1271964D01*
X233527Y1264850D01*
Y1259624D01*
G01X300433Y1560985D02*
Y1562489D01*
X300933Y1562989D01*
X302465D01*
X304113Y1561341D01*
Y1552987D01*
X308143Y1548957D01*
Y1548533D01*
X309523Y1547153D01*
X309947D01*
X311325Y1545775D01*
Y1545350D01*
X312705Y1543971D01*
X313129D01*
X319188Y1537912D01*
X364775Y1528845D01*
X366530Y1528118D01*
X369718Y1524930D01*
X371369Y1520944D01*
Y1517468D01*
X372600Y1462296D01*
Y1460647D01*
X370235Y1448753D01*
X368728Y1445116D01*
X334568Y1410956D01*
Y1347441D01*
X332940Y1343510D01*
X313566Y1324136D01*
X249759Y1281501D01*
X239196Y1270938D01*
X236157Y1263602D01*
Y1259624D01*
G01X309094Y1570434D02*
Y1568929D01*
X309594Y1568429D01*
X311393D01*
X313718Y1566104D01*
Y1554382D01*
X326715Y1541385D01*
X366192Y1533531D01*
X369288Y1532249D01*
X374063Y1527474D01*
X376240Y1522216D01*
Y1517524D01*
X377510Y1460638D01*
Y1460362D01*
X375826Y1451892D01*
X374941Y1446793D01*
X373188Y1441895D01*
X349016Y1412442D01*
X347918Y1409373D01*
Y1346592D01*
X346381Y1342881D01*
X337217Y1333717D01*
X251766Y1276620D01*
X243510Y1268364D01*
X241007Y1262325D01*
Y1259424D01*
G01X247378Y1259812D02*
Y1260900D01*
X248978Y1264766D01*
X254530Y1270318D01*
X269644Y1276579D01*
X369512Y1343310D01*
X371721Y1346996D01*
X381583Y1447123D01*
X384000Y1455862D01*
Y1460821D01*
X382730Y1517601D01*
Y1523704D01*
X379781Y1530824D01*
X372921Y1537684D01*
X368052Y1539701D01*
X338776Y1545524D01*
X336294Y1548006D01*
X335870D01*
X334490Y1549385D01*
Y1549810D01*
X333112Y1551188D01*
X332688D01*
X331308Y1552567D01*
Y1552992D01*
X329930Y1554370D01*
Y1565645D01*
X328256Y1567319D01*
X326917D01*
X326417Y1566819D01*
Y1565315D01*
G01X256238Y1260808D02*
X256680Y1261250D01*
X262559Y1265178D01*
X281369Y1272969D01*
X373379Y1334449D01*
X376084Y1337154D01*
X379236Y1343818D01*
X388861Y1441546D01*
X391600Y1455320D01*
Y1460987D01*
X390330Y1517687D01*
Y1525315D01*
X386374Y1534868D01*
X376263Y1544979D01*
X371354Y1547012D01*
X370962Y1546849D01*
X369159Y1547596D01*
X368997Y1547988D01*
X367196Y1548734D01*
X359135Y1550336D01*
X358782Y1550101D01*
X356869Y1550481D01*
X356633Y1550835D01*
X354721Y1551215D01*
X354368Y1550979D01*
X352455Y1551359D01*
X352219Y1551713D01*
X350307Y1552093D01*
X347253Y1555147D01*
Y1565645D01*
X345579Y1567319D01*
X344240D01*
X343740Y1566819D01*
Y1565315D01*
G01X252228Y1259412D02*
Y1259908D01*
X253075Y1261755D01*
X254831Y1263268D01*
X260551Y1267511D01*
X275450Y1273684D01*
X372870Y1338779D01*
X376546Y1344912D01*
X385987Y1440785D01*
X388910Y1455487D01*
Y1460917D01*
X387640Y1517657D01*
Y1524645D01*
X383957Y1533537D01*
X375679Y1541815D01*
X365499Y1546031D01*
X345738Y1549962D01*
X339868Y1555832D01*
Y1561801D01*
X337570Y1564099D01*
X335578D01*
X335078Y1564599D01*
Y1566103D01*
G01X257023Y1260023D02*
X257388Y1260388D01*
X263085Y1264194D01*
X281895Y1271985D01*
X374087Y1333587D01*
X377005Y1336505D01*
X380323Y1343517D01*
X389961Y1441383D01*
X392710Y1455210D01*
Y1461000D01*
X391440Y1517700D01*
Y1525536D01*
X387315Y1535497D01*
X376892Y1545920D01*
X367520Y1549802D01*
X350854Y1553116D01*
X348363Y1555607D01*
Y1566105D01*
X346039Y1568429D01*
X344240D01*
X343740Y1568929D01*
Y1570434D01*
G01X248488Y1259812D02*
Y1260679D01*
X249919Y1264137D01*
X255159Y1269377D01*
X270170Y1275595D01*
X370337Y1342525D01*
X372802Y1346639D01*
X382679Y1446919D01*
X385110Y1455711D01*
Y1460834D01*
X383840Y1517614D01*
Y1523925D01*
X380722Y1531453D01*
X373550Y1538625D01*
X368376Y1540769D01*
X339323Y1546547D01*
X331040Y1554830D01*
Y1566105D01*
X328716Y1568429D01*
X326917D01*
X326417Y1568929D01*
Y1570434D01*
G01X251118Y1259412D02*
Y1260151D01*
X252167Y1262438D01*
X254136Y1264136D01*
X259999Y1268485D01*
X274924Y1274668D01*
X372046Y1339564D01*
X375465Y1345269D01*
X384887Y1440948D01*
X387800Y1455597D01*
Y1460904D01*
X386530Y1517644D01*
Y1524423D01*
X386529Y1524424D01*
X383016Y1532908D01*
X375050Y1540874D01*
X365175Y1544963D01*
X354019Y1547182D01*
X353666Y1546946D01*
X351753Y1547326D01*
X351517Y1547680D01*
X345191Y1548939D01*
X341940Y1552190D01*
X341516D01*
X340136Y1553569D01*
Y1553994D01*
X338758Y1555372D01*
Y1561341D01*
X337110Y1562989D01*
X335578D01*
X335078Y1562489D01*
Y1560985D01*
G01X331395Y614511D02*
X332540Y613366D01*
X334937D01*
X336123Y614552D01*
Y616125D01*
X334254Y619362D01*
X333776Y619491D01*
X332800Y621180D01*
X332928Y621658D01*
X331954Y623346D01*
X331475Y623474D01*
X330499Y625164D01*
X330628Y625642D01*
X302801Y673843D01*
X296823Y696149D01*
X296814Y696247D01*
X296815D01*
X281810Y867757D01*
X285291Y907543D01*
X295702Y1026550D01*
Y1052825D01*
X292260Y1061137D01*
Y1068787D01*
G01X331395Y611111D02*
X332540Y612256D01*
X335397D01*
X337233Y614092D01*
Y616423D01*
X303836Y674272D01*
X297921Y696343D01*
X282925Y867757D01*
X296812Y1026501D01*
Y1053046D01*
X293370Y1061358D01*
Y1068787D01*
G01X320993Y607399D02*
X322138Y606254D01*
X333940D01*
X338925Y611239D01*
X339926Y613656D01*
Y617166D01*
X307185Y673877D01*
X301247Y696041D01*
X301049Y698312D01*
X300560Y698721D01*
X300395Y700615D01*
X300804Y701103D01*
X300622Y703184D01*
X300134Y703593D01*
X299968Y705487D01*
X300377Y705974D01*
X300378Y705975D01*
X285936Y871062D01*
X299512Y1026297D01*
Y1053560D01*
X296000Y1062041D01*
Y1069000D01*
G01X320993Y603999D02*
X322138Y605144D01*
X334400D01*
X339866Y610610D01*
X341036Y613435D01*
Y617464D01*
X308220Y674305D01*
Y674306D01*
X302345Y696234D01*
X301606Y704681D01*
X301485Y706072D01*
X301484D01*
X287051Y871062D01*
X300622Y1026248D01*
Y1053781D01*
X298984Y1057737D01*
X299147Y1058129D01*
X298399Y1059932D01*
X298008Y1060094D01*
X297110Y1062262D01*
Y1069000D01*
G01X299740Y1068787D02*
Y1062945D01*
X303322Y1054295D01*
Y1026626D01*
X289754Y871505D01*
X305053Y696663D01*
X310781Y675288D01*
X343736Y618203D01*
Y612727D01*
X342212Y609047D01*
X341006Y607242D01*
X340451Y607132D01*
X339561Y605801D01*
X339672Y605246D01*
X338783Y603916D01*
X338784D01*
X338229Y603806D01*
X337339Y602475D01*
X337449Y601920D01*
X336561Y600590D01*
X335164Y599193D01*
X332540D01*
X331395Y600338D01*
G01X300850Y1068787D02*
Y1063166D01*
X304432Y1054516D01*
Y1026577D01*
X290869Y871505D01*
X306151Y696857D01*
X311816Y675717D01*
X344846Y618501D01*
Y612506D01*
X343196Y608521D01*
X337423Y599882D01*
X335624Y598083D01*
X332540D01*
X331395Y596938D01*
G01X303480Y1069000D02*
Y1064239D01*
X304226Y1062438D01*
X304063Y1062046D01*
X304810Y1060243D01*
X305202Y1060081D01*
X307132Y1055421D01*
Y1026889D01*
X293799Y874399D01*
X301368Y787890D01*
X308927Y701482D01*
X308518Y700995D01*
X308666Y699300D01*
X309154Y698891D01*
X309302Y697198D01*
X315052Y675744D01*
X347546Y619456D01*
Y611169D01*
X345603Y606476D01*
X339130Y596790D01*
X336444Y594104D01*
X331559Y592080D01*
X322138D01*
X320993Y593225D01*
G01Y589825D02*
X322138Y590970D01*
X331780D01*
X337073Y593163D01*
X339992Y596082D01*
X346587Y605950D01*
X348656Y610948D01*
Y619754D01*
X316087Y676173D01*
X310400Y697392D01*
X294914Y874399D01*
X308242Y1026840D01*
Y1055642D01*
X304590Y1064460D01*
Y1069000D01*
G01X331395Y491991D02*
X332540Y490846D01*
X334687D01*
X335525Y491684D01*
X336218Y493358D01*
X337242Y498509D01*
X337941Y500167D01*
X337728Y500691D01*
X338427Y502351D01*
X338952Y502564D01*
X338951D01*
X339650Y504222D01*
X339651D01*
X339438Y504746D01*
X340137Y506406D01*
X340662Y506619D01*
X340661D01*
X341360Y508277D01*
X341361D01*
X341148Y508801D01*
X341847Y510461D01*
X342372Y510674D01*
X342371Y510675D01*
X343070Y512333D01*
X342857Y512857D01*
X343556Y514517D01*
X344081Y514730D01*
X344780Y516388D01*
X344567Y516912D01*
X345266Y518572D01*
X345791Y518785D01*
X346910Y521440D01*
X348789Y523320D01*
X349498Y525034D01*
X349282Y525556D01*
X349971Y527220D01*
X350494Y527437D01*
X351182Y529099D01*
X350966Y529622D01*
X351655Y531286D01*
X352178Y531503D01*
X381836Y603105D01*
Y628136D01*
X381309Y630107D01*
X347222Y689173D01*
X343281Y703863D01*
X328520Y872552D01*
X338439Y986172D01*
X378932Y1046769D01*
X382384Y1055103D01*
X383845Y1071882D01*
X379162Y1083189D01*
X344932Y1117419D01*
X335341Y1121392D01*
X330290D01*
G01X331395Y521952D02*
X332540Y520807D01*
X334848D01*
X336771Y522730D01*
Y523295D01*
X338045Y524569D01*
X338610D01*
X341159Y527118D01*
X342456Y530251D01*
X342240Y530774D01*
X342929Y532438D01*
X343452Y532654D01*
X344140Y534316D01*
X343924Y534839D01*
X344613Y536503D01*
X345136Y536720D01*
X345824Y538382D01*
X345608Y538905D01*
X346297Y540569D01*
X346820Y540786D01*
X347508Y542448D01*
X347292Y542971D01*
X347981Y544635D01*
X348504Y544852D01*
X349192Y546514D01*
X348976Y547037D01*
X349665Y548701D01*
X350188Y548918D01*
X350876Y550580D01*
X350660Y551103D01*
X351349Y552767D01*
X351873Y552983D01*
X358933Y570027D01*
X360466Y571560D01*
X360465D01*
X374216Y604756D01*
Y626978D01*
X340214Y685894D01*
X335763Y702492D01*
X320877Y872648D01*
X331017Y988758D01*
X372337Y1050596D01*
X374993Y1057009D01*
X376191Y1070701D01*
X372781Y1078932D01*
X340669Y1111044D01*
X333746Y1113912D01*
X330290D01*
G01X331395Y477818D02*
X332540Y476673D01*
X334712D01*
X336482Y478443D01*
Y479009D01*
X337756Y480283D01*
X338322D01*
X339594Y481555D01*
X340282Y483217D01*
X340066Y483740D01*
X340755Y485404D01*
X341278Y485621D01*
X344220Y492725D01*
X344004Y493247D01*
X344693Y494911D01*
X345217Y495128D01*
X345216D01*
X345904Y496790D01*
X345688Y497313D01*
X346377Y498977D01*
X346901Y499193D01*
X346900D01*
X347588Y500855D01*
X347589D01*
X347373Y501378D01*
X348062Y503042D01*
X348585Y503259D01*
X349273Y504921D01*
X349057Y505444D01*
X349746Y507108D01*
X350269Y507325D01*
X350957Y508987D01*
X350741Y509510D01*
X351430Y511174D01*
X351954Y511390D01*
X351953D01*
X354515Y517574D01*
X355580Y518639D01*
X355579D01*
X389456Y600423D01*
Y629142D01*
X388427Y632993D01*
X354478Y691823D01*
X350892Y705187D01*
X336256Y872486D01*
X336264Y872582D01*
X336265D01*
X345916Y983177D01*
X384918Y1041544D01*
X387346Y1047405D01*
X389774Y1053265D01*
X391506Y1073044D01*
X385540Y1087449D01*
X349196Y1123793D01*
X336933Y1128873D01*
X330290D01*
G01X331395Y586165D02*
X332540Y585020D01*
X335248D01*
X336629Y586401D01*
Y586967D01*
X337973Y588311D01*
X338539D01*
X340844Y590616D01*
X342550Y593170D01*
X342440Y593725D01*
X343496Y595306D01*
X344051Y595416D01*
X347008Y599841D01*
X351340Y610298D01*
Y620818D01*
X318495Y677715D01*
X313094Y697852D01*
X305364Y786194D01*
X305365D01*
X297636Y874535D01*
X310942Y1026725D01*
Y1057444D01*
X307220Y1066431D01*
Y1068787D01*
G01X331395Y582765D02*
X332540Y583910D01*
X335708D01*
X341706Y589908D01*
X344718Y594415D01*
X344719Y594416D01*
X347992Y599315D01*
X352450Y610077D01*
Y621116D01*
X319530Y678144D01*
X314192Y698046D01*
X298751Y874535D01*
X312052Y1026676D01*
Y1057665D01*
X308330Y1066652D01*
Y1068787D01*
G01X320993Y579052D02*
X322138Y577907D01*
X330482D01*
X337723Y580906D01*
X342966Y586149D01*
X344049Y587770D01*
X343952Y588255D01*
X345037Y589878D01*
X345522Y589974D01*
X346605Y591595D01*
X346508Y592080D01*
X347592Y593703D01*
X348078Y593799D01*
X349516Y595952D01*
X355166Y609593D01*
Y621812D01*
X322094Y679103D01*
X316829Y698740D01*
X316820Y698838D01*
X316821D01*
X301444Y874406D01*
X314752Y1026635D01*
Y1058163D01*
X310960Y1067320D01*
Y1069000D01*
G01X320993Y575652D02*
X322138Y576797D01*
X330822D01*
X330906Y576881D01*
X338352Y579965D01*
X343889Y585502D01*
Y585532D01*
X350500Y595426D01*
X356276Y609372D01*
Y622110D01*
X323129Y679532D01*
X317927Y698934D01*
X302559Y874406D01*
X315862Y1026586D01*
Y1058384D01*
X312070Y1067541D01*
Y1069000D01*
G01X331395Y568591D02*
X332540Y569736D01*
X335326D01*
X343809Y578219D01*
X353486Y592701D01*
X360086Y608634D01*
Y623130D01*
X326687Y680991D01*
X321648Y699780D01*
X306439Y873440D01*
X319672Y1024861D01*
Y1059013D01*
X315811Y1068336D01*
Y1068787D01*
G01X331395Y571991D02*
X332540Y570846D01*
X334866D01*
X336774Y572754D01*
Y573292D01*
X338048Y574566D01*
X338586D01*
X339858Y575838D01*
Y576376D01*
X341132Y577649D01*
X341669D01*
X342947Y578927D01*
X352502Y593227D01*
X358976Y608855D01*
Y622832D01*
X325652Y680562D01*
X320550Y699586D01*
X305324Y873440D01*
X318562Y1024910D01*
Y1058792D01*
X314701Y1068115D01*
Y1068787D01*
G01X320993Y564879D02*
X322138Y563734D01*
X324009D01*
X326024Y562900D01*
X329082D01*
X330883Y563646D01*
X331072Y564103D01*
X332875Y564850D01*
X333332Y564661D01*
X335668Y565628D01*
X340025Y569985D01*
Y570480D01*
X341405Y571860D01*
X341900D01*
X343278Y573238D01*
Y573733D01*
X344658Y575113D01*
X345153D01*
X346733Y576693D01*
Y577188D01*
X348112Y578567D01*
X348607D01*
X349502Y579462D01*
X350585Y581083D01*
X350489Y581568D01*
X351573Y583190D01*
X352059Y583287D01*
X352058D01*
X353776Y585857D01*
X354522Y587658D01*
X354332Y588115D01*
X355080Y589918D01*
X355537Y590107D01*
X355536D01*
X362786Y607609D01*
Y623783D01*
X329297Y681801D01*
X324482Y699759D01*
X316850Y786981D01*
X316851D01*
X309220Y874202D01*
X322372Y1024728D01*
Y1028410D01*
X325922Y1064457D01*
Y1069988D01*
G01X320993Y561479D02*
X322138Y562624D01*
X323788D01*
X325803Y561790D01*
X329303D01*
X336297Y564687D01*
X350364Y578754D01*
X354760Y585331D01*
X363896Y607388D01*
Y624081D01*
X330332Y682230D01*
X325580Y699953D01*
X310335Y874202D01*
X323482Y1024679D01*
Y1028355D01*
X327032Y1064402D01*
Y1069988D01*
G01X320993Y514839D02*
X322138Y513694D01*
X325740D01*
X326140Y514094D01*
X327940D01*
X328340Y513694D01*
X331512D01*
X335306Y515266D01*
X336920Y516880D01*
Y517446D01*
X338194Y518720D01*
X338760D01*
X340032Y519992D01*
Y520558D01*
X341306Y521832D01*
X341872D01*
X344737Y524697D01*
X345425Y526359D01*
X345209Y526882D01*
X345898Y528546D01*
X346421Y528763D01*
X347109Y530425D01*
X346893Y530948D01*
X347582Y532612D01*
X348105Y532829D01*
X348793Y534491D01*
X348577Y535014D01*
X349266Y536678D01*
X349789Y536895D01*
X350477Y538557D01*
X350261Y539080D01*
X350950Y540744D01*
X351473Y540961D01*
X362942Y568647D01*
X363620Y569325D01*
X378026Y604104D01*
Y627633D01*
X377789Y628520D01*
X343662Y687653D01*
X339485Y703234D01*
X324683Y872414D01*
X329700Y929871D01*
X334732Y987513D01*
X375645Y1048745D01*
X378691Y1056100D01*
X380018Y1071289D01*
X375969Y1081063D01*
X342800Y1114232D01*
X334542Y1117653D01*
X330384D01*
G01X320993Y525613D02*
X322138Y526758D01*
X329828D01*
X337066Y529756D01*
X340142Y532832D01*
X355857Y570770D01*
X357665Y572578D01*
X371516Y606018D01*
Y625976D01*
X337674Y684609D01*
X333124Y701576D01*
X318161Y872601D01*
X328406Y989884D01*
X370059Y1052222D01*
X372407Y1057892D01*
X373401Y1069229D01*
X370347Y1077617D01*
X339167Y1108797D01*
X333164Y1111283D01*
X330384D01*
G01X331395Y518552D02*
X332540Y519697D01*
X335308D01*
X342100Y526489D01*
X359874Y569398D01*
X361407Y570931D01*
X375326Y604535D01*
Y627276D01*
X341249Y686323D01*
X336861Y702686D01*
X321992Y872648D01*
X332099Y988378D01*
X373321Y1050070D01*
X376084Y1056742D01*
X377321Y1070875D01*
X373722Y1079561D01*
X341298Y1111985D01*
X333967Y1115022D01*
X330290D01*
G01X320993Y511439D02*
X322138Y512584D01*
X331733D01*
X335935Y514325D01*
X345678Y524068D01*
X363883Y568018D01*
X364561Y568696D01*
X379136Y603883D01*
Y627779D01*
X378824Y628948D01*
X344697Y688082D01*
X340583Y703428D01*
X325798Y872414D01*
X335814Y987133D01*
X376629Y1048219D01*
X379782Y1055833D01*
X381148Y1071463D01*
X376910Y1081692D01*
X343429Y1115173D01*
X334763Y1118763D01*
X330384D01*
G01X320993Y529013D02*
X322138Y527868D01*
X325167D01*
X325587Y528288D01*
X327387D01*
X327807Y527868D01*
X329606D01*
X331269Y528557D01*
Y528556D01*
X331497Y529106D01*
X333161Y529795D01*
X333710Y529568D01*
X336437Y530697D01*
X339201Y533461D01*
X339889Y535123D01*
X339662Y535672D01*
X340351Y537336D01*
X340901Y537564D01*
X340900D01*
X341588Y539226D01*
X341372Y539749D01*
X342061Y541413D01*
X342584Y541630D01*
X343272Y543292D01*
X343056Y543815D01*
X343745Y545479D01*
X344268Y545696D01*
X344956Y547358D01*
X344740Y547881D01*
X345429Y549545D01*
X345953Y549761D01*
X346641Y551423D01*
X346425Y551946D01*
X347114Y553610D01*
X347637Y553827D01*
X354916Y571399D01*
X356724Y573207D01*
X370406Y606239D01*
Y625678D01*
X336639Y684180D01*
X332026Y701382D01*
X317046Y872601D01*
X317054Y872697D01*
X317055D01*
X327324Y990264D01*
X348310Y1021671D01*
X369075Y1052748D01*
X371316Y1058159D01*
X372273Y1069080D01*
X369388Y1077006D01*
X338538Y1107856D01*
X332943Y1110173D01*
X330384D01*
G01X331395Y488591D02*
X332540Y489736D01*
X335147D01*
X336466Y491055D01*
X337286Y493034D01*
X338309Y498182D01*
X347849Y520809D01*
X349730Y522691D01*
X382946Y602884D01*
Y628282D01*
X382344Y630535D01*
X348257Y689602D01*
X344379Y704057D01*
X329635Y872552D01*
X339521Y985792D01*
X379916Y1046243D01*
X383475Y1054836D01*
X384221Y1063397D01*
X384975Y1072056D01*
X380103Y1083818D01*
X345561Y1118360D01*
X335562Y1122502D01*
X330290D01*
G01X320993Y481479D02*
X322138Y482624D01*
X333534D01*
X339598Y488688D01*
X340953Y491960D01*
X341406Y494233D01*
X351496Y518586D01*
X353497Y520587D01*
X386756Y600879D01*
Y628785D01*
X385880Y632064D01*
X351839Y691052D01*
X348261Y704390D01*
X333531Y872745D01*
X343274Y984369D01*
X382973Y1043779D01*
X387169Y1053910D01*
X388809Y1072630D01*
X383290Y1085950D01*
X347693Y1121547D01*
X336355Y1126244D01*
X330384D01*
G01X320993Y467306D02*
X322138Y468451D01*
X331582D01*
X343172Y476194D01*
X359179Y514839D01*
X360421Y516081D01*
X394376Y598053D01*
Y629791D01*
X392997Y634953D01*
X359249Y693438D01*
X355909Y705678D01*
X341254Y873173D01*
X350703Y981454D01*
X389171Y1039020D01*
X391861Y1045514D01*
X394574Y1052063D01*
X395516Y1062886D01*
X396466Y1073807D01*
X389671Y1090207D01*
X351956Y1127922D01*
X337948Y1133724D01*
X330384D01*
G01X320993Y470706D02*
X322138Y469561D01*
X326844D01*
X327244Y469961D01*
X329044D01*
X329444Y469561D01*
X331244D01*
X338111Y474148D01*
X338222Y474703D01*
X339719Y475704D01*
X340274Y475594D01*
X342275Y476930D01*
X343262Y479314D01*
X343046Y479837D01*
X343735Y481501D01*
X344258Y481717D01*
X344946Y483380D01*
X344730Y483902D01*
X345419Y485566D01*
X345942Y485783D01*
X346630Y487446D01*
X346414Y487968D01*
X347103Y489632D01*
X347626Y489849D01*
X348314Y491511D01*
X348098Y492034D01*
X348787Y493698D01*
X349310Y493915D01*
X350368Y496470D01*
X350152Y496993D01*
X350841Y498657D01*
X351364Y498874D01*
X358238Y515468D01*
X359480Y516710D01*
X393266Y598274D01*
Y629645D01*
X391962Y634525D01*
X358216Y693007D01*
X354811Y705482D01*
X340139Y873173D01*
X349621Y981834D01*
X388187Y1039546D01*
X393483Y1052330D01*
X395336Y1073633D01*
X388730Y1089578D01*
X351327Y1126981D01*
X337727Y1132614D01*
X330384D01*
G01X320993Y484879D02*
X322138Y483734D01*
X328140D01*
X328540Y484134D01*
X330340D01*
X330740Y483734D01*
X333074D01*
X338657Y489317D01*
X339885Y492284D01*
X340338Y494557D01*
X341092Y496378D01*
X340876Y496900D01*
X341565Y498564D01*
X342088Y498781D01*
X342777Y500443D01*
X342560Y500966D01*
X343249Y502630D01*
X343773Y502846D01*
X344461Y504508D01*
X344245Y505031D01*
X344934Y506695D01*
X345458Y506911D01*
X345457Y506912D01*
X346146Y508574D01*
X345929Y509097D01*
X346618Y510761D01*
X347142Y510977D01*
X347141D01*
X347830Y512639D01*
X347613Y513162D01*
X348302Y514826D01*
X348826Y515042D01*
X350555Y519215D01*
X352556Y521216D01*
X353244Y522878D01*
X353028Y523401D01*
X353717Y525065D01*
X354240Y525282D01*
X385646Y601100D01*
Y628639D01*
X384845Y631636D01*
X350804Y690623D01*
X347163Y704196D01*
X332416Y872745D01*
X332424Y872841D01*
X332425D01*
X342192Y984749D01*
X381989Y1044305D01*
X386078Y1054177D01*
X387679Y1072456D01*
X382349Y1085321D01*
X347064Y1120606D01*
X336134Y1125134D01*
X330384D01*
G01X331395Y474418D02*
X332540Y475563D01*
X335172D01*
X340535Y480926D01*
X355456Y516945D01*
X356521Y518010D01*
X390566Y600202D01*
Y629288D01*
X389462Y633421D01*
X355513Y692252D01*
X351990Y705381D01*
X337371Y872486D01*
X346998Y982797D01*
X385902Y1041018D01*
X390865Y1052998D01*
X392636Y1073218D01*
X386481Y1088078D01*
X349825Y1124734D01*
X337154Y1129983D01*
X330290D01*
G01X331395Y536125D02*
X332540Y534980D01*
X334820D01*
X335520Y535680D01*
X336617Y538329D01*
X336390Y538877D01*
X337078Y540541D01*
X337628Y540769D01*
X338371Y542565D01*
X338144Y543113D01*
X338833Y544777D01*
X339383Y545005D01*
X339382D01*
X340070Y546667D01*
X339843Y547216D01*
X340532Y548880D01*
X341082Y549107D01*
X341081D01*
X341769Y550769D01*
X341542Y551318D01*
X342231Y552982D01*
X342781Y553209D01*
X342780D01*
X343468Y554871D01*
X343241Y555420D01*
X343930Y557084D01*
X344480Y557311D01*
X345168Y558973D01*
X344941Y559522D01*
X345630Y561186D01*
X346180Y561414D01*
X346179D01*
X350873Y572745D01*
X353509Y575381D01*
X353508D01*
X366596Y606976D01*
Y624743D01*
X332987Y682973D01*
X330606Y691849D01*
X330607D01*
X329435Y696217D01*
X329434D01*
X328848Y698401D01*
X328849D01*
X328239Y700678D01*
X313220Y872367D01*
X321842Y971071D01*
X321843D01*
X330452Y1069620D01*
X329970Y1091637D01*
X327184Y1097285D01*
X326264Y1098206D01*
G01X331395Y532725D02*
X332540Y533870D01*
X335280D01*
X336461Y535051D01*
X351814Y572116D01*
X354450Y574752D01*
X367706Y606755D01*
Y625041D01*
X334022Y683402D01*
X329337Y700872D01*
X314335Y872367D01*
X322949Y970970D01*
X322950D01*
X331564Y1069584D01*
X331075Y1091908D01*
X328099Y1097940D01*
X327049Y1098991D01*
G01X343212Y1784624D02*
Y1780829D01*
X343862Y1780179D01*
X352007D01*
X353307Y1781479D01*
Y1783453D01*
X355257Y1785403D01*
X358237D01*
X360187Y1783453D01*
Y1776255D01*
X361487Y1774955D01*
X363547D01*
X364847Y1776255D01*
Y1783453D01*
X366797Y1785403D01*
X369777D01*
X371727Y1783453D01*
Y1776255D01*
X373027Y1774955D01*
X375087D01*
X376387Y1776255D01*
Y1783453D01*
X378337Y1785403D01*
X381317D01*
X383267Y1783453D01*
Y1776255D01*
X384567Y1774955D01*
X386627D01*
X387927Y1776255D01*
Y1783453D01*
X389877Y1785403D01*
X392857D01*
X394807Y1783453D01*
Y1776255D01*
X396107Y1774955D01*
X398167D01*
X399467Y1776255D01*
Y1783453D01*
X401417Y1785403D01*
X404397D01*
X406347Y1783453D01*
Y1776255D01*
X407647Y1774955D01*
X409707D01*
X411007Y1776255D01*
Y1783453D01*
X412957Y1785403D01*
X415937D01*
X417887Y1783453D01*
Y1776255D01*
X419187Y1774955D01*
X421247D01*
X422547Y1776255D01*
Y1783453D01*
X424497Y1785403D01*
X427477D01*
X429427Y1783453D01*
Y1776255D01*
X430727Y1774955D01*
X432787D01*
X434087Y1776255D01*
Y1783453D01*
X436037Y1785403D01*
X439017D01*
X440967Y1783453D01*
Y1776255D01*
X442267Y1774955D01*
X444327D01*
X445627Y1776255D01*
Y1783453D01*
X447577Y1785403D01*
X450557D01*
X452507Y1783453D01*
Y1776255D01*
X453807Y1774955D01*
X455867D01*
X457167Y1776255D01*
Y1783453D01*
X459117Y1785403D01*
X462097D01*
X464047Y1783453D01*
Y1776255D01*
X465347Y1774955D01*
X467407D01*
X468707Y1776255D01*
Y1783453D01*
X470657Y1785403D01*
X473637D01*
X475587Y1783453D01*
Y1776255D01*
X476887Y1774955D01*
X478947D01*
X480247Y1776255D01*
Y1783453D01*
X482197Y1785403D01*
X485177D01*
X487127Y1783453D01*
Y1776255D01*
X488427Y1774955D01*
X490487D01*
X491787Y1776255D01*
Y1783453D01*
X493737Y1785403D01*
X496717D01*
X498667Y1783453D01*
Y1776255D01*
X499967Y1774955D01*
X502027D01*
X503327Y1776255D01*
Y1783453D01*
X505277Y1785403D01*
X508257D01*
X510207Y1783453D01*
Y1776255D01*
X511507Y1774955D01*
X513567D01*
X514867Y1776255D01*
Y1783453D01*
X516817Y1785403D01*
X519797D01*
X521747Y1783453D01*
Y1776255D01*
X523047Y1774955D01*
X525107D01*
X526407Y1776255D01*
Y1783453D01*
X528357Y1785403D01*
X531337D01*
X533287Y1783453D01*
Y1776255D01*
X534587Y1774955D01*
X536647D01*
X537947Y1776255D01*
Y1783453D01*
X539897Y1785403D01*
X542877D01*
X544827Y1783453D01*
Y1776255D01*
X546127Y1774955D01*
X548187D01*
X549487Y1776255D01*
Y1783453D01*
X551437Y1785403D01*
X554417D01*
X556367Y1783453D01*
Y1776255D01*
X557667Y1774955D01*
X559727D01*
X561027Y1776255D01*
Y1783453D01*
X562977Y1785403D01*
X565957D01*
X567907Y1783453D01*
Y1776255D01*
X569207Y1774955D01*
X571267D01*
X572567Y1776255D01*
Y1783453D01*
X574517Y1785403D01*
X577497D01*
X579447Y1783453D01*
Y1776255D01*
X580747Y1774955D01*
X582807D01*
X584107Y1776255D01*
Y1778229D01*
X586057Y1780179D01*
X594662D01*
X595312Y1780829D01*
Y1784624D01*
G01X343212Y1774624D02*
Y1778419D01*
X343862Y1779069D01*
X352467D01*
X354417Y1781019D01*
Y1782993D01*
X355717Y1784293D01*
X357777D01*
X359077Y1782993D01*
Y1775795D01*
X361027Y1773845D01*
X364007D01*
X365957Y1775795D01*
Y1782993D01*
X367257Y1784293D01*
X369317D01*
X370617Y1782993D01*
Y1775795D01*
X372567Y1773845D01*
X375547D01*
X377497Y1775795D01*
Y1782993D01*
X378797Y1784293D01*
X380857D01*
X382157Y1782993D01*
Y1775795D01*
X384107Y1773845D01*
X387087D01*
X389037Y1775795D01*
Y1782993D01*
X390337Y1784293D01*
X392397D01*
X393697Y1782993D01*
Y1775795D01*
X395647Y1773845D01*
X398627D01*
X400577Y1775795D01*
Y1782993D01*
X401877Y1784293D01*
X403937D01*
X405237Y1782993D01*
Y1775795D01*
X407187Y1773845D01*
X410167D01*
X412117Y1775795D01*
Y1782993D01*
X413417Y1784293D01*
X415477D01*
X416777Y1782993D01*
Y1775795D01*
X418727Y1773845D01*
X421707D01*
X423657Y1775795D01*
Y1782993D01*
X424957Y1784293D01*
X427017D01*
X428317Y1782993D01*
Y1775795D01*
X430267Y1773845D01*
X433247D01*
X435197Y1775795D01*
Y1782993D01*
X436497Y1784293D01*
X438557D01*
X439857Y1782993D01*
Y1775795D01*
X441807Y1773845D01*
X444787D01*
X446737Y1775795D01*
Y1782993D01*
X448037Y1784293D01*
X450097D01*
X451397Y1782993D01*
Y1775795D01*
X453347Y1773845D01*
X456327D01*
X458277Y1775795D01*
Y1782993D01*
X459577Y1784293D01*
X461637D01*
X462937Y1782993D01*
Y1775795D01*
X464887Y1773845D01*
X467867D01*
X469817Y1775795D01*
Y1782993D01*
X471117Y1784293D01*
X473177D01*
X474477Y1782993D01*
Y1775795D01*
X476427Y1773845D01*
X479407D01*
X481357Y1775795D01*
Y1782993D01*
X482657Y1784293D01*
X484717D01*
X486017Y1782993D01*
Y1775795D01*
X487967Y1773845D01*
X490947D01*
X492897Y1775795D01*
Y1782993D01*
X494197Y1784293D01*
X496257D01*
X497557Y1782993D01*
Y1775795D01*
X499507Y1773845D01*
X502487D01*
X504437Y1775795D01*
Y1782993D01*
X505737Y1784293D01*
X507797D01*
X509097Y1782993D01*
Y1775795D01*
X511047Y1773845D01*
X514027D01*
X515977Y1775795D01*
Y1782993D01*
X517277Y1784293D01*
X519337D01*
X520637Y1782993D01*
Y1775795D01*
X522587Y1773845D01*
X525567D01*
X527517Y1775795D01*
Y1782993D01*
X528817Y1784293D01*
X530877D01*
X532177Y1782993D01*
Y1775795D01*
X534127Y1773845D01*
X537107D01*
X539057Y1775795D01*
Y1782993D01*
X540357Y1784293D01*
X542417D01*
X543717Y1782993D01*
Y1775795D01*
X545667Y1773845D01*
X548647D01*
X550597Y1775795D01*
Y1782993D01*
X551897Y1784293D01*
X553957D01*
X555257Y1782993D01*
Y1775795D01*
X557207Y1773845D01*
X560187D01*
X562137Y1775795D01*
Y1782993D01*
X563437Y1784293D01*
X565497D01*
X566797Y1782993D01*
Y1775795D01*
X568747Y1773845D01*
X571727D01*
X573677Y1775795D01*
Y1782993D01*
X574977Y1784293D01*
X577037D01*
X578337Y1782993D01*
Y1775795D01*
X580287Y1773845D01*
X583267D01*
X585217Y1775795D01*
Y1777769D01*
X586517Y1779069D01*
X594662D01*
X595312Y1778419D01*
Y1774624D01*
G01X942731Y324044D02*
X941586Y322899D01*
Y321050D01*
X940436Y319900D01*
X931200D01*
X929000Y317700D01*
X907900D01*
X888000Y337600D01*
X866800D01*
X865400Y336200D01*
X812700D01*
X806900Y342000D01*
X769300D01*
X766500Y344800D01*
X577000D01*
X572500Y340300D01*
X528700D01*
X520800Y348200D01*
Y375500D01*
X479000Y417300D01*
Y426400D01*
X421700Y483700D01*
X412300D01*
X402700Y493300D01*
Y656300D01*
X372200Y686800D01*
Y733300D01*
X358700Y746800D01*
Y788900D01*
X367000Y797200D01*
X389320D01*
X391270Y795250D01*
Y793870D01*
X392415Y792725D01*
G01X389015D02*
X390160Y793870D01*
Y794790D01*
X388860Y796090D01*
X367460D01*
X359810Y788440D01*
Y782525D01*
X360260Y782075D01*
Y780125D01*
X359810Y779675D01*
Y777725D01*
X360260Y777275D01*
Y775325D01*
X359810Y774875D01*
Y772925D01*
X360260Y772475D01*
Y770525D01*
X359810Y770075D01*
Y768125D01*
X360260Y767675D01*
Y765725D01*
X359810Y765275D01*
Y747260D01*
X373310Y733760D01*
Y687260D01*
X403810Y656760D01*
Y493760D01*
X412760Y484810D01*
X422160D01*
X428227Y478743D01*
X428863D01*
X430243Y477363D01*
Y476727D01*
X431621Y475349D01*
X432258D01*
X433638Y473969D01*
Y473332D01*
X435016Y471954D01*
X435653D01*
X437033Y470574D01*
Y469937D01*
X438411Y468559D01*
X439048D01*
X440428Y467179D01*
Y466542D01*
X480110Y426860D01*
Y417760D01*
X521910Y375960D01*
Y348660D01*
X529160Y341410D01*
X545175D01*
X545625Y341860D01*
X547575D01*
X548025Y341410D01*
X550875D01*
X551325Y341860D01*
X553275D01*
X553725Y341410D01*
X555675D01*
X556125Y341860D01*
X558075D01*
X558525Y341410D01*
X560475D01*
X560925Y341860D01*
X562875D01*
X563325Y341410D01*
X572040D01*
X576540Y345910D01*
X766960D01*
X769760Y343110D01*
X807360D01*
X813160Y337310D01*
X829375D01*
X829825Y337760D01*
X831775D01*
X832225Y337310D01*
X834175D01*
X834625Y337760D01*
X836575D01*
X837025Y337310D01*
X838975D01*
X839425Y337760D01*
X841375D01*
X841825Y337310D01*
X843775D01*
X844225Y337760D01*
X846175D01*
X846625Y337310D01*
X864940D01*
X866340Y338710D01*
X888460D01*
X908360Y318810D01*
X911975D01*
X912425Y319260D01*
X914375D01*
X914825Y318810D01*
X922075D01*
X922525Y319260D01*
X924475D01*
X924925Y318810D01*
X928540D01*
X930740Y321010D01*
X933475D01*
X933925Y321460D01*
X935875D01*
X936325Y321010D01*
X939976D01*
X940476Y321510D01*
Y322899D01*
X939331Y324044D01*
G01X1079748Y322743D02*
X1078603Y321598D01*
X1062428D01*
X1051540Y310710D01*
X1031640D01*
X1026140Y305210D01*
X991686D01*
X987581Y303510D01*
X954840D01*
X945640Y294310D01*
X884240D01*
X880940Y291010D01*
X872360D01*
X866060Y297310D01*
X774360D01*
X749560Y322110D01*
X465279D01*
X458736Y319400D01*
X427563D01*
X414627Y321973D01*
X408204Y328396D01*
X404456Y337444D01*
X401268Y340632D01*
X396028D01*
X394883Y341777D01*
G01X1079748Y319343D02*
X1078603Y320488D01*
X1062888D01*
X1052000Y309600D01*
X1032100D01*
X1026600Y304100D01*
X991907D01*
X987802Y302400D01*
X955300D01*
X946100Y293200D01*
X884700D01*
X881400Y289900D01*
X871900D01*
X865600Y296200D01*
X773900D01*
X749100Y321000D01*
X465500D01*
X458957Y318290D01*
X427453D01*
X414080Y320950D01*
X407263Y327767D01*
X403515Y336815D01*
X400808Y339522D01*
X396028D01*
X394883Y338377D01*
G01X942700Y346363D02*
X941555Y347508D01*
Y349845D01*
X940100Y351300D01*
X932500D01*
X928800Y355000D01*
X917700D01*
X905800Y343100D01*
X884300D01*
X875900Y351500D01*
X834800D01*
X833200Y353100D01*
X817724D01*
X796477Y361900D01*
X594300D01*
X529700Y426500D01*
X511400D01*
X480000Y457900D01*
Y520300D01*
X478300Y522000D01*
Y553800D01*
X479900Y555400D01*
Y635000D01*
X493400Y648500D01*
X538308D01*
X543242Y651796D01*
X553500Y676562D01*
Y753700D01*
X557100Y757300D01*
Y769300D01*
X548023Y778377D01*
Y780455D01*
X549168Y781600D01*
G01X939300Y346363D02*
X940445Y347508D01*
Y349385D01*
X939640Y350190D01*
X932040D01*
X928340Y353890D01*
X918160D01*
X906260Y341990D01*
X883840D01*
X875440Y350390D01*
X834340D01*
X832740Y351990D01*
X817503D01*
X796256Y360790D01*
X593840D01*
X529240Y425390D01*
X510940D01*
X478890Y457440D01*
Y519840D01*
X477190Y521540D01*
Y554260D01*
X478790Y555860D01*
Y635460D01*
X492940Y649610D01*
X537971D01*
X542345Y652532D01*
X552390Y676783D01*
Y754160D01*
X555990Y757760D01*
Y768840D01*
X546913Y777917D01*
Y780455D01*
X545768Y781600D01*
G01X605778Y391001D02*
X604633Y392146D01*
X599830D01*
X590066Y396191D01*
X568149Y418107D01*
X559799Y438267D01*
X536635Y514625D01*
Y547811D01*
X546872Y572527D01*
X549666Y629432D01*
X551889Y640608D01*
X689504Y1047181D01*
Y1068787D01*
G01X605778Y394401D02*
X604633Y393256D01*
X600056D01*
X598296Y393984D01*
X598053Y394573D01*
X596296Y395300D01*
X595708Y395056D01*
X590695Y397132D01*
X588467Y399360D01*
Y399996D01*
X587123Y401340D01*
X586487D01*
X585144Y402683D01*
Y403319D01*
X583799Y404664D01*
X583163D01*
X581820Y406007D01*
Y406643D01*
X580475Y407988D01*
X579839D01*
X578496Y409331D01*
Y409967D01*
X577151Y411312D01*
X576515D01*
X575172Y412655D01*
Y413291D01*
X573827Y414636D01*
X573191D01*
X569090Y418736D01*
X568268Y420724D01*
X568512Y421312D01*
X567785Y423068D01*
X567196Y423312D01*
X566434Y425151D01*
X566678Y425739D01*
X565951Y427496D01*
X565362Y427739D01*
X560846Y438642D01*
X537745Y514790D01*
Y547590D01*
X547972Y572280D01*
X550771Y629296D01*
X552964Y640321D01*
X690614Y1046998D01*
Y1068787D01*
G01X629567Y1607048D02*
Y1608552D01*
X630067Y1609052D01*
X630939D01*
X633041Y1606950D01*
Y1554600D01*
X630186Y1551745D01*
X627665Y1550700D01*
X627142Y1550916D01*
X625340Y1550169D01*
X625123Y1549646D01*
X622327Y1548487D01*
X604990Y1534350D01*
X597066Y1519962D01*
X575845Y1362806D01*
X570460Y1347771D01*
X549577Y1313982D01*
X549576Y1313981D01*
X528547Y1279954D01*
X526656Y1272916D01*
X526655D01*
X526654Y1272912D01*
Y1272910D01*
X526618Y1272775D01*
Y1248494D01*
X545870Y1205093D01*
X559436Y1191527D01*
X559556D01*
X566545Y1188633D01*
X582010Y1184976D01*
X600088D01*
G01X638228Y1611378D02*
Y1612883D01*
X638728Y1613383D01*
X639600D01*
X641702Y1611281D01*
Y1555402D01*
X640173Y1553873D01*
X639607D01*
X638227Y1552493D01*
Y1551927D01*
X636615Y1550315D01*
X624425Y1545262D01*
X608188Y1532021D01*
X600640Y1518315D01*
X579433Y1361267D01*
X574194Y1346636D01*
X532077Y1278491D01*
X530388Y1272201D01*
Y1250746D01*
X549468Y1207731D01*
X562884Y1194315D01*
X567083Y1192576D01*
X580904Y1190008D01*
X585047Y1188716D01*
X597500D01*
G01X629567Y1612166D02*
Y1610662D01*
X630067Y1610162D01*
X631399D01*
X634151Y1607410D01*
Y1554140D01*
X630815Y1550804D01*
X622903Y1547523D01*
X605859Y1533625D01*
X598139Y1519608D01*
X576930Y1362541D01*
X571466Y1347287D01*
X529577Y1279509D01*
X527728Y1272625D01*
Y1248730D01*
X543221Y1213803D01*
X543220D01*
X543748Y1213600D01*
X544540Y1211817D01*
X544336Y1211289D01*
X546801Y1205732D01*
X550008Y1202525D01*
X550574D01*
X551954Y1201145D01*
Y1200579D01*
X553332Y1199201D01*
X553898D01*
X555278Y1197821D01*
Y1197255D01*
X556656Y1195877D01*
X557222D01*
X558602Y1194497D01*
Y1193931D01*
X559980Y1192553D01*
X566887Y1189693D01*
X582140Y1186086D01*
X600088D01*
G01X638228Y1616496D02*
Y1614993D01*
X638728Y1614493D01*
X640060D01*
X642812Y1611741D01*
Y1554942D01*
X637244Y1549374D01*
X625001Y1544298D01*
X609057Y1531296D01*
X601713Y1517961D01*
X580518Y1361002D01*
X575200Y1346152D01*
X533107Y1278046D01*
X531498Y1272054D01*
Y1250982D01*
X542775Y1225558D01*
X543303Y1225354D01*
X544094Y1223571D01*
X543891Y1223043D01*
X544681Y1221261D01*
X545209Y1221057D01*
X546000Y1219274D01*
X545797Y1218746D01*
X546587Y1216964D01*
X547115Y1216760D01*
X547906Y1214977D01*
X547703Y1214449D01*
X548493Y1212667D01*
X549021Y1212463D01*
X549812Y1210680D01*
X549609Y1210152D01*
X550399Y1208370D01*
X553262Y1205507D01*
X553827D01*
X555207Y1204127D01*
Y1203562D01*
X556688Y1202081D01*
X557254D01*
X558634Y1200701D01*
Y1200135D01*
X560012Y1198757D01*
X560577D01*
X561957Y1197377D01*
Y1196812D01*
X563513Y1195256D01*
X567400Y1193647D01*
X581172Y1191088D01*
X585217Y1189826D01*
X597500D01*
G01X646890Y1607048D02*
Y1608552D01*
X647390Y1609052D01*
X648262D01*
X650364Y1606950D01*
Y1555062D01*
X648263Y1552961D01*
X647697D01*
X646317Y1551581D01*
Y1551015D01*
X644939Y1549637D01*
X626476Y1541985D01*
X611145Y1529485D01*
X604258Y1516984D01*
X583001Y1359569D01*
X578013Y1345639D01*
X535607Y1277027D01*
X534196Y1271774D01*
X534195D01*
X534158Y1271633D01*
Y1253928D01*
X553875Y1209477D01*
X566416Y1196935D01*
X567791Y1196364D01*
X578032Y1194462D01*
X578033D01*
X581150Y1193883D01*
X585723Y1192456D01*
X597500D01*
G01X655551Y1611378D02*
Y1612883D01*
X656051Y1613383D01*
X656923D01*
X659025Y1611281D01*
Y1557118D01*
X648986Y1547079D01*
X628274Y1538494D01*
X614178Y1526998D01*
X607858Y1515523D01*
X586633Y1358345D01*
X581580Y1344237D01*
X560432Y1310019D01*
X560431Y1310018D01*
X539137Y1275562D01*
X537966Y1271203D01*
X537965D01*
X537964Y1271199D01*
Y1271197D01*
X537928Y1271062D01*
Y1254816D01*
X554361Y1217768D01*
X571150Y1200979D01*
X586479Y1196196D01*
X597500D01*
G01X646890Y1612166D02*
Y1610662D01*
X647390Y1610162D01*
X648722D01*
X651474Y1607410D01*
Y1554602D01*
X645568Y1548696D01*
X627052Y1541021D01*
X612014Y1528760D01*
X605331Y1516630D01*
X584086Y1359304D01*
X579019Y1345155D01*
X536637Y1276582D01*
X535268Y1271483D01*
Y1254164D01*
X554806Y1210116D01*
X558814Y1206107D01*
X559380D01*
X560760Y1204727D01*
Y1204161D01*
X562138Y1202783D01*
X562704D01*
X564083Y1201404D01*
Y1200838D01*
X567045Y1197876D01*
X568109Y1197435D01*
X570908Y1196916D01*
X571375Y1197236D01*
X573293Y1196880D01*
X573613Y1196413D01*
X575530Y1196057D01*
X575996Y1196377D01*
X577915Y1196021D01*
X578235Y1195554D01*
X581418Y1194963D01*
X585893Y1193566D01*
X597500D01*
G01X655551Y1616496D02*
Y1614993D01*
X656051Y1614493D01*
X657383D01*
X660135Y1611741D01*
Y1556658D01*
X649615Y1546138D01*
X628850Y1537530D01*
X615047Y1526273D01*
X608931Y1515169D01*
X587718Y1358080D01*
X582586Y1343753D01*
X540167Y1275117D01*
X539038Y1270912D01*
Y1255052D01*
X543508Y1244975D01*
X543507Y1244974D01*
X544035Y1244770D01*
X544826Y1242987D01*
X544623Y1242459D01*
X544624D01*
X545414Y1240678D01*
X545413Y1240677D01*
X545941Y1240473D01*
X546732Y1238690D01*
X546529Y1238162D01*
X546530D01*
X547320Y1236381D01*
X547319Y1236380D01*
X547847Y1236176D01*
X548638Y1234393D01*
X548435Y1233865D01*
X548436D01*
X549226Y1232084D01*
X549225Y1232083D01*
X549753Y1231879D01*
X550544Y1230096D01*
X550341Y1229568D01*
X550342D01*
X551132Y1227787D01*
X551131Y1227786D01*
X551659Y1227582D01*
X552450Y1225799D01*
X552247Y1225271D01*
X552248D01*
X553038Y1223490D01*
X553037Y1223489D01*
X553565Y1223286D01*
X554357Y1221502D01*
X554153Y1220975D01*
X555292Y1218407D01*
X571742Y1201958D01*
X586649Y1197306D01*
X597500D01*
G01X694354Y1069000D02*
Y1046160D01*
X556774Y639694D01*
X554551Y628516D01*
X551730Y571117D01*
X541555Y546551D01*
Y515205D01*
X563058Y444322D01*
X564125Y441746D01*
X564604Y441548D01*
X565414Y439590D01*
X565216Y439112D01*
X565962Y437311D01*
X566465Y437103D01*
X567261Y435179D01*
X567053Y434677D01*
X567799Y432876D01*
X568388Y432633D01*
X569134Y430830D01*
X568890Y430242D01*
X569636Y428441D01*
X570225Y428198D01*
X570971Y426395D01*
X570727Y425807D01*
X572641Y421186D01*
X575290Y418537D01*
X575927D01*
X577307Y417157D01*
Y416520D01*
X578685Y415142D01*
X579322D01*
X580702Y413762D01*
Y413125D01*
X582080Y411747D01*
X582717D01*
X584097Y410367D01*
Y409730D01*
X585475Y408352D01*
X585969D01*
X587314Y407008D01*
Y406513D01*
X588657Y405170D01*
X589152D01*
X590497Y403825D01*
Y403330D01*
X592461Y401366D01*
X594870Y400368D01*
X596631D01*
X597776Y401513D01*
G01Y398113D02*
X596631Y399258D01*
X594649D01*
X591832Y400425D01*
X571700Y420557D01*
X562011Y443947D01*
X540445Y515040D01*
Y546772D01*
X550630Y571364D01*
X553446Y628652D01*
X555699Y639981D01*
X693244Y1046343D01*
Y1069000D01*
G01X605778Y405174D02*
X604633Y406319D01*
X597444D01*
X593001Y408159D01*
X593002D01*
X589241Y409717D01*
X574765Y424193D01*
X566171Y444941D01*
X566170Y444943D01*
X564310Y449431D01*
X544255Y515547D01*
Y546038D01*
X554396Y570522D01*
X556507Y613445D01*
X557213Y627807D01*
X559510Y639355D01*
X696984Y1045504D01*
Y1068787D01*
G01X605778Y408574D02*
X604633Y407429D01*
X602038D01*
X601588Y407879D01*
X599688D01*
X599238Y407429D01*
X597665D01*
X595590Y408290D01*
Y408288D01*
X595346Y408877D01*
X593590Y409604D01*
X593002Y409361D01*
X589870Y410658D01*
X588527Y412001D01*
Y412637D01*
X587182Y413982D01*
X586546D01*
X585203Y415325D01*
Y415961D01*
X583858Y417306D01*
X583222D01*
X581879Y418649D01*
Y419285D01*
X580534Y420630D01*
X579898D01*
X575706Y424822D01*
X574599Y427495D01*
X574843Y428083D01*
X574116Y429840D01*
X573527Y430083D01*
X572359Y432903D01*
X572603Y433491D01*
X571876Y435247D01*
X571287Y435491D01*
X570107Y438340D01*
X570351Y438928D01*
X569624Y440684D01*
X569035Y440928D01*
X565357Y449806D01*
X545365Y515712D01*
Y545817D01*
X555496Y570275D01*
X558318Y627671D01*
X560585Y639068D01*
X698094Y1045321D01*
Y1068787D01*
G01X595376Y412287D02*
X594231Y413432D01*
X591625D01*
X578434Y426623D01*
X566245Y456053D01*
X548065Y515982D01*
Y545170D01*
X558153Y569524D01*
X559559Y598173D01*
Y598172D01*
X560261Y612461D01*
X560966Y626823D01*
X563354Y638828D01*
X700724Y1044666D01*
Y1069000D01*
G01X605778Y419347D02*
X604633Y420492D01*
X597105D01*
X588672Y423985D01*
X580977Y431680D01*
X568287Y462317D01*
X551875Y516427D01*
Y544307D01*
X562042Y568853D01*
X564894Y626857D01*
X567130Y638099D01*
X704465Y1043830D01*
Y1068787D01*
G01X595376Y415687D02*
X594231Y414542D01*
X592085D01*
X590647Y415980D01*
Y416475D01*
X589302Y417820D01*
X588807D01*
X587464Y419163D01*
Y419658D01*
X586119Y421002D01*
X585625D01*
X584247Y422380D01*
Y423017D01*
X582867Y424397D01*
X582230D01*
X579375Y427252D01*
X579000Y428158D01*
Y428159D01*
X578874Y428462D01*
X579118Y429050D01*
X578372Y430853D01*
X577783Y431096D01*
X577037Y432897D01*
X577281Y433485D01*
X576535Y435288D01*
X575946Y435531D01*
Y435532D01*
X575200Y437333D01*
X575444Y437921D01*
X574698Y439724D01*
X574109Y439967D01*
X573363Y441768D01*
X573607Y442356D01*
X572861Y444159D01*
X572272Y444402D01*
X571526Y446203D01*
X571770Y446791D01*
X571024Y448594D01*
X570435Y448837D01*
X570436D01*
X569690Y450638D01*
X569689D01*
X569837Y450994D01*
X568955Y453125D01*
X568598Y453272D01*
X568599Y453273D01*
X567292Y456428D01*
X549175Y516147D01*
Y544949D01*
X559253Y569277D01*
X562071Y626687D01*
X564429Y638541D01*
X701834Y1044483D01*
Y1069000D01*
G01X605778Y422747D02*
X604633Y421602D01*
X602027D01*
X601577Y422052D01*
X599677D01*
X599227Y421602D01*
X597326D01*
X589301Y424926D01*
X587958Y426269D01*
Y426905D01*
X586613Y428250D01*
X585977D01*
X581919Y432308D01*
X581719Y432792D01*
X581718D01*
X581117Y434244D01*
X581361Y434832D01*
X580634Y436588D01*
X580045Y436832D01*
X579318Y438587D01*
X579562Y439175D01*
X578835Y440931D01*
X578246Y441175D01*
X577508Y442958D01*
X577752Y443546D01*
X577024Y445302D01*
X576436Y445545D01*
X575709Y447300D01*
X575953Y447888D01*
X575226Y449644D01*
X574637Y449888D01*
X573910Y451643D01*
X574154Y452231D01*
X573427Y453987D01*
X572838Y454231D01*
X571750Y456858D01*
X571994Y457446D01*
X571267Y459202D01*
X570678Y459446D01*
X569334Y462692D01*
X552985Y516592D01*
Y544086D01*
X563142Y568606D01*
X565999Y626721D01*
X568205Y637812D01*
X705575Y1043647D01*
Y1068787D01*
G01X664213Y1612166D02*
Y1610662D01*
X664713Y1610162D01*
X666045D01*
X668797Y1607410D01*
Y1554140D01*
X666397Y1551740D01*
X655471Y1544438D01*
X630798Y1534210D01*
X618029Y1523797D01*
X612550Y1513852D01*
X591368Y1356995D01*
X586080Y1342228D01*
X543697Y1273652D01*
X542808Y1270341D01*
Y1257305D01*
X559264Y1220208D01*
X567439Y1212033D01*
X568005D01*
X569385Y1210653D01*
Y1210087D01*
X570763Y1208709D01*
X571329D01*
X572709Y1207329D01*
Y1206763D01*
X574333Y1205139D01*
X578463Y1203849D01*
X578964Y1204112D01*
X580827Y1203531D01*
X581089Y1203029D01*
X582950Y1202448D01*
X583451Y1202711D01*
X585314Y1202130D01*
X585576Y1201628D01*
X587437Y1201047D01*
X597500D01*
G01X664213Y1607048D02*
Y1608552D01*
X664713Y1609052D01*
X665585D01*
X667687Y1606950D01*
Y1554600D01*
X665689Y1552602D01*
X663934Y1551429D01*
X663379Y1551540D01*
X661757Y1550455D01*
X661647Y1549900D01*
Y1549901D01*
X654945Y1545422D01*
X630222Y1535174D01*
X617160Y1524522D01*
X611477Y1514206D01*
X590283Y1357260D01*
X585074Y1342712D01*
X542667Y1274097D01*
X541698Y1270488D01*
Y1257069D01*
X558333Y1219569D01*
X573741Y1204160D01*
X587267Y1199937D01*
X597500D01*
G01X681535Y1612166D02*
Y1610662D01*
X682035Y1610162D01*
X683367D01*
X686119Y1607410D01*
Y1554608D01*
X683987Y1552476D01*
X666358Y1540693D01*
X634706Y1527573D01*
X624188Y1518997D01*
X619752Y1510949D01*
X598658Y1354731D01*
X593118Y1339265D01*
X550757Y1270723D01*
X550348Y1269202D01*
Y1259597D01*
X555365Y1248297D01*
X563456Y1236185D01*
X567749Y1231092D01*
X568313Y1231044D01*
X569571Y1229552D01*
X569523Y1228988D01*
X570779Y1227498D01*
X574294Y1223983D01*
X574860D01*
X576240Y1222603D01*
Y1222037D01*
X577618Y1220659D01*
X578184D01*
X579564Y1219279D01*
Y1218713D01*
X580942Y1217335D01*
X581508D01*
X582888Y1215955D01*
Y1215389D01*
X584266Y1214011D01*
X584831D01*
X586211Y1212631D01*
Y1212066D01*
X587752Y1210525D01*
X592575Y1208527D01*
X597500D01*
G01X672874Y1611378D02*
Y1612883D01*
X673374Y1613383D01*
X674246D01*
X676348Y1611281D01*
Y1556998D01*
X669049Y1549699D01*
X658965Y1542959D01*
X632262Y1531891D01*
X620321Y1522152D01*
X615048Y1512529D01*
X593928Y1356127D01*
X588593Y1341229D01*
X546196Y1272631D01*
X545468Y1269920D01*
Y1258248D01*
X551995Y1243532D01*
X559254Y1232667D01*
X559255Y1232666D01*
X568096Y1219435D01*
X579132Y1208398D01*
X588183Y1203677D01*
X597500D01*
G01X681535Y1607048D02*
Y1608552D01*
X682035Y1609052D01*
X682907D01*
X685009Y1606950D01*
Y1555068D01*
X683279Y1553338D01*
X681007Y1551820D01*
X680452Y1551930D01*
X678830Y1550846D01*
X678720Y1550291D01*
X677099Y1549208D01*
X676544Y1549318D01*
X674922Y1548234D01*
X674812Y1547679D01*
X665832Y1541677D01*
X634130Y1528537D01*
X623319Y1519722D01*
X618679Y1511303D01*
X597573Y1354996D01*
X592112Y1339749D01*
X570993Y1305578D01*
X570992Y1305577D01*
X560402Y1288443D01*
X560403D01*
X549727Y1271168D01*
X549238Y1269349D01*
Y1259361D01*
X554388Y1247759D01*
X562567Y1235517D01*
X569961Y1226746D01*
X587123Y1209584D01*
X592354Y1207417D01*
X597500D01*
G01X672874Y1616496D02*
Y1614993D01*
X673374Y1614493D01*
X674706D01*
X677458Y1611741D01*
Y1556538D01*
X669757Y1548837D01*
X659491Y1541975D01*
X646164Y1536451D01*
X646162Y1536450D01*
X632838Y1530927D01*
X621191Y1521428D01*
X616121Y1512176D01*
X595013Y1355862D01*
X589599Y1340745D01*
X547226Y1272186D01*
X546578Y1269773D01*
Y1258484D01*
X552972Y1244070D01*
X559922Y1233667D01*
X560477Y1233557D01*
X561562Y1231935D01*
X561451Y1231380D01*
X562534Y1229759D01*
X563088Y1229648D01*
X564173Y1228026D01*
X564062Y1227471D01*
X565145Y1225850D01*
X565700Y1225739D01*
X566784Y1224117D01*
X566674Y1223562D01*
X568958Y1220143D01*
X573149Y1215952D01*
X573715D01*
X575095Y1214572D01*
Y1214006D01*
X576473Y1212628D01*
X577039D01*
X578419Y1211248D01*
Y1210682D01*
X579797Y1209304D01*
X584289Y1206961D01*
X584829Y1207131D01*
X586559Y1206228D01*
X586729Y1205688D01*
X588456Y1204787D01*
X597500D01*
G01X690197Y1611378D02*
Y1612882D01*
X690697Y1613382D01*
X691569D01*
X693671Y1611280D01*
Y1559080D01*
X692601Y1556497D01*
X686255Y1550151D01*
X669961Y1539261D01*
X636299Y1525308D01*
X626558Y1517365D01*
X622235Y1509515D01*
X601225Y1353920D01*
X595598Y1338211D01*
X574500Y1304076D01*
X574501D01*
X553256Y1269702D01*
X553008Y1268778D01*
Y1260255D01*
X556888Y1251507D01*
X564268Y1240462D01*
X572088Y1231033D01*
X583643Y1219478D01*
X583644D01*
X589964Y1213158D01*
X591982Y1211809D01*
X593558Y1211157D01*
X597500D01*
G01X690197Y1616496D02*
Y1614992D01*
X690697Y1614492D01*
X692029D01*
X694781Y1611740D01*
Y1558859D01*
X693542Y1555868D01*
X686963Y1549289D01*
X670487Y1538277D01*
X653681Y1531310D01*
X653680D01*
X636875Y1524344D01*
X627427Y1516640D01*
X623308Y1509161D01*
X602310Y1353655D01*
X596604Y1337727D01*
X554286Y1269257D01*
X554118Y1268631D01*
Y1260491D01*
X557865Y1252045D01*
X565159Y1241127D01*
X566494Y1239518D01*
X567127Y1239459D01*
X568374Y1237957D01*
X568314Y1237323D01*
X569559Y1235823D01*
X570192Y1235764D01*
X571438Y1234262D01*
X571379Y1233628D01*
X572910Y1231782D01*
X575948Y1228744D01*
X576585D01*
X577965Y1227364D01*
Y1226727D01*
X579343Y1225349D01*
X579980D01*
X581360Y1223969D01*
Y1223332D01*
X582738Y1221954D01*
X583374D01*
X584754Y1220574D01*
Y1219938D01*
X590672Y1214020D01*
X592508Y1212793D01*
X593779Y1212267D01*
X597500D01*
G01X595376Y426460D02*
X594231Y427605D01*
X591151D01*
X584588Y434167D01*
X570439Y468321D01*
X555685Y516964D01*
Y543414D01*
X565798Y567830D01*
X567939Y611407D01*
X568656Y625988D01*
X570940Y637471D01*
X708205Y1042992D01*
Y1069000D01*
G01X595376Y429860D02*
X594231Y428715D01*
X591611D01*
X590268Y430058D01*
Y430525D01*
X588923Y431869D01*
X588457D01*
X585529Y434796D01*
X584484Y437319D01*
X584662Y437750D01*
X583934Y439506D01*
X583503Y439685D01*
Y439687D01*
X582757Y441487D01*
X583001Y442075D01*
X582254Y443878D01*
X581665Y444121D01*
X581666D01*
X580920Y445922D01*
X581164Y446510D01*
X580417Y448313D01*
X579828Y448556D01*
X579829D01*
X579083Y450357D01*
X579327Y450945D01*
X578580Y452748D01*
X577991Y452991D01*
X577992Y452992D01*
X577246Y454792D01*
X577245D01*
X577489Y455380D01*
X576743Y457183D01*
X576154Y457426D01*
X575408Y459227D01*
X575702Y459935D01*
X575026Y461569D01*
X574317Y461861D01*
X573571Y463662D01*
X573865Y464370D01*
X573189Y466004D01*
X572480Y466296D01*
X571486Y468696D01*
X556795Y517129D01*
Y543193D01*
X566898Y567583D01*
X569761Y625852D01*
X572015Y637184D01*
X709315Y1042809D01*
Y1069000D01*
G01X605778Y433521D02*
X604633Y434666D01*
X596095D01*
X591974Y436373D01*
X591973D01*
X588576Y437781D01*
X587389Y438968D01*
X572204Y475633D01*
X559495Y517525D01*
Y542546D01*
X569621Y566991D01*
X571773Y610837D01*
X572494Y625508D01*
X574748Y636841D01*
X711945Y1042154D01*
Y1068787D01*
G01X605778Y436921D02*
X604633Y435776D01*
X602327D01*
X601877Y436226D01*
X599977D01*
X599527Y435776D01*
X596316D01*
X594561Y436503D01*
X594318Y437092D01*
X592561Y437819D01*
X591973Y437575D01*
X589205Y438722D01*
X588330Y439597D01*
X587604Y441352D01*
X587847Y441940D01*
X587120Y443696D01*
X586531Y443940D01*
Y443941D01*
X585805Y445696D01*
X586048Y446284D01*
X585321Y448040D01*
X584732Y448284D01*
Y448285D01*
X584006Y450040D01*
X584249Y450628D01*
X583522Y452384D01*
X582933Y452628D01*
X582207Y454383D01*
X582450Y454971D01*
X581723Y456727D01*
X581134Y456971D01*
X581135D01*
X580408Y458726D01*
X580652Y459314D01*
X579925Y461070D01*
X579336Y461314D01*
X578610Y463069D01*
X578853Y463657D01*
X578126Y465413D01*
X577537Y465657D01*
Y465659D01*
X573251Y476008D01*
X560605Y517690D01*
Y542325D01*
X570721Y566744D01*
X572166Y596194D01*
Y596195D01*
X573599Y625372D01*
X575823Y636554D01*
X713055Y1041971D01*
Y1068787D01*
G01X595376Y440633D02*
X594231Y441778D01*
X591478D01*
X590449Y442807D01*
X574428Y481484D01*
X563305Y518152D01*
Y541838D01*
X573387Y566178D01*
X574823Y595414D01*
Y595413D01*
X576260Y624651D01*
X578560Y636215D01*
X715685Y1041317D01*
Y1069000D01*
G01X595376Y444033D02*
X594231Y442888D01*
X591938D01*
X591390Y443436D01*
X590163Y446398D01*
X590353Y446856D01*
X589701Y448427D01*
X589244Y448617D01*
X588594Y450187D01*
X588783Y450644D01*
X588132Y452216D01*
X587675Y452405D01*
X586929Y454206D01*
X587173Y454794D01*
X586427Y456597D01*
X585838Y456840D01*
X585092Y458641D01*
X585336Y459229D01*
X584590Y461032D01*
X584001Y461275D01*
X583255Y463076D01*
X583499Y463664D01*
X582753Y465467D01*
X582164Y465710D01*
X581418Y467511D01*
X581662Y468099D01*
X580916Y469902D01*
X580327Y470145D01*
X579581Y471946D01*
X579875Y472654D01*
X579199Y474288D01*
X578490Y474580D01*
X577744Y476381D01*
X578038Y477089D01*
X577362Y478723D01*
X576653Y479015D01*
X575475Y481859D01*
X564415Y518317D01*
Y541617D01*
X574487Y565931D01*
X577365Y624515D01*
X579635Y635928D01*
X716795Y1041134D01*
Y1069000D01*
G01X605778Y476499D02*
X604633Y477644D01*
X592713D01*
X585956Y484401D01*
X570925Y520689D01*
Y540359D01*
X580941Y564540D01*
X583814Y622993D01*
X586215Y635063D01*
X723165Y1039639D01*
Y1069000D01*
G01X595376Y469387D02*
X594231Y470532D01*
X591267D01*
X584251Y477548D01*
X567115Y518918D01*
Y541152D01*
X577184Y565461D01*
X580062Y623985D01*
X582370Y635587D01*
X719425Y1040479D01*
Y1068787D01*
G01X595376Y472787D02*
X594231Y471642D01*
X591727D01*
X589488Y473881D01*
Y474517D01*
X588144Y475861D01*
X587508D01*
X585193Y478177D01*
X584320Y480284D01*
X584536Y480806D01*
X583809Y482563D01*
X583286Y482779D01*
X582559Y484534D01*
X582776Y485056D01*
X582049Y486813D01*
X581525Y487029D01*
X581526D01*
X580799Y488784D01*
X581016Y489306D01*
X580289Y491063D01*
X579765Y491279D01*
X579038Y493034D01*
X579255Y493556D01*
X578528Y495313D01*
X578004Y495529D01*
X578005D01*
X577278Y497284D01*
X577495Y497806D01*
X576768Y499563D01*
X576244Y499779D01*
Y499780D01*
X575517Y501535D01*
X575734Y502057D01*
X575007Y503814D01*
X574483Y504030D01*
Y504031D01*
X573756Y505786D01*
X573973Y506308D01*
X573246Y508065D01*
X572722Y508281D01*
X572723D01*
X571906Y510254D01*
X572123Y510776D01*
X571395Y512533D01*
X570872Y512749D01*
X568225Y519139D01*
Y540931D01*
X578284Y565214D01*
X581167Y623849D01*
X583445Y635300D01*
X720535Y1040296D01*
Y1068787D01*
G01X605778Y479899D02*
X604633Y478754D01*
X601577D01*
X601227Y479104D01*
X599627D01*
X599277Y478754D01*
X597677D01*
X597327Y479104D01*
X595727D01*
X595377Y478754D01*
X593173D01*
X586897Y485030D01*
X586151Y486831D01*
X586395Y487419D01*
X585649Y489222D01*
X585060Y489465D01*
X584314Y491266D01*
X584558Y491854D01*
X583812Y493657D01*
X583223Y493900D01*
X582477Y495701D01*
X582721Y496289D01*
X581975Y498092D01*
X581386Y498335D01*
X580640Y500136D01*
X580884Y500724D01*
X580138Y502527D01*
X579549Y502770D01*
X578803Y504571D01*
X579047Y505159D01*
X578301Y506962D01*
X577712Y507205D01*
X576966Y509006D01*
X577210Y509594D01*
X576464Y511397D01*
X575875Y511640D01*
X575129Y513441D01*
X575317Y513893D01*
X574490Y515888D01*
X574038Y516075D01*
X572035Y520910D01*
Y540138D01*
X582041Y564293D01*
X584919Y622857D01*
X587290Y634776D01*
X724275Y1039456D01*
Y1069000D01*
G01X595376Y483560D02*
X594231Y484705D01*
X591267D01*
X589842Y486130D01*
X574735Y522603D01*
Y539435D01*
X584858Y563873D01*
X587737Y622383D01*
X590290Y635219D01*
X726906Y1038803D01*
Y1068787D01*
G01X595376Y486960D02*
X594231Y485815D01*
X591727D01*
X590783Y486759D01*
X589848Y489017D01*
X590092Y489605D01*
X589365Y491361D01*
X588776Y491605D01*
X588049Y493360D01*
X588293Y493948D01*
X587566Y495704D01*
X586977Y495948D01*
X586250Y497703D01*
X586494Y498291D01*
X585767Y500047D01*
X585178Y500291D01*
Y500292D01*
X584451Y502047D01*
X584695Y502635D01*
X583968Y504391D01*
X583379Y504635D01*
X582652Y506390D01*
X582896Y506978D01*
X582169Y508734D01*
X581580Y508978D01*
X580853Y510733D01*
X581097Y511321D01*
X580370Y513077D01*
X579781Y513321D01*
Y513322D01*
X578760Y515788D01*
X579004Y516376D01*
X578276Y518132D01*
X577687Y518375D01*
X577688D01*
X575845Y522824D01*
Y539214D01*
X585958Y563626D01*
X588842Y622247D01*
X589904Y627587D01*
X590375Y627902D01*
X590746Y629766D01*
X590431Y630236D01*
X591365Y634931D01*
X728016Y1038620D01*
Y1068787D01*
G01X605778Y490673D02*
X604633Y491818D01*
X601939D01*
X597913Y495844D01*
X581817Y519932D01*
X578545Y527833D01*
Y538703D01*
X588694Y563204D01*
X591468Y619589D01*
X594952Y637107D01*
X730646Y1037965D01*
Y1069000D01*
G01X595376Y513521D02*
X594231Y514666D01*
X591693D01*
X590511Y515298D01*
X589538Y516755D01*
X589537D01*
X586349Y521527D01*
X586348D01*
X583441Y525880D01*
X582355Y528502D01*
Y535633D01*
X592600Y560368D01*
X595554Y620421D01*
X598726Y636375D01*
X734386Y1037127D01*
Y1068787D01*
G01X605778Y494073D02*
X604633Y492928D01*
X602399D01*
X598775Y496552D01*
X595985Y500728D01*
X596081Y501214D01*
X595136Y502628D01*
X594650Y502725D01*
X593596Y504303D01*
X593693Y504788D01*
X592747Y506203D01*
X592262Y506299D01*
X591179Y507920D01*
X591303Y508544D01*
X590219Y510166D01*
X589595Y510291D01*
X588512Y511912D01*
X588636Y512536D01*
X587552Y514158D01*
X586928Y514282D01*
X585845Y515903D01*
X585969Y516527D01*
X584885Y518149D01*
X584261Y518273D01*
X582801Y520458D01*
X579655Y528054D01*
Y538482D01*
X589794Y562957D01*
X591190Y591341D01*
X592573Y619453D01*
X596027Y636820D01*
X731756Y1037782D01*
Y1049675D01*
X732306Y1050225D01*
Y1051975D01*
X731756Y1052525D01*
Y1054475D01*
X732306Y1055025D01*
Y1056775D01*
X731756Y1057325D01*
Y1059275D01*
X732306Y1059825D01*
Y1061575D01*
X731756Y1062125D01*
Y1069000D01*
G01X595376Y516921D02*
X594231Y515776D01*
X591972D01*
X591280Y516146D01*
X590461Y517372D01*
X590585Y517996D01*
X589528Y519577D01*
X588904Y519701D01*
X587849Y521280D01*
X587973Y521905D01*
X586917Y523485D01*
X586293Y523610D01*
X584425Y526406D01*
X583465Y528723D01*
Y535412D01*
X584192Y537167D01*
X584781Y537410D01*
X585508Y539167D01*
X585264Y539755D01*
X585991Y541510D01*
X586580Y541753D01*
X587307Y543510D01*
X587063Y544098D01*
X587790Y545853D01*
X588379Y546096D01*
X589106Y547853D01*
X588862Y548441D01*
X589589Y550196D01*
X590177Y550439D01*
X590904Y552196D01*
X590661Y552784D01*
X591387Y554539D01*
X591976Y554783D01*
X592703Y556539D01*
X592460Y557127D01*
X593700Y560121D01*
X596659Y620285D01*
X597030Y622148D01*
X597029D01*
X597559Y622502D01*
X597930Y624366D01*
X597576Y624895D01*
X598688Y630491D01*
X599801Y636088D01*
X735496Y1036944D01*
Y1068787D01*
G01X605778Y520633D02*
X604633Y521778D01*
X595801D01*
X591615Y523512D01*
X587161Y527966D01*
X586117Y530486D01*
Y533582D01*
X596346Y558273D01*
X599231Y616915D01*
X603605Y638902D01*
X738126Y1036289D01*
Y1069000D01*
G01X605778Y524033D02*
X604633Y522888D01*
X601027D01*
X600577Y523338D01*
X598677D01*
X598227Y522888D01*
X596022D01*
X592244Y524453D01*
X588102Y528595D01*
X587227Y530707D01*
Y533361D01*
X592627Y546394D01*
X593216Y546638D01*
X593962Y548440D01*
X593718Y549028D01*
X594464Y550829D01*
X595053Y551072D01*
X595799Y552875D01*
X595556Y553463D01*
X597446Y558026D01*
X597541Y559973D01*
X598014Y560400D01*
X598110Y562349D01*
X597682Y562821D01*
X597777Y564768D01*
X598250Y565195D01*
X598346Y567144D01*
X597918Y567616D01*
X598013Y569563D01*
X598486Y569990D01*
X598582Y571939D01*
X598154Y572411D01*
X598249Y574358D01*
X598722Y574785D01*
X598818Y576734D01*
X598390Y577206D01*
X598485Y579153D01*
X598958Y579581D01*
X599054Y581529D01*
X598626Y582001D01*
X600336Y616779D01*
X604680Y638615D01*
X739236Y1036106D01*
Y1069000D01*
G01X605778Y534806D02*
X604634Y535950D01*
Y535951D01*
X601775D01*
X600227Y537499D01*
Y540270D01*
X605102Y545145D01*
X606770Y549172D01*
X642616Y729659D01*
X745606Y1033900D01*
Y1069000D01*
G01X742975Y1068787D02*
Y1035224D01*
X636699Y721272D01*
X608467Y579149D01*
X608820Y578619D01*
X608440Y576706D01*
X607910Y576352D01*
X607531Y574440D01*
X607884Y573910D01*
X607505Y571997D01*
X606974Y571643D01*
X606595Y569731D01*
X606948Y569202D01*
X606569Y567289D01*
X606038Y566935D01*
X605659Y565023D01*
X606012Y564494D01*
X605633Y562581D01*
X605102Y562227D01*
X604723Y560315D01*
X605077Y559786D01*
X604697Y557873D01*
X604166Y557519D01*
X603787Y555607D01*
X604141Y555078D01*
X603761Y553165D01*
X603230Y552811D01*
X602851Y550899D01*
X601334Y547238D01*
X597469Y543373D01*
Y542737D01*
X596124Y541392D01*
X595488D01*
X594145Y540049D01*
X592835Y536888D01*
X593079Y536300D01*
X592352Y534543D01*
X591763Y534300D01*
Y534299D01*
X591036Y532547D01*
Y531545D01*
X591352Y530783D01*
X592186Y529949D01*
X594231D01*
X595376Y531094D01*
G01Y527694D02*
X594231Y528839D01*
X591726D01*
X590411Y530154D01*
X589926Y531324D01*
Y532768D01*
X593204Y540678D01*
X600393Y547867D01*
X601783Y551223D01*
X635624Y721559D01*
X741865Y1035407D01*
Y1068787D01*
G01X605778Y538206D02*
X604634Y537062D01*
Y537061D01*
X602235D01*
X601337Y537959D01*
Y539810D01*
X602790Y541263D01*
X603355D01*
X604700Y542607D01*
Y543173D01*
X606043Y544516D01*
X607838Y548848D01*
X608245Y550899D01*
X608716Y551213D01*
X609086Y553078D01*
X608772Y553548D01*
X609151Y555460D01*
X609681Y555814D01*
X610061Y557728D01*
X609708Y558257D01*
X610087Y560169D01*
X610617Y560523D01*
X610997Y562437D01*
X610644Y562966D01*
X611023Y564878D01*
X611553Y565232D01*
X611933Y567146D01*
X611579Y567675D01*
X611958Y569587D01*
X612488Y569941D01*
X612868Y571855D01*
X612514Y572384D01*
X612893Y574296D01*
X613423Y574650D01*
X613803Y576564D01*
X613449Y577093D01*
X613828Y579005D01*
X614358Y579359D01*
X614738Y581273D01*
X614385Y581802D01*
X614764Y583714D01*
X615088Y583930D01*
X615536Y586188D01*
X615320Y586511D01*
X643691Y729372D01*
X746716Y1033717D01*
Y1069000D01*
G01X597446Y1214897D02*
X594875D01*
X593494Y1215469D01*
X591131Y1217832D01*
X589614Y1221487D01*
X588797Y1233382D01*
X589494Y1243350D01*
X593044Y1258066D01*
X613675Y1410840D01*
X632589Y1453769D01*
X633042Y1455918D01*
Y1504588D01*
X630941Y1506689D01*
X630067D01*
X629567Y1506189D01*
Y1504685D01*
G01X599645Y1223485D02*
X595470Y1227660D01*
Y1236225D01*
X595070Y1236625D01*
Y1238575D01*
X595470Y1238975D01*
Y1240925D01*
X595070Y1241325D01*
Y1243275D01*
X595470Y1243675D01*
Y1247314D01*
X617435Y1409973D01*
X619454Y1414559D01*
X631808Y1434887D01*
X631692Y1435364D01*
X632761Y1437122D01*
X633238Y1437238D01*
X634250Y1438904D01*
X634115Y1439454D01*
X635129Y1441121D01*
X635679Y1441255D01*
X636691Y1442921D01*
X636557Y1443470D01*
X637571Y1445138D01*
X638121Y1445272D01*
X640469Y1449136D01*
X640470Y1449139D01*
X641153Y1450946D01*
X641156Y1450953D01*
X641150Y1450955D01*
X641153Y1450962D01*
X641673Y1453473D01*
Y1508947D01*
X639666Y1510954D01*
X638728D01*
X638228Y1510454D01*
Y1509016D01*
G01X597446Y1216007D02*
X595096D01*
X594123Y1216410D01*
X592072Y1218461D01*
X590710Y1221745D01*
X590479Y1225113D01*
X590851Y1225539D01*
X590717Y1227486D01*
X590289Y1227857D01*
X589910Y1233381D01*
X590214Y1237734D01*
X590642Y1238105D01*
X590778Y1240052D01*
X590407Y1240478D01*
X590595Y1243180D01*
X591216Y1245754D01*
X591699Y1246049D01*
X592157Y1247945D01*
X591861Y1248428D01*
X594137Y1257861D01*
X614755Y1410536D01*
X633652Y1453427D01*
X634152Y1455802D01*
Y1505048D01*
X631401Y1507799D01*
X630067D01*
X629567Y1508299D01*
Y1509804D01*
G01X600430Y1224270D02*
X596580Y1228120D01*
Y1247239D01*
X618515Y1409669D01*
X620441Y1414044D01*
X641474Y1448652D01*
X642192Y1450553D01*
X642195Y1450560D01*
X642205Y1450564D01*
X642783Y1453359D01*
Y1509407D01*
X640126Y1512064D01*
X638728D01*
X638228Y1512564D01*
Y1514134D01*
G01X646890Y1504685D02*
Y1506189D01*
X647390Y1506689D01*
X648264D01*
X650365Y1504588D01*
Y1450078D01*
X649793Y1448372D01*
X647585Y1445443D01*
X646955Y1445354D01*
X645781Y1443796D01*
X645869Y1443166D01*
X644696Y1441609D01*
X644066Y1441521D01*
X642891Y1439962D01*
X642980Y1439332D01*
X641807Y1437775D01*
X641177Y1437687D01*
X640002Y1436128D01*
X640091Y1435498D01*
X638918Y1433941D01*
X638288Y1433853D01*
X637113Y1432294D01*
X637202Y1431664D01*
X636029Y1430107D01*
X635399Y1430019D01*
X634224Y1428460D01*
X634313Y1427830D01*
X633140Y1426273D01*
X632650Y1426204D01*
X631475Y1424646D01*
X631544Y1424156D01*
X622776Y1412523D01*
X621169Y1408871D01*
X603480Y1277879D01*
Y1255712D01*
G01X646890Y1509804D02*
Y1508299D01*
X647390Y1507799D01*
X648724D01*
X651475Y1505048D01*
Y1449897D01*
X650789Y1447848D01*
X623741Y1411957D01*
X622249Y1408567D01*
X604590Y1277804D01*
Y1255712D01*
G01X672874Y1509016D02*
Y1510520D01*
X673374Y1511020D01*
X674246D01*
X676319Y1508947D01*
Y1454453D01*
X675291Y1449566D01*
X671913Y1441888D01*
X671319Y1441657D01*
X670534Y1439871D01*
X670764Y1439278D01*
X658033Y1410341D01*
Y1342104D01*
X616282Y1269991D01*
X614701Y1264100D01*
Y1259412D01*
G01X681535Y1504685D02*
Y1506190D01*
X682035Y1506690D01*
X682908D01*
X684980Y1504618D01*
Y1455542D01*
X683146Y1445045D01*
X680862Y1438707D01*
X680414Y1438496D01*
X679751Y1436661D01*
X679962Y1436213D01*
X679301Y1434379D01*
X678853Y1434168D01*
X678191Y1432333D01*
X678402Y1431885D01*
X677741Y1430051D01*
X677293Y1429840D01*
X676631Y1428005D01*
X676842Y1427557D01*
X670273Y1409332D01*
Y1342121D01*
X620017Y1268213D01*
X618442Y1263095D01*
Y1259412D01*
G01X619552D02*
Y1262928D01*
X621029Y1267727D01*
X671383Y1341779D01*
Y1409138D01*
X684223Y1444759D01*
X686090Y1455445D01*
Y1505078D01*
X683368Y1507800D01*
X682035D01*
X681535Y1508300D01*
Y1509804D01*
G01X608331Y1259412D02*
Y1265412D01*
X609755Y1278671D01*
X634663Y1393340D01*
Y1408839D01*
X635071Y1410263D01*
Y1410264D01*
X658727Y1448224D01*
Y1448225D01*
X660106Y1453158D01*
Y1509407D01*
X657383Y1512130D01*
X656051D01*
X655551Y1512630D01*
Y1514134D01*
G01X664213Y1509804D02*
Y1508300D01*
X664713Y1507800D01*
X666046D01*
X668768Y1505078D01*
Y1455052D01*
X667076Y1448226D01*
X647420Y1411031D01*
X646903Y1408945D01*
Y1368936D01*
X644105Y1353614D01*
X613534Y1272708D01*
X612072Y1264704D01*
Y1259612D01*
G01X615811Y1259412D02*
Y1263953D01*
X617317Y1269561D01*
X659143Y1341805D01*
Y1410107D01*
X676354Y1449224D01*
X677429Y1454337D01*
Y1509407D01*
X674706Y1512130D01*
X673374D01*
X672874Y1512630D01*
Y1514134D01*
G01X664213Y1504685D02*
Y1506190D01*
X664713Y1506690D01*
X665586D01*
X667658Y1504618D01*
Y1455188D01*
X666031Y1448625D01*
X661183Y1439450D01*
X660710Y1439304D01*
X659798Y1437579D01*
X659943Y1437106D01*
X659032Y1435382D01*
X658559Y1435236D01*
X657647Y1433511D01*
X657793Y1433038D01*
X656882Y1431314D01*
X656409Y1431168D01*
X655497Y1429443D01*
X655643Y1428970D01*
X646375Y1411430D01*
X645793Y1409081D01*
Y1369037D01*
X643031Y1353912D01*
X612460Y1273006D01*
X610962Y1264805D01*
Y1259612D01*
G01X655551Y1509016D02*
Y1510520D01*
X656051Y1511020D01*
X656923D01*
X658996Y1508947D01*
Y1453311D01*
X657700Y1448677D01*
X652539Y1440395D01*
X651919Y1440251D01*
X650887Y1438595D01*
X651031Y1437975D01*
X634046Y1410719D01*
X633553Y1408995D01*
Y1393460D01*
X608657Y1278849D01*
X607221Y1265472D01*
Y1259412D01*
G01X623291Y1259312D02*
Y1262036D01*
X624257Y1264726D01*
X648925Y1294644D01*
X683623Y1346046D01*
Y1410190D01*
X693919Y1447555D01*
X694752Y1453711D01*
Y1509407D01*
X692029Y1512130D01*
X690697D01*
X690197Y1512630D01*
Y1514134D01*
G01Y1509016D02*
Y1510520D01*
X690697Y1511020D01*
X691569D01*
X693642Y1508947D01*
Y1453786D01*
X692829Y1447778D01*
X690362Y1438824D01*
X689808Y1438510D01*
X689290Y1436629D01*
X689604Y1436075D01*
X682513Y1410341D01*
Y1346386D01*
X648034Y1295310D01*
X623277Y1265283D01*
X622181Y1262230D01*
Y1259312D01*
G01X788481Y614511D02*
X789626Y613366D01*
X792024D01*
X793210Y614552D01*
Y616125D01*
X791341Y619362D01*
X790863Y619491D01*
X789887Y621180D01*
X790015Y621658D01*
X789041Y623346D01*
X788562Y623474D01*
X787586Y625164D01*
X787715Y625642D01*
X759888Y673843D01*
X753910Y696149D01*
X753901Y696247D01*
X753902D01*
X738897Y867757D01*
X742378Y907543D01*
X752789Y1026550D01*
Y1052825D01*
X749347Y1061137D01*
Y1068787D01*
G01X788481Y611111D02*
X789626Y612256D01*
X792484D01*
X794320Y614092D01*
Y616423D01*
X760923Y674272D01*
X755008Y696343D01*
X740012Y867757D01*
X753899Y1026501D01*
Y1053046D01*
X750457Y1061358D01*
Y1068787D01*
G01X778079Y607399D02*
X779224Y606254D01*
X791027D01*
X796012Y611239D01*
X797013Y613656D01*
Y617166D01*
X764272Y673877D01*
X758334Y696041D01*
X758136Y698312D01*
X757647Y698721D01*
X757482Y700615D01*
X757891Y701103D01*
X757709Y703184D01*
X757221Y703593D01*
X757055Y705487D01*
X757464Y705974D01*
X757465Y705975D01*
X743023Y871062D01*
X756599Y1026297D01*
Y1053560D01*
X753087Y1062041D01*
Y1069000D01*
G01X778079Y603999D02*
X779224Y605144D01*
X791487D01*
X796953Y610610D01*
X798123Y613435D01*
Y617464D01*
X765307Y674305D01*
Y674306D01*
X759432Y696234D01*
X758693Y704681D01*
X758572Y706072D01*
X758571D01*
X744138Y871062D01*
X757709Y1026248D01*
Y1053781D01*
X756071Y1057737D01*
X756234Y1058129D01*
X755486Y1059932D01*
X755095Y1060094D01*
X754197Y1062262D01*
Y1069000D01*
G01X788481Y600338D02*
X789626Y599193D01*
X792251D01*
X793648Y600590D01*
X794536Y601920D01*
X794426Y602475D01*
X795316Y603806D01*
X795871Y603916D01*
X795870D01*
X796759Y605246D01*
X796648Y605801D01*
X797538Y607132D01*
X798093Y607242D01*
X799299Y609047D01*
X800823Y612727D01*
Y618203D01*
X767868Y675288D01*
X762140Y696663D01*
X746841Y871505D01*
X760409Y1026626D01*
Y1054295D01*
X756827Y1062945D01*
Y1068787D01*
G01X788481Y596938D02*
X789626Y598083D01*
X792711D01*
X794510Y599882D01*
X800283Y608521D01*
X801933Y612506D01*
Y618501D01*
X768903Y675717D01*
X763238Y696857D01*
X747956Y871505D01*
X761519Y1026577D01*
Y1054516D01*
X757937Y1063166D01*
Y1068787D01*
G01X778079Y593225D02*
X779224Y592080D01*
X788646D01*
X793531Y594104D01*
X796217Y596790D01*
X802690Y606476D01*
X804633Y611169D01*
Y619456D01*
X772139Y675744D01*
X766389Y697198D01*
X766241Y698891D01*
X765753Y699300D01*
X765605Y700995D01*
X766014Y701482D01*
X758455Y787890D01*
X750886Y874399D01*
X764219Y1026889D01*
Y1055421D01*
X762289Y1060081D01*
X761897Y1060243D01*
X761150Y1062046D01*
X761313Y1062438D01*
X760567Y1064239D01*
Y1069000D01*
G01X778079Y589825D02*
X779224Y590970D01*
X788867D01*
X794160Y593163D01*
X797079Y596082D01*
X803674Y605950D01*
X805743Y610948D01*
Y619754D01*
X773174Y676173D01*
X767487Y697392D01*
X752001Y874399D01*
X765329Y1026840D01*
Y1055642D01*
X761677Y1064460D01*
Y1069000D01*
G01X788481Y586165D02*
X789626Y585020D01*
X792335D01*
X793716Y586401D01*
Y586967D01*
X795060Y588311D01*
X795626D01*
X797931Y590616D01*
X799637Y593170D01*
X799527Y593725D01*
X800583Y595306D01*
X801138Y595416D01*
X804095Y599841D01*
X808427Y610298D01*
Y620818D01*
X775582Y677715D01*
X770181Y697852D01*
X762451Y786194D01*
X762452D01*
X754723Y874535D01*
X768029Y1026725D01*
Y1057444D01*
X764307Y1066431D01*
Y1068787D01*
G01X788481Y582765D02*
X789626Y583910D01*
X792795D01*
X798793Y589908D01*
X801805Y594415D01*
X801806Y594416D01*
X805079Y599315D01*
X809537Y610077D01*
Y621116D01*
X776617Y678144D01*
X771279Y698046D01*
X755838Y874535D01*
X769139Y1026676D01*
Y1057665D01*
X765417Y1066652D01*
Y1068787D01*
G01X778079Y579052D02*
X779224Y577907D01*
X787569D01*
X794810Y580906D01*
X800053Y586149D01*
X801136Y587770D01*
X801039Y588255D01*
X802124Y589878D01*
X802609Y589974D01*
X803692Y591595D01*
X803595Y592080D01*
X804679Y593703D01*
X805165Y593799D01*
X806603Y595952D01*
X812253Y609593D01*
Y621812D01*
X779181Y679103D01*
X773916Y698740D01*
X773907Y698838D01*
X773908D01*
X758531Y874406D01*
X771839Y1026635D01*
Y1058163D01*
X768047Y1067320D01*
Y1069000D01*
G01X778079Y575652D02*
X779224Y576797D01*
X787909D01*
X787993Y576881D01*
X795439Y579965D01*
X800976Y585502D01*
Y585532D01*
X807587Y595426D01*
X813363Y609372D01*
Y622110D01*
X780216Y679532D01*
X775014Y698934D01*
X759646Y874406D01*
X772949Y1026586D01*
Y1058384D01*
X769157Y1067541D01*
Y1069000D01*
G01X788481Y571991D02*
X789626Y570846D01*
X791953D01*
X793861Y572754D01*
Y573292D01*
X795135Y574566D01*
X795673D01*
X796945Y575838D01*
Y576376D01*
X798219Y577649D01*
X798756D01*
X800034Y578927D01*
X809589Y593227D01*
X816063Y608855D01*
Y622832D01*
X782739Y680562D01*
X777637Y699586D01*
X762411Y873440D01*
X775649Y1024910D01*
Y1058792D01*
X771788Y1068115D01*
Y1068787D01*
G01X788481Y568591D02*
X789626Y569736D01*
X792413D01*
X800896Y578219D01*
X810573Y592701D01*
X817173Y608634D01*
Y623130D01*
X783774Y680991D01*
X778735Y699780D01*
X763526Y873440D01*
X776759Y1024861D01*
Y1059013D01*
X772898Y1068336D01*
Y1068787D01*
G01X778079Y564879D02*
X779224Y563734D01*
X781096D01*
X783111Y562900D01*
X786169D01*
X787970Y563646D01*
X788159Y564103D01*
X789962Y564850D01*
X790419Y564661D01*
X792755Y565628D01*
X797112Y569985D01*
Y570480D01*
X798492Y571860D01*
X798987D01*
X800365Y573238D01*
Y573733D01*
X801745Y575113D01*
X802240D01*
X803820Y576693D01*
Y577188D01*
X805199Y578567D01*
X805694D01*
X806589Y579462D01*
X807672Y581083D01*
X807576Y581568D01*
X808660Y583190D01*
X809146Y583287D01*
X809145D01*
X810863Y585857D01*
X811609Y587658D01*
X811419Y588115D01*
X812167Y589918D01*
X812624Y590107D01*
X812623D01*
X819873Y607609D01*
Y623783D01*
X786384Y681801D01*
X781569Y699759D01*
X773937Y786981D01*
X773938D01*
X766307Y874202D01*
X779459Y1024728D01*
Y1028410D01*
X783009Y1064457D01*
Y1069988D01*
G01X788481Y488591D02*
X789626Y489736D01*
X792234D01*
X793553Y491055D01*
X794373Y493034D01*
X795396Y498182D01*
X804936Y520809D01*
X806817Y522691D01*
X840033Y602884D01*
Y628282D01*
X839431Y630535D01*
X805344Y689602D01*
X801466Y704057D01*
X786722Y872552D01*
X796608Y985792D01*
X837003Y1046243D01*
X840562Y1054836D01*
X841308Y1063397D01*
X842062Y1072056D01*
X837190Y1083818D01*
X802648Y1118360D01*
X792649Y1122502D01*
X787377D01*
G01X778079Y529013D02*
X779224Y527868D01*
X782254D01*
X782674Y528288D01*
X784474D01*
X784894Y527868D01*
X786693D01*
X788356Y528557D01*
Y528556D01*
X788584Y529106D01*
X790248Y529795D01*
X790797Y529568D01*
X793524Y530697D01*
X796288Y533461D01*
X796976Y535123D01*
X796749Y535672D01*
X797438Y537336D01*
X797988Y537564D01*
X797987D01*
X798675Y539226D01*
X798459Y539749D01*
X799148Y541413D01*
X799671Y541630D01*
X800359Y543292D01*
X800143Y543815D01*
X800832Y545479D01*
X801355Y545696D01*
X802043Y547358D01*
X801827Y547881D01*
X802516Y549545D01*
X803040Y549761D01*
X803728Y551423D01*
X803512Y551946D01*
X804201Y553610D01*
X804724Y553827D01*
X812003Y571399D01*
X813811Y573207D01*
X827493Y606239D01*
Y625678D01*
X793726Y684180D01*
X789113Y701382D01*
X774133Y872601D01*
X774141Y872697D01*
X774142D01*
X784411Y990264D01*
X805397Y1021671D01*
X826162Y1052748D01*
X828403Y1058159D01*
X829360Y1069080D01*
X826475Y1077006D01*
X795625Y1107856D01*
X790030Y1110173D01*
X787471D01*
G01X788481Y491991D02*
X789626Y490846D01*
X791774D01*
X792612Y491684D01*
X793305Y493358D01*
X794329Y498509D01*
X795028Y500167D01*
X794815Y500691D01*
X795514Y502351D01*
X796039Y502564D01*
X796038D01*
X796737Y504222D01*
X796738D01*
X796525Y504746D01*
X797224Y506406D01*
X797749Y506619D01*
X797748D01*
X798447Y508277D01*
X798448D01*
X798235Y508801D01*
X798934Y510461D01*
X799459Y510674D01*
X799458Y510675D01*
X800157Y512333D01*
X799944Y512857D01*
X800643Y514517D01*
X801168Y514730D01*
X801867Y516388D01*
X801654Y516912D01*
X802353Y518572D01*
X802878Y518785D01*
X803997Y521440D01*
X805876Y523320D01*
X806585Y525034D01*
X806369Y525556D01*
X807058Y527220D01*
X807581Y527437D01*
X808269Y529099D01*
X808053Y529622D01*
X808742Y531286D01*
X809265Y531503D01*
X838923Y603105D01*
Y628136D01*
X838396Y630107D01*
X804309Y689173D01*
X800368Y703863D01*
X785607Y872552D01*
X795526Y986172D01*
X836019Y1046769D01*
X839471Y1055103D01*
X840932Y1071882D01*
X836249Y1083189D01*
X802019Y1117419D01*
X792428Y1121392D01*
X787377D01*
G01X778079Y525613D02*
X779224Y526758D01*
X786915D01*
X794153Y529756D01*
X797229Y532832D01*
X812944Y570770D01*
X814752Y572578D01*
X828603Y606018D01*
Y625976D01*
X794761Y684609D01*
X790211Y701576D01*
X775248Y872601D01*
X785493Y989884D01*
X827146Y1052222D01*
X829494Y1057892D01*
X830488Y1069229D01*
X827434Y1077617D01*
X796254Y1108797D01*
X790251Y1111283D01*
X787471D01*
G01X788481Y518552D02*
X789626Y519697D01*
X792395D01*
X799187Y526489D01*
X816961Y569398D01*
X818494Y570931D01*
X832413Y604535D01*
Y627276D01*
X798336Y686323D01*
X793948Y702686D01*
X779079Y872648D01*
X789186Y988378D01*
X830408Y1050070D01*
X833171Y1056742D01*
X834408Y1070875D01*
X830809Y1079561D01*
X798385Y1111985D01*
X791054Y1115022D01*
X787377D01*
G01X788481Y521952D02*
X789626Y520807D01*
X791935D01*
X793858Y522730D01*
Y523295D01*
X795132Y524569D01*
X795697D01*
X798246Y527118D01*
X799543Y530251D01*
X799327Y530774D01*
X800016Y532438D01*
X800539Y532654D01*
X801227Y534316D01*
X801011Y534839D01*
X801700Y536503D01*
X802223Y536720D01*
X802911Y538382D01*
X802695Y538905D01*
X803384Y540569D01*
X803907Y540786D01*
X804595Y542448D01*
X804379Y542971D01*
X805068Y544635D01*
X805591Y544852D01*
X806279Y546514D01*
X806063Y547037D01*
X806752Y548701D01*
X807275Y548918D01*
X807963Y550580D01*
X807747Y551103D01*
X808436Y552767D01*
X808960Y552983D01*
X816020Y570027D01*
X817553Y571560D01*
X817552D01*
X831303Y604756D01*
Y626978D01*
X797301Y685894D01*
X792850Y702492D01*
X777964Y872648D01*
X788104Y988758D01*
X829424Y1050596D01*
X832080Y1057009D01*
X833278Y1070701D01*
X829868Y1078932D01*
X797756Y1111044D01*
X790833Y1113912D01*
X787377D01*
G01X778079Y514839D02*
X779224Y513694D01*
X782827D01*
X783227Y514094D01*
X785027D01*
X785427Y513694D01*
X788599D01*
X792393Y515266D01*
X794007Y516880D01*
Y517446D01*
X795281Y518720D01*
X795847D01*
X797119Y519992D01*
Y520558D01*
X798393Y521832D01*
X798959D01*
X801824Y524697D01*
X802512Y526359D01*
X802296Y526882D01*
X802985Y528546D01*
X803508Y528763D01*
X804196Y530425D01*
X803980Y530948D01*
X804669Y532612D01*
X805192Y532829D01*
X805880Y534491D01*
X805664Y535014D01*
X806353Y536678D01*
X806876Y536895D01*
X807564Y538557D01*
X807348Y539080D01*
X808037Y540744D01*
X808560Y540961D01*
X820029Y568647D01*
X820707Y569325D01*
X835113Y604104D01*
Y627633D01*
X834876Y628520D01*
X800749Y687653D01*
X796572Y703234D01*
X781770Y872414D01*
X786787Y929871D01*
X791819Y987513D01*
X832732Y1048745D01*
X835778Y1056100D01*
X837105Y1071289D01*
X833056Y1081063D01*
X799887Y1114232D01*
X791629Y1117653D01*
X787471D01*
G01X778079Y511439D02*
X779224Y512584D01*
X788820D01*
X793022Y514325D01*
X802765Y524068D01*
X820970Y568018D01*
X821648Y568696D01*
X836223Y603883D01*
Y627779D01*
X835911Y628948D01*
X801784Y688082D01*
X797670Y703428D01*
X782885Y872414D01*
X792901Y987133D01*
X833716Y1048219D01*
X836869Y1055833D01*
X838235Y1071463D01*
X833997Y1081692D01*
X800516Y1115173D01*
X791850Y1118763D01*
X787471D01*
G01X788481Y477818D02*
X789626Y476673D01*
X791799D01*
X793569Y478443D01*
Y479009D01*
X794843Y480283D01*
X795409D01*
X796681Y481555D01*
X797369Y483217D01*
X797153Y483740D01*
X797842Y485404D01*
X798365Y485621D01*
X801307Y492725D01*
X801091Y493247D01*
X801780Y494911D01*
X802304Y495128D01*
X802303D01*
X802991Y496790D01*
X802775Y497313D01*
X803464Y498977D01*
X803988Y499193D01*
X803987D01*
X804675Y500855D01*
X804676D01*
X804460Y501378D01*
X805149Y503042D01*
X805672Y503259D01*
X806360Y504921D01*
X806144Y505444D01*
X806833Y507108D01*
X807356Y507325D01*
X808044Y508987D01*
X807828Y509510D01*
X808517Y511174D01*
X809041Y511390D01*
X809040D01*
X811602Y517574D01*
X812667Y518639D01*
X812666D01*
X846543Y600423D01*
Y629142D01*
X845514Y632993D01*
X811565Y691823D01*
X807979Y705187D01*
X793343Y872486D01*
X793351Y872582D01*
X793352D01*
X803003Y983177D01*
X842005Y1041544D01*
X844433Y1047405D01*
X846861Y1053265D01*
X848593Y1073044D01*
X842627Y1087449D01*
X806283Y1123793D01*
X794020Y1128873D01*
X787377D01*
G01X778079Y467306D02*
X779224Y468451D01*
X788669D01*
X800259Y476194D01*
X816266Y514839D01*
X817508Y516081D01*
X851463Y598053D01*
Y629791D01*
X850084Y634953D01*
X816336Y693438D01*
X812996Y705678D01*
X798341Y873173D01*
X807790Y981454D01*
X846258Y1039020D01*
X848948Y1045514D01*
X851661Y1052063D01*
X852603Y1062886D01*
X853553Y1073807D01*
X846758Y1090207D01*
X809043Y1127922D01*
X795035Y1133724D01*
X787471D01*
G01X788481Y474418D02*
X789626Y475563D01*
X792259D01*
X797622Y480926D01*
X812543Y516945D01*
X813608Y518010D01*
X847653Y600202D01*
Y629288D01*
X846549Y633421D01*
X812600Y692252D01*
X809077Y705381D01*
X794458Y872486D01*
X804085Y982797D01*
X842989Y1041018D01*
X847952Y1052998D01*
X849723Y1073218D01*
X843568Y1088078D01*
X806912Y1124734D01*
X794241Y1129983D01*
X787377D01*
G01X778079Y481479D02*
X779224Y482624D01*
X790621D01*
X796685Y488688D01*
X798040Y491960D01*
X798493Y494233D01*
X808583Y518586D01*
X810584Y520587D01*
X843843Y600879D01*
Y628785D01*
X842967Y632064D01*
X808926Y691052D01*
X805348Y704390D01*
X790618Y872745D01*
X800361Y984369D01*
X840060Y1043779D01*
X844256Y1053910D01*
X845896Y1072630D01*
X840377Y1085950D01*
X804780Y1121547D01*
X793442Y1126244D01*
X787471D01*
G01X778079Y470706D02*
X779224Y469561D01*
X783931D01*
X784331Y469961D01*
X786131D01*
X786531Y469561D01*
X788331D01*
X795198Y474148D01*
X795309Y474703D01*
X796806Y475704D01*
X797361Y475594D01*
X799362Y476930D01*
X800349Y479314D01*
X800133Y479837D01*
X800822Y481501D01*
X801345Y481717D01*
X802033Y483380D01*
X801817Y483902D01*
X802506Y485566D01*
X803029Y485783D01*
X803717Y487446D01*
X803501Y487968D01*
X804190Y489632D01*
X804713Y489849D01*
X805401Y491511D01*
X805185Y492034D01*
X805874Y493698D01*
X806397Y493915D01*
X807455Y496470D01*
X807239Y496993D01*
X807928Y498657D01*
X808451Y498874D01*
X815325Y515468D01*
X816567Y516710D01*
X850353Y598274D01*
Y629645D01*
X849049Y634525D01*
X815303Y693007D01*
X811898Y705482D01*
X797226Y873173D01*
X806708Y981834D01*
X845274Y1039546D01*
X850570Y1052330D01*
X852423Y1073633D01*
X845817Y1089578D01*
X808414Y1126981D01*
X794814Y1132614D01*
X787471D01*
G01X778079Y484879D02*
X779224Y483734D01*
X785227D01*
X785627Y484134D01*
X787427D01*
X787827Y483734D01*
X790161D01*
X795744Y489317D01*
X796972Y492284D01*
X797425Y494557D01*
X798179Y496378D01*
X797963Y496900D01*
X798652Y498564D01*
X799175Y498781D01*
X799864Y500443D01*
X799647Y500966D01*
X800336Y502630D01*
X800860Y502846D01*
X801548Y504508D01*
X801332Y505031D01*
X802021Y506695D01*
X802545Y506911D01*
X802544Y506912D01*
X803233Y508574D01*
X803016Y509097D01*
X803705Y510761D01*
X804229Y510977D01*
X804228D01*
X804917Y512639D01*
X804700Y513162D01*
X805389Y514826D01*
X805913Y515042D01*
X807642Y519215D01*
X809643Y521216D01*
X810331Y522878D01*
X810115Y523401D01*
X810804Y525065D01*
X811327Y525282D01*
X842733Y601100D01*
Y628639D01*
X841932Y631636D01*
X807891Y690623D01*
X804250Y704196D01*
X789503Y872745D01*
X789511Y872841D01*
X789512D01*
X799279Y984749D01*
X839076Y1044305D01*
X843165Y1054177D01*
X844766Y1072456D01*
X839436Y1085321D01*
X804151Y1120606D01*
X793221Y1125134D01*
X787471D01*
G01X778079Y561479D02*
X779224Y562624D01*
X780875D01*
X782890Y561790D01*
X786390D01*
X793384Y564687D01*
X807451Y578754D01*
X811847Y585331D01*
X820983Y607388D01*
Y624081D01*
X787419Y682230D01*
X782667Y699953D01*
X767422Y874202D01*
X780569Y1024679D01*
Y1028355D01*
X784119Y1064402D01*
Y1069988D01*
G01X788481Y536125D02*
X789626Y534980D01*
X791907D01*
X792607Y535680D01*
X793704Y538329D01*
X793477Y538877D01*
X794165Y540541D01*
X794715Y540769D01*
X795458Y542565D01*
X795231Y543113D01*
X795920Y544777D01*
X796470Y545005D01*
X796469D01*
X797157Y546667D01*
X796930Y547216D01*
X797619Y548880D01*
X798169Y549107D01*
X798168D01*
X798856Y550769D01*
X798629Y551318D01*
X799318Y552982D01*
X799868Y553209D01*
X799867D01*
X800555Y554871D01*
X800328Y555420D01*
X801017Y557084D01*
X801567Y557311D01*
X802255Y558973D01*
X802028Y559522D01*
X802717Y561186D01*
X803267Y561414D01*
X803266D01*
X807960Y572745D01*
X810596Y575381D01*
X810595D01*
X823683Y606976D01*
Y624743D01*
X790074Y682973D01*
X787693Y691849D01*
X787694D01*
X786522Y696217D01*
X786521D01*
X785935Y698401D01*
X785936D01*
X785326Y700678D01*
X770307Y872367D01*
X778929Y971071D01*
X778930D01*
X787539Y1069620D01*
X787057Y1091637D01*
X784271Y1097285D01*
X783351Y1098206D01*
G01X788481Y532725D02*
X789626Y533870D01*
X792367D01*
X793548Y535051D01*
X808901Y572116D01*
X811537Y574752D01*
X824793Y606755D01*
Y625041D01*
X791109Y683402D01*
X786424Y700872D01*
X771422Y872367D01*
X780036Y970970D01*
X780037D01*
X788651Y1069584D01*
X788162Y1091908D01*
X785186Y1097940D01*
X784136Y1098991D01*
G01X1062865Y391001D02*
X1061720Y392146D01*
X1056916D01*
X1047152Y396191D01*
X1025069Y418274D01*
Y418394D01*
X1017017Y437833D01*
X993721Y514625D01*
Y547811D01*
X1003958Y572527D01*
X1006752Y629432D01*
X1008975Y640608D01*
X1146590Y1047181D01*
Y1068787D01*
G01X1062865Y394401D02*
X1061720Y393256D01*
X1057142D01*
X1055382Y393984D01*
X1055139Y394573D01*
X1053382Y395300D01*
X1052794Y395056D01*
X1047781Y397132D01*
X1045553Y399360D01*
Y399996D01*
X1044209Y401340D01*
X1043573D01*
X1042230Y402683D01*
Y403319D01*
X1040885Y404664D01*
X1040249D01*
X1038906Y406007D01*
Y406643D01*
X1037561Y407988D01*
X1036925D01*
X1035582Y409331D01*
Y409967D01*
X1034237Y411312D01*
X1033601D01*
X1032258Y412655D01*
Y413291D01*
X1030913Y414636D01*
X1030277D01*
X1026095Y418818D01*
X1025029Y421393D01*
X1025272Y421981D01*
X1024526Y423784D01*
X1023937Y424027D01*
X1023191Y425828D01*
X1023435Y426416D01*
X1022689Y428219D01*
X1022100Y428462D01*
X1018064Y438208D01*
X994831Y514790D01*
Y547590D01*
X1005058Y572280D01*
X1007857Y629296D01*
X1010050Y640321D01*
X1147700Y1046998D01*
Y1068787D01*
G01X1054863Y398113D02*
X1053718Y399258D01*
X1051735D01*
X1048918Y400425D01*
X1028763Y420580D01*
Y420700D01*
X1018999Y444270D01*
X997531Y515040D01*
Y546772D01*
X1007716Y571364D01*
X1010532Y628652D01*
X1012785Y639981D01*
X1150330Y1046343D01*
Y1069000D01*
G01X1155180Y1068787D02*
Y1045321D01*
X1017671Y639068D01*
X1015404Y627671D01*
X1012582Y570275D01*
X1002451Y545817D01*
Y515712D01*
X1022036Y451153D01*
X1026909Y439386D01*
X1027498Y439143D01*
X1028244Y437340D01*
X1028000Y436752D01*
X1028746Y434951D01*
X1029335Y434708D01*
X1030081Y432905D01*
X1029837Y432317D01*
X1030583Y430516D01*
X1031172Y430272D01*
X1031918Y428470D01*
X1031674Y427882D01*
X1033047Y424567D01*
X1036984Y420630D01*
X1037620D01*
X1038965Y419285D01*
Y418649D01*
X1040308Y417306D01*
X1040944D01*
X1042289Y415961D01*
Y415325D01*
X1043632Y413982D01*
X1044268D01*
X1045613Y412637D01*
Y412001D01*
X1046956Y410658D01*
X1050088Y409361D01*
X1050676Y409604D01*
X1052432Y408877D01*
X1052676Y408288D01*
Y408290D01*
X1054751Y407429D01*
X1056324D01*
X1056774Y407879D01*
X1058674D01*
X1059124Y407429D01*
X1061720D01*
X1062865Y408574D01*
G01X1151440Y1069000D02*
Y1046160D01*
X1013860Y639694D01*
X1011637Y628516D01*
X1008816Y571117D01*
X998641Y546551D01*
Y515205D01*
X1020046Y444645D01*
X1021934Y440087D01*
X1022456Y439870D01*
X1023204Y438068D01*
X1022987Y437545D01*
X1023733Y435744D01*
X1024255Y435527D01*
X1025003Y433725D01*
X1024786Y433202D01*
X1025532Y431401D01*
X1026054Y431184D01*
X1026802Y429382D01*
X1026585Y428859D01*
X1027331Y427058D01*
Y427057D01*
X1027854Y426841D01*
X1028601Y425038D01*
X1028384Y424516D01*
X1029789Y421124D01*
X1032589Y418324D01*
X1033155D01*
X1034535Y416944D01*
Y416378D01*
X1035913Y415000D01*
X1036479D01*
X1037859Y413620D01*
Y413054D01*
X1039237Y411676D01*
X1039803D01*
X1041183Y410296D01*
Y409730D01*
X1042561Y408352D01*
X1043055D01*
X1044400Y407008D01*
Y406513D01*
X1045743Y405170D01*
X1046238D01*
X1047583Y403825D01*
Y403330D01*
X1049547Y401366D01*
X1051956Y400368D01*
X1053718D01*
X1054863Y401513D01*
G01X1062865Y405174D02*
X1061720Y406319D01*
X1054530D01*
X1050087Y408159D01*
X1050088D01*
X1046327Y409717D01*
X1032106Y423938D01*
X1020989Y450778D01*
X1001341Y515547D01*
Y546038D01*
X1011482Y570522D01*
X1013593Y613445D01*
X1014299Y627807D01*
X1016596Y639355D01*
X1154070Y1045504D01*
Y1068787D01*
G01X1052463Y412287D02*
X1051318Y413432D01*
X1048711D01*
X1036056Y426087D01*
X1036054D01*
X1022473Y458882D01*
X1005151Y515982D01*
Y545170D01*
X1015239Y569524D01*
X1016645Y598173D01*
Y598172D01*
X1017347Y612461D01*
X1018052Y626823D01*
X1020440Y638828D01*
X1157810Y1044666D01*
Y1069000D01*
G01X1052463Y415687D02*
X1051318Y414542D01*
X1049171D01*
X1047793Y415920D01*
Y416557D01*
X1046413Y417937D01*
X1045776D01*
X1044398Y419315D01*
Y419952D01*
X1043018Y421332D01*
X1042381D01*
X1041003Y422710D01*
Y423276D01*
X1039623Y424656D01*
X1039057D01*
X1036997Y426716D01*
X1036996D01*
X1035610Y430062D01*
X1035854Y430650D01*
X1035108Y432453D01*
X1034519Y432696D01*
X1033773Y434497D01*
X1034017Y435085D01*
X1033271Y436888D01*
X1032682Y437131D01*
X1032683D01*
X1031937Y438932D01*
X1031936D01*
X1032180Y439520D01*
X1031434Y441323D01*
X1030845Y441566D01*
X1030846D01*
X1030100Y443367D01*
X1030344Y443955D01*
X1029598Y445758D01*
X1029009Y446001D01*
X1028263Y447802D01*
X1028507Y448390D01*
X1027761Y450193D01*
X1027172Y450436D01*
X1027173D01*
X1023520Y459257D01*
X1006261Y516147D01*
Y544949D01*
X1016339Y569277D01*
X1019157Y626687D01*
X1021515Y638541D01*
X1158920Y1044483D01*
Y1069000D01*
G01X1162661Y1068787D02*
Y1043647D01*
X1025291Y637812D01*
X1023085Y626721D01*
X1020228Y568606D01*
X1010071Y544086D01*
Y516592D01*
X1025751Y464898D01*
X1027937Y459619D01*
X1028526Y459375D01*
X1029253Y457619D01*
X1029009Y457031D01*
X1030097Y454404D01*
X1030686Y454160D01*
X1031413Y452404D01*
X1031169Y451816D01*
X1031896Y450061D01*
X1032485Y449817D01*
X1033212Y448061D01*
X1032968Y447473D01*
X1033695Y445718D01*
X1034283Y445475D01*
X1035011Y443719D01*
X1034767Y443131D01*
X1035505Y441348D01*
X1036094Y441104D01*
X1036821Y439348D01*
X1036577Y438760D01*
X1037304Y437005D01*
X1037893Y436761D01*
X1038620Y435005D01*
X1038376Y434417D01*
X1039422Y431891D01*
X1043063Y428250D01*
X1043699D01*
X1045044Y426905D01*
Y426269D01*
X1046387Y424926D01*
X1054412Y421602D01*
X1056313D01*
X1056763Y422052D01*
X1058663D01*
X1059113Y421602D01*
X1061720D01*
X1062865Y422747D01*
G01Y419347D02*
X1061720Y420492D01*
X1054191D01*
X1045758Y423985D01*
X1038481Y431262D01*
X1024704Y464523D01*
X1008961Y516427D01*
Y544307D01*
X1019128Y568853D01*
X1021980Y626857D01*
X1024216Y638099D01*
X1161551Y1043830D01*
Y1068787D01*
G01X1052463Y426460D02*
X1051318Y427605D01*
X1048237D01*
X1041920Y433922D01*
Y434042D01*
X1026849Y470424D01*
X1012771Y516838D01*
Y543414D01*
X1022884Y567830D01*
X1025025Y611407D01*
X1025742Y625988D01*
X1028026Y637471D01*
X1165291Y1042992D01*
Y1069000D01*
G01X1170141Y1068787D02*
Y1041971D01*
X1032909Y636554D01*
X1030685Y625372D01*
X1029252Y596195D01*
Y596194D01*
X1027807Y566744D01*
X1017691Y542325D01*
Y517690D01*
X1030337Y476008D01*
X1034623Y465659D01*
Y465657D01*
X1035212Y465413D01*
X1035939Y463657D01*
X1035696Y463069D01*
X1036422Y461314D01*
X1037011Y461070D01*
X1037738Y459314D01*
X1037494Y458726D01*
X1038221Y456971D01*
X1038220D01*
X1038809Y456727D01*
X1039536Y454971D01*
X1039293Y454383D01*
X1040019Y452628D01*
X1040608Y452384D01*
X1041335Y450628D01*
X1041092Y450040D01*
X1041818Y448285D01*
Y448284D01*
X1042407Y448040D01*
X1043134Y446284D01*
X1042891Y445696D01*
X1043617Y443941D01*
Y443940D01*
X1044206Y443696D01*
X1044933Y441940D01*
X1044690Y441352D01*
X1045416Y439597D01*
X1046291Y438722D01*
X1049059Y437575D01*
X1049647Y437819D01*
X1051404Y437092D01*
X1051647Y436503D01*
X1053402Y435776D01*
X1056613D01*
X1057063Y436226D01*
X1058963D01*
X1059413Y435776D01*
X1061720D01*
X1062865Y436921D01*
G01X1169031Y1068787D02*
Y1042154D01*
X1031834Y636841D01*
X1029580Y625508D01*
X1028859Y610837D01*
X1026707Y566991D01*
X1016581Y542546D01*
Y517525D01*
X1029290Y475633D01*
X1044475Y438968D01*
X1045662Y437781D01*
X1049059Y436373D01*
X1049060D01*
X1053181Y434666D01*
X1061720D01*
X1062865Y433521D01*
G01X1166401Y1069000D02*
Y1060475D01*
X1166801Y1060075D01*
Y1058125D01*
X1166401Y1057725D01*
Y1042809D01*
X1029101Y637184D01*
X1026847Y625852D01*
X1023984Y567583D01*
X1013881Y543193D01*
Y517003D01*
X1027896Y470799D01*
X1030201Y465234D01*
X1030593Y465072D01*
X1031340Y463269D01*
X1031177Y462877D01*
X1031923Y461076D01*
X1032512Y460833D01*
X1033259Y459030D01*
X1033015Y458442D01*
X1033761Y456641D01*
X1034349Y456398D01*
X1035096Y454595D01*
X1034852Y454007D01*
X1035598Y452206D01*
X1036186Y451963D01*
X1036933Y450160D01*
X1036689Y449572D01*
X1037435Y447771D01*
X1038024Y447528D01*
X1038770Y445725D01*
X1038526Y445137D01*
X1039272Y443336D01*
X1039861Y443093D01*
X1040607Y441290D01*
X1040363Y440702D01*
X1041109Y438901D01*
X1041698Y438658D01*
X1042444Y436855D01*
X1042200Y436267D01*
X1042946Y434466D01*
X1045543Y431869D01*
X1046009D01*
X1047354Y430525D01*
Y430058D01*
X1048697Y428715D01*
X1051318D01*
X1052463Y429860D01*
G01X1172771Y1069000D02*
Y1041317D01*
X1035646Y636215D01*
X1033346Y624651D01*
X1031909Y595413D01*
Y595414D01*
X1030473Y566178D01*
X1020391Y541838D01*
Y518152D01*
X1031514Y481484D01*
X1047535Y442807D01*
X1048564Y441778D01*
X1051318D01*
X1052463Y440633D01*
G01Y444033D02*
X1051318Y442888D01*
X1049024D01*
X1048476Y443436D01*
X1047494Y445807D01*
X1047738Y446395D01*
X1046992Y448198D01*
X1046403Y448441D01*
X1045657Y450242D01*
X1045901Y450830D01*
X1045155Y452633D01*
X1044566Y452876D01*
X1043820Y454677D01*
X1044064Y455265D01*
X1043318Y457068D01*
X1042729Y457311D01*
X1041983Y459112D01*
X1042227Y459700D01*
X1041481Y461503D01*
X1040892Y461746D01*
X1040146Y463547D01*
X1040390Y464135D01*
X1039644Y465938D01*
X1039055Y466181D01*
X1038309Y467982D01*
X1038553Y468570D01*
X1037807Y470373D01*
X1037218Y470616D01*
X1036472Y472417D01*
X1036716Y473005D01*
X1035970Y474808D01*
X1035381Y475051D01*
X1034635Y476852D01*
X1034879Y477440D01*
X1034133Y479243D01*
X1033544Y479486D01*
X1032561Y481859D01*
X1021501Y518317D01*
Y541617D01*
X1031573Y565931D01*
X1034451Y624515D01*
X1036721Y635928D01*
X1173881Y1041134D01*
Y1069000D01*
G01X1176511Y1068787D02*
Y1040479D01*
X1039456Y635587D01*
X1037148Y623985D01*
X1034270Y565461D01*
X1024201Y541152D01*
Y519159D01*
X1041508Y477377D01*
X1048353Y470532D01*
X1051318D01*
X1052463Y469387D01*
G01X1177621Y1068787D02*
Y1040296D01*
X1040531Y635300D01*
X1038253Y623849D01*
X1036818Y594668D01*
X1035370Y565214D01*
X1025311Y540931D01*
Y519380D01*
X1028058Y512749D01*
X1028581Y512533D01*
X1029309Y510776D01*
X1029092Y510254D01*
X1029909Y508281D01*
X1029908D01*
X1030432Y508065D01*
X1031159Y506308D01*
X1030942Y505786D01*
X1031669Y504031D01*
Y504030D01*
X1032193Y503814D01*
X1032920Y502057D01*
X1032703Y501535D01*
X1033430Y499780D01*
Y499779D01*
X1033954Y499563D01*
X1034681Y497806D01*
X1034464Y497284D01*
X1035191Y495529D01*
X1035190D01*
X1035714Y495313D01*
X1036441Y493556D01*
X1036224Y493034D01*
X1036951Y491279D01*
X1037475Y491063D01*
X1038202Y489306D01*
X1037985Y488784D01*
X1038712Y487029D01*
X1038711D01*
X1039235Y486813D01*
X1039962Y485056D01*
X1039745Y484534D01*
X1040472Y482779D01*
X1040995Y482563D01*
X1041722Y480806D01*
X1041506Y480284D01*
X1042449Y478006D01*
X1044594Y475861D01*
X1045230D01*
X1046574Y474517D01*
Y473881D01*
X1048813Y471642D01*
X1051318D01*
X1052463Y472787D01*
G01X1062865Y476499D02*
X1061720Y477644D01*
X1049359D01*
X1043550Y483453D01*
X1028011Y520968D01*
Y540359D01*
X1038027Y564540D01*
X1040900Y622993D01*
X1043301Y635063D01*
X1180251Y1039639D01*
Y1069000D01*
G01X1181361D02*
Y1039456D01*
X1044376Y634776D01*
X1042005Y622857D01*
X1039127Y564293D01*
X1029121Y540138D01*
Y521189D01*
X1031527Y515381D01*
Y515380D01*
X1031984Y515191D01*
X1032732Y513388D01*
X1032542Y512931D01*
X1033288Y511130D01*
X1033287D01*
X1033744Y510941D01*
X1034492Y509138D01*
X1034302Y508681D01*
X1035048Y506880D01*
Y506879D01*
X1035505Y506690D01*
X1036253Y504887D01*
X1036063Y504430D01*
X1036809Y502629D01*
Y502628D01*
X1037266Y502439D01*
X1038014Y500636D01*
X1037824Y500179D01*
X1038570Y498378D01*
X1038569D01*
X1039026Y498189D01*
X1039774Y496386D01*
X1039584Y495929D01*
X1040330Y494128D01*
Y494127D01*
X1040787Y493938D01*
X1041535Y492135D01*
X1041345Y491678D01*
X1042091Y489877D01*
Y489876D01*
X1042548Y489687D01*
X1043295Y487885D01*
X1043106Y487427D01*
X1044491Y484082D01*
X1045950Y482623D01*
X1046516D01*
X1047896Y481243D01*
Y480677D01*
X1049819Y478754D01*
X1052463D01*
X1052813Y479104D01*
X1054413D01*
X1054763Y478754D01*
X1056363D01*
X1056713Y479104D01*
X1058313D01*
X1058663Y478754D01*
X1061720D01*
X1062865Y479899D01*
G01X1052463Y486960D02*
X1051318Y485815D01*
X1048813D01*
X1047869Y486759D01*
X1046934Y489017D01*
X1047178Y489605D01*
X1046451Y491361D01*
X1045862Y491605D01*
X1045135Y493360D01*
X1045379Y493948D01*
X1044652Y495704D01*
X1044063Y495948D01*
X1043336Y497703D01*
X1043580Y498291D01*
X1042853Y500047D01*
X1042264Y500291D01*
Y500292D01*
X1041537Y502047D01*
X1041781Y502635D01*
X1041054Y504391D01*
X1040465Y504635D01*
X1039738Y506390D01*
X1039982Y506978D01*
X1039255Y508734D01*
X1038666Y508978D01*
X1037939Y510733D01*
X1038183Y511321D01*
X1037456Y513077D01*
X1036867Y513321D01*
Y513322D01*
X1035846Y515788D01*
X1036090Y516376D01*
X1035362Y518132D01*
X1034773Y518375D01*
X1034774D01*
X1033853Y520599D01*
X1033854D01*
X1032931Y522824D01*
Y539217D01*
X1043044Y563630D01*
X1045928Y622247D01*
X1046990Y627587D01*
X1047461Y627902D01*
X1047832Y629766D01*
X1047517Y630236D01*
X1048451Y634931D01*
X1185102Y1038620D01*
Y1068787D01*
G01X1052463Y483560D02*
X1051318Y484705D01*
X1048353D01*
X1046928Y486130D01*
X1031821Y522603D01*
Y539438D01*
X1041944Y563877D01*
X1044823Y622383D01*
X1047376Y635219D01*
X1183992Y1038803D01*
Y1068787D01*
G01X1191472D02*
Y1037127D01*
X1055812Y636375D01*
X1052640Y620421D01*
X1049686Y560368D01*
X1039441Y535633D01*
Y528502D01*
X1040527Y525880D01*
X1043434Y521527D01*
X1043435D01*
X1046623Y516755D01*
X1046624D01*
X1047597Y515298D01*
X1048779Y514666D01*
X1051318D01*
X1052463Y513521D01*
G01X1062865Y494073D02*
X1061720Y492928D01*
X1059485D01*
X1055861Y496552D01*
X1053071Y500728D01*
X1053167Y501214D01*
X1052222Y502628D01*
X1051736Y502725D01*
X1050682Y504303D01*
X1050779Y504788D01*
X1049833Y506203D01*
X1049348Y506299D01*
X1048265Y507920D01*
X1048389Y508544D01*
X1047305Y510166D01*
X1046681Y510291D01*
X1045598Y511912D01*
X1045722Y512536D01*
X1044638Y514158D01*
X1044014Y514282D01*
X1042931Y515903D01*
X1043055Y516527D01*
X1041971Y518149D01*
X1041347Y518273D01*
X1039887Y520458D01*
X1036741Y528054D01*
Y538482D01*
X1038149Y541881D01*
X1038738Y542125D01*
X1039484Y543927D01*
X1039241Y544515D01*
X1039987Y546316D01*
X1040576Y546560D01*
X1041322Y548362D01*
X1041078Y548950D01*
X1041824Y550751D01*
X1042413Y550995D01*
X1043159Y552797D01*
X1042915Y553385D01*
X1043661Y555186D01*
X1044118Y555375D01*
X1044865Y557178D01*
X1044676Y557635D01*
X1046880Y562957D01*
X1048276Y591341D01*
X1049659Y619453D01*
X1053113Y636820D01*
X1188842Y1037782D01*
Y1069000D01*
G01X1187732D02*
Y1037965D01*
X1052038Y637107D01*
X1048554Y619589D01*
X1045780Y563204D01*
X1035631Y538703D01*
Y527833D01*
X1038903Y519932D01*
X1054999Y495844D01*
X1059025Y491818D01*
X1061720D01*
X1062865Y490673D01*
G01X1192582Y1068787D02*
Y1036944D01*
X1056887Y636088D01*
X1055774Y630491D01*
X1054662Y624895D01*
X1055016Y624366D01*
X1054645Y622502D01*
X1054115Y622148D01*
X1054116D01*
X1053745Y620285D01*
X1050786Y560121D01*
X1049546Y557127D01*
X1049789Y556539D01*
X1049062Y554783D01*
X1048473Y554539D01*
X1047747Y552784D01*
X1047990Y552196D01*
X1047263Y550439D01*
X1046675Y550196D01*
X1045948Y548441D01*
X1046192Y547853D01*
X1045465Y546096D01*
X1044876Y545853D01*
X1044149Y544098D01*
X1044393Y543510D01*
X1043666Y541753D01*
X1043077Y541510D01*
X1042350Y539755D01*
X1042594Y539167D01*
X1041867Y537410D01*
X1041278Y537167D01*
X1040551Y535412D01*
Y528723D01*
X1041511Y526406D01*
X1043379Y523610D01*
X1044003Y523485D01*
X1045059Y521905D01*
X1044935Y521280D01*
X1045990Y519701D01*
X1046614Y519577D01*
X1047671Y517996D01*
X1047547Y517372D01*
X1048366Y516146D01*
X1049058Y515776D01*
X1051318D01*
X1052463Y516921D01*
G01X1195212Y1069000D02*
Y1036289D01*
X1060691Y638902D01*
X1056317Y616915D01*
X1053432Y558273D01*
X1043203Y533582D01*
Y530486D01*
X1044247Y527966D01*
X1048701Y523512D01*
X1052887Y521778D01*
X1061720D01*
X1062865Y520633D01*
G01X1196322Y1069000D02*
Y1036106D01*
X1061766Y638615D01*
X1057422Y616779D01*
X1055900Y585821D01*
X1056328Y585349D01*
X1056232Y583401D01*
X1055759Y582973D01*
X1055664Y581026D01*
X1056092Y580554D01*
X1055996Y578606D01*
X1055523Y578178D01*
X1055428Y576231D01*
X1055856Y575759D01*
X1055760Y573810D01*
X1055287Y573383D01*
X1055192Y571436D01*
X1055620Y570965D01*
X1055524Y569016D01*
X1055051Y568589D01*
X1054951Y566538D01*
X1055379Y566067D01*
X1055283Y564118D01*
X1054810Y563691D01*
X1054532Y558026D01*
X1052037Y552002D01*
X1052280Y551414D01*
X1051534Y549612D01*
X1050945Y549368D01*
X1050199Y547567D01*
X1050442Y546979D01*
X1049696Y545176D01*
X1049107Y544933D01*
X1044313Y533361D01*
Y530707D01*
X1045188Y528595D01*
X1049330Y524453D01*
X1053108Y522888D01*
X1055313D01*
X1055763Y523338D01*
X1057663D01*
X1058113Y522888D01*
X1061720D01*
X1062865Y524033D01*
G01X1052463Y531094D02*
X1051318Y529949D01*
X1049273D01*
X1048439Y530783D01*
X1048123Y531545D01*
Y532547D01*
X1048850Y534299D01*
Y534300D01*
X1049439Y534543D01*
X1050166Y536300D01*
X1049922Y536888D01*
X1051232Y540049D01*
X1052575Y541392D01*
X1053211D01*
X1054556Y542737D01*
Y543373D01*
X1058421Y547238D01*
X1059938Y550899D01*
X1060317Y552811D01*
X1060848Y553165D01*
X1061228Y555078D01*
X1060874Y555607D01*
X1061253Y557519D01*
X1061784Y557873D01*
X1062164Y559786D01*
X1061810Y560315D01*
X1062189Y562227D01*
X1062720Y562581D01*
X1063099Y564494D01*
X1062746Y565023D01*
X1063125Y566935D01*
X1063656Y567289D01*
X1064035Y569202D01*
X1063682Y569731D01*
X1064061Y571643D01*
X1064592Y571997D01*
X1064971Y573910D01*
X1064618Y574440D01*
X1064997Y576352D01*
X1065527Y576706D01*
X1065907Y578619D01*
X1065554Y579149D01*
X1093786Y721272D01*
X1200062Y1035224D01*
Y1068787D01*
G01X1202692Y1069000D02*
Y1033900D01*
X1099702Y729659D01*
X1063856Y549172D01*
X1062188Y545145D01*
X1057313Y540270D01*
Y537499D01*
X1058861Y535951D01*
X1061720D01*
X1062865Y534806D01*
G01X1203802Y1069000D02*
Y1033717D01*
X1100777Y729372D01*
X1072289Y585917D01*
X1072643Y585388D01*
X1072263Y583474D01*
X1071733Y583120D01*
X1071354Y581208D01*
X1071668Y580738D01*
X1071289Y578825D01*
X1070817Y578510D01*
X1070438Y576598D01*
X1070752Y576128D01*
X1070373Y574215D01*
X1069901Y573900D01*
X1069522Y571988D01*
X1069836Y571518D01*
X1069457Y569605D01*
X1068985Y569290D01*
X1068606Y567378D01*
X1068920Y566908D01*
X1068541Y564995D01*
X1068069Y564680D01*
X1067690Y562768D01*
X1068004Y562298D01*
X1067625Y560385D01*
X1067153Y560070D01*
X1066774Y558158D01*
X1067088Y557688D01*
X1066709Y555775D01*
X1066237Y555460D01*
X1065858Y553548D01*
X1066172Y553078D01*
X1065802Y551213D01*
X1065331Y550899D01*
X1064924Y548848D01*
X1063129Y544516D01*
X1061786Y543173D01*
Y542607D01*
X1060441Y541263D01*
X1059876D01*
X1058423Y539810D01*
Y537959D01*
X1059321Y537061D01*
X1061720D01*
X1062865Y538206D01*
G01X1198952Y1068787D02*
Y1035407D01*
X1092711Y721559D01*
X1058870Y551223D01*
X1057480Y547867D01*
X1050291Y540678D01*
X1047013Y532768D01*
Y531324D01*
X1047498Y530154D01*
X1048813Y528839D01*
X1051318D01*
X1052463Y527694D01*
G01X1322402Y1473977D02*
Y1475481D01*
X1322902Y1475981D01*
X1324596D01*
X1325725Y1474852D01*
Y1454012D01*
X1324966Y1450602D01*
X1322720Y1449181D01*
X1322099Y1449320D01*
X1320450Y1448276D01*
X1320310Y1447656D01*
X1318663Y1446614D01*
X1318042Y1446753D01*
X1316393Y1445709D01*
X1316254Y1445088D01*
X1313815Y1443545D01*
X1306346Y1440607D01*
X1305892Y1440805D01*
X1304077Y1440090D01*
X1303879Y1439636D01*
X1302065Y1438923D01*
X1301611Y1439120D01*
X1299795Y1438405D01*
X1299598Y1437952D01*
X1297784Y1437239D01*
X1297330Y1437436D01*
X1295514Y1436721D01*
X1295317Y1436268D01*
X1241813Y1415221D01*
X1238695Y1412165D01*
X1188912Y1339449D01*
X1139114Y1300404D01*
X1122526Y1283816D01*
X1120409Y1278705D01*
Y1259512D01*
G01X1313740Y1478308D02*
Y1479812D01*
X1314240Y1480312D01*
X1315934D01*
X1317063Y1479183D01*
Y1453424D01*
X1315298Y1450059D01*
X1310668Y1446732D01*
X1301109Y1443047D01*
X1300592Y1443276D01*
X1298772Y1442575D01*
X1298542Y1442057D01*
X1296723Y1441356D01*
X1296206Y1441585D01*
X1294385Y1440884D01*
X1294156Y1440366D01*
X1240820Y1419803D01*
X1236349Y1415427D01*
X1185774Y1341957D01*
X1132716Y1300155D01*
X1121027Y1288615D01*
X1119399Y1286215D01*
X1116668Y1279618D01*
Y1259512D01*
G01X1313740Y1483426D02*
Y1481922D01*
X1314240Y1481422D01*
X1316394D01*
X1318173Y1479643D01*
Y1453150D01*
X1316160Y1449310D01*
X1311201Y1445747D01*
X1241433Y1418849D01*
X1237203Y1414708D01*
X1186593Y1341189D01*
X1133452Y1299321D01*
X1127215Y1293164D01*
X1127212Y1292669D01*
X1125824Y1291298D01*
X1125329Y1291301D01*
X1121885Y1287901D01*
X1120382Y1285685D01*
X1117778Y1279397D01*
Y1259512D01*
G01X1322402Y1479095D02*
Y1477591D01*
X1322902Y1477091D01*
X1325056D01*
X1326835Y1475312D01*
Y1453890D01*
X1325950Y1449910D01*
X1314320Y1442550D01*
X1242430Y1414270D01*
X1239550Y1411448D01*
X1189732Y1338680D01*
X1183512Y1333803D01*
X1183452Y1333312D01*
X1181917Y1332108D01*
X1181425Y1332167D01*
X1139852Y1299572D01*
X1123467Y1283187D01*
X1121519Y1278484D01*
Y1259512D01*
G01X1305079Y1473977D02*
Y1475481D01*
X1305579Y1475981D01*
X1307273D01*
X1308402Y1474852D01*
Y1453757D01*
X1306699Y1450546D01*
X1305179Y1449438D01*
X1293120Y1444822D01*
X1292668Y1445024D01*
X1290845Y1444326D01*
X1290644Y1443874D01*
X1288823Y1443177D01*
X1288371Y1443379D01*
X1286549Y1442681D01*
X1286347Y1442229D01*
X1284526Y1441532D01*
X1284074Y1441734D01*
X1282252Y1441036D01*
X1282050Y1440584D01*
X1282049Y1440585D01*
X1280229Y1439888D01*
Y1439887D01*
X1279777Y1440089D01*
X1277955Y1439391D01*
X1277753Y1438939D01*
Y1438940D01*
X1275932Y1438243D01*
Y1438242D01*
X1275480Y1438444D01*
X1273658Y1437746D01*
X1273456Y1437294D01*
X1273455Y1437295D01*
X1239831Y1424424D01*
X1233449Y1417926D01*
X1182948Y1344720D01*
X1126728Y1300293D01*
X1118389Y1292033D01*
X1115676Y1287976D01*
X1112929Y1281344D01*
Y1259512D01*
G01X1305079Y1479095D02*
Y1477591D01*
X1305579Y1477091D01*
X1307733D01*
X1309512Y1475312D01*
Y1453480D01*
X1307560Y1449800D01*
X1305714Y1448454D01*
X1240454Y1423473D01*
X1234309Y1417216D01*
X1183767Y1343952D01*
X1127466Y1299460D01*
X1124813Y1296833D01*
X1124811Y1296267D01*
X1123424Y1294894D01*
X1122858Y1294897D01*
X1119250Y1291323D01*
X1116660Y1287450D01*
X1114039Y1281123D01*
Y1259512D01*
G01X1331063Y1483426D02*
Y1481922D01*
X1331563Y1481422D01*
X1333717D01*
X1335496Y1479643D01*
Y1452290D01*
X1333440Y1449230D01*
X1319680Y1440310D01*
X1253620Y1413590D01*
X1250941Y1410911D01*
Y1347400D01*
X1249095Y1343531D01*
X1162786Y1309650D01*
X1141505Y1295715D01*
X1126792Y1281002D01*
X1125258Y1277298D01*
Y1259512D01*
G01X1365709Y1483426D02*
Y1481922D01*
X1366209Y1481422D01*
X1368363D01*
X1370142Y1479643D01*
Y1452630D01*
X1368964Y1450617D01*
X1348310Y1435380D01*
X1301040Y1412600D01*
X1299901Y1411461D01*
Y1346944D01*
X1296983Y1341821D01*
X1182240Y1299194D01*
Y1299195D01*
X1182063Y1298809D01*
X1180234Y1298129D01*
X1179848Y1298306D01*
Y1298305D01*
X1166015Y1293167D01*
X1151701Y1283981D01*
X1140600Y1272880D01*
X1140220Y1271962D01*
Y1259512D01*
G01X1357047Y1473977D02*
Y1475481D01*
X1357547Y1475981D01*
X1359241D01*
X1360370Y1474852D01*
Y1452903D01*
X1359555Y1451345D01*
X1352825Y1446661D01*
X1352407Y1446735D01*
X1350806Y1445620D01*
X1350731Y1445203D01*
X1349131Y1444089D01*
X1348713Y1444164D01*
X1347112Y1443049D01*
X1347037Y1442632D01*
X1345437Y1441518D01*
X1345019Y1441593D01*
X1343418Y1440478D01*
X1343343Y1440061D01*
X1336316Y1435169D01*
X1331034Y1432789D01*
X1330637Y1432939D01*
X1328858Y1432137D01*
X1328708Y1431740D01*
X1326931Y1430939D01*
X1326534Y1431090D01*
X1324755Y1430287D01*
X1324605Y1429891D01*
X1322828Y1429090D01*
X1322431Y1429241D01*
X1320652Y1428438D01*
X1320502Y1428042D01*
X1288298Y1413528D01*
X1286551Y1411781D01*
Y1347681D01*
X1284829Y1343893D01*
X1163351Y1297627D01*
X1148782Y1288192D01*
X1136038Y1275448D01*
X1135370Y1273835D01*
Y1259512D01*
G01X1339725Y1479095D02*
Y1477591D01*
X1340225Y1477091D01*
X1342379D01*
X1344158Y1475312D01*
Y1452500D01*
X1343090Y1450458D01*
X1321730Y1436450D01*
X1265850Y1413830D01*
X1263181Y1411161D01*
Y1347860D01*
X1261441Y1343560D01*
X1173723Y1309388D01*
X1173552Y1309000D01*
X1171734Y1308291D01*
X1171346Y1308461D01*
X1162850Y1305152D01*
X1143982Y1292832D01*
X1130192Y1279042D01*
X1128999Y1276161D01*
Y1259512D01*
G01X1365709Y1478308D02*
Y1479812D01*
X1366209Y1480312D01*
X1367903D01*
X1369032Y1479183D01*
Y1452931D01*
X1368121Y1451375D01*
X1361420Y1446432D01*
X1360860Y1446516D01*
X1359290Y1445357D01*
X1359206Y1444798D01*
X1357637Y1443641D01*
X1357077Y1443725D01*
X1355507Y1442567D01*
X1355423Y1442008D01*
X1347734Y1436336D01*
X1300388Y1413518D01*
X1298791Y1411921D01*
Y1347238D01*
X1296218Y1342721D01*
X1165516Y1294166D01*
X1151001Y1284851D01*
X1139659Y1273509D01*
X1139110Y1272184D01*
Y1259512D01*
G01X1331063Y1478308D02*
Y1479812D01*
X1331563Y1480312D01*
X1333257D01*
X1334386Y1479183D01*
Y1452629D01*
X1332645Y1450038D01*
X1328826Y1447563D01*
X1328411Y1447651D01*
X1326774Y1446589D01*
X1326685Y1446175D01*
X1325049Y1445115D01*
X1324634Y1445203D01*
X1322997Y1444142D01*
X1322909Y1443727D01*
X1319165Y1441300D01*
X1252994Y1414535D01*
X1249831Y1411371D01*
Y1347652D01*
X1248281Y1344405D01*
X1162273Y1310642D01*
X1140801Y1296581D01*
X1125851Y1281631D01*
X1124148Y1277520D01*
Y1259512D01*
G01X1357047Y1479095D02*
Y1477591D01*
X1357547Y1477091D01*
X1359701D01*
X1361480Y1475312D01*
Y1452630D01*
X1360413Y1450589D01*
X1343978Y1439149D01*
Y1439150D01*
X1336866Y1434199D01*
X1288939Y1412599D01*
X1287661Y1411321D01*
Y1347440D01*
X1285651Y1343018D01*
X1174865Y1300824D01*
X1174692Y1300437D01*
X1172868Y1299742D01*
X1172481Y1299916D01*
X1163856Y1296631D01*
X1149484Y1287324D01*
X1136980Y1274819D01*
X1136480Y1273613D01*
Y1259512D01*
G01X1339725Y1473977D02*
Y1475481D01*
X1340225Y1475981D01*
X1341919D01*
X1343048Y1474852D01*
Y1452773D01*
X1342240Y1451228D01*
X1337930Y1448402D01*
X1337515Y1448488D01*
X1335884Y1447418D01*
X1335797Y1447003D01*
X1334167Y1445934D01*
X1333751Y1446020D01*
X1332120Y1444950D01*
X1332034Y1444535D01*
X1330404Y1443466D01*
X1329988Y1443552D01*
X1328357Y1442482D01*
X1328270Y1442067D01*
X1321212Y1437438D01*
X1315004Y1434925D01*
X1314613Y1435091D01*
X1312805Y1434358D01*
X1312639Y1433968D01*
X1310832Y1433237D01*
X1310441Y1433402D01*
X1308633Y1432670D01*
X1308467Y1432279D01*
X1306660Y1431548D01*
X1306269Y1431713D01*
X1304461Y1430981D01*
X1304295Y1430590D01*
X1265224Y1414775D01*
X1262071Y1411621D01*
Y1348077D01*
X1260591Y1344421D01*
X1162339Y1306145D01*
X1143278Y1293699D01*
X1129251Y1279671D01*
X1127889Y1276383D01*
Y1259512D01*
G01X1348386Y1478308D02*
Y1479812D01*
X1348886Y1480312D01*
X1350580D01*
X1351709Y1479183D01*
Y1454344D01*
X1350421Y1451128D01*
X1346247Y1448186D01*
X1345829Y1448259D01*
X1344235Y1447134D01*
X1344162Y1446716D01*
X1342569Y1445593D01*
X1342151Y1445665D01*
X1340556Y1444541D01*
X1340483Y1444123D01*
X1331305Y1437654D01*
X1276355Y1413935D01*
X1274311Y1411891D01*
Y1347790D01*
X1272808Y1344317D01*
X1161830Y1301224D01*
X1145826Y1290786D01*
X1132816Y1277776D01*
X1131629Y1274910D01*
Y1259512D01*
G01X1348386Y1483426D02*
Y1481922D01*
X1348886Y1481422D01*
X1351040D01*
X1352819Y1479643D01*
Y1454130D01*
X1351330Y1450410D01*
X1331850Y1436680D01*
X1276990Y1413000D01*
X1275421Y1411431D01*
Y1347560D01*
X1273643Y1343450D01*
X1162340Y1300231D01*
X1146529Y1289919D01*
X1133757Y1277147D01*
X1132740Y1274689D01*
X1132739Y1274688D01*
Y1259512D01*
G01X1313740Y1570434D02*
Y1568930D01*
X1314240Y1568430D01*
X1316394D01*
X1318173Y1566651D01*
Y1556673D01*
X1319555Y1553639D01*
X1324166Y1549028D01*
X1349858Y1535871D01*
X1384996Y1522734D01*
X1386357Y1521631D01*
X1386857Y1520899D01*
X1387619Y1518525D01*
X1388760Y1456464D01*
X1385671Y1450465D01*
X1363591Y1432357D01*
X1339020Y1418540D01*
X1325580Y1412550D01*
X1324381Y1411351D01*
Y1345706D01*
X1321870Y1340200D01*
X1168557Y1283679D01*
X1157840Y1276820D01*
X1153178Y1272158D01*
X1147700Y1263961D01*
Y1259512D01*
G01X1305079Y1566103D02*
Y1564599D01*
X1305579Y1564099D01*
X1306913D01*
X1307956Y1563057D01*
X1318718Y1548112D01*
X1322792Y1544037D01*
X1377413Y1517959D01*
X1378830Y1515724D01*
X1379948Y1454946D01*
X1376740Y1448700D01*
X1360898Y1435800D01*
X1323840Y1416800D01*
X1313240Y1412340D01*
X1312141Y1411241D01*
Y1346209D01*
X1311361Y1344630D01*
X1304019Y1338012D01*
X1166653Y1287035D01*
X1155445Y1279845D01*
X1148067Y1272467D01*
Y1272113D01*
X1146687Y1270733D01*
X1146333D01*
X1144801Y1269201D01*
X1143960Y1267942D01*
Y1259512D01*
G01X1322402Y1560985D02*
Y1562489D01*
X1322902Y1562989D01*
X1324596D01*
X1325725Y1561860D01*
Y1557317D01*
X1327245Y1555817D01*
X1327248Y1555322D01*
X1328638Y1553952D01*
X1329133Y1553955D01*
Y1553954D01*
X1330520Y1552585D01*
X1330521Y1552586D01*
X1330524Y1552091D01*
X1331913Y1550720D01*
X1332408Y1550724D01*
Y1550723D01*
X1335637Y1547537D01*
X1338132Y1546101D01*
Y1546102D01*
X1338261Y1545624D01*
X1339952Y1544650D01*
X1340429Y1544779D01*
X1349919Y1539318D01*
X1386203Y1525161D01*
X1387858Y1524094D01*
X1390324Y1520960D01*
X1391163Y1518609D01*
X1392257Y1459142D01*
X1390752Y1453272D01*
X1388366Y1449124D01*
X1365132Y1429536D01*
X1337170Y1413530D01*
X1335511Y1411871D01*
Y1346060D01*
X1333300Y1341173D01*
X1333291Y1341170D01*
X1169747Y1281216D01*
X1159696Y1274797D01*
X1155217Y1270317D01*
X1150330Y1263004D01*
Y1259512D01*
G01X1155180D02*
Y1261478D01*
X1158809Y1266909D01*
X1163018Y1271118D01*
X1170320Y1275778D01*
X1174097Y1277159D01*
X1174610Y1276921D01*
X1176442Y1277591D01*
X1176680Y1278105D01*
Y1278104D01*
X1346560Y1340240D01*
X1348861Y1347077D01*
Y1411461D01*
X1350140Y1412740D01*
X1368868Y1424882D01*
X1391108Y1443961D01*
X1395560Y1451810D01*
X1397503Y1459597D01*
X1396388Y1520365D01*
X1394927Y1523262D01*
X1391258Y1527697D01*
X1388651Y1529582D01*
X1353564Y1543268D01*
X1336124Y1554581D01*
X1335496Y1556170D01*
Y1566651D01*
X1333717Y1568430D01*
X1331563D01*
X1331063Y1568930D01*
Y1570434D01*
G01X1305079Y1560985D02*
Y1562489D01*
X1305579Y1562989D01*
X1306453D01*
X1307108Y1562335D01*
X1310000Y1558319D01*
X1309909Y1557761D01*
X1311049Y1556177D01*
X1311608Y1556086D01*
X1312747Y1554504D01*
X1312656Y1553946D01*
X1313796Y1552362D01*
X1314355Y1552271D01*
X1317869Y1547390D01*
X1322142Y1543117D01*
X1376646Y1517094D01*
X1377725Y1515392D01*
X1378833Y1455205D01*
X1375858Y1449415D01*
X1360287Y1436735D01*
X1323371Y1417807D01*
X1312609Y1413279D01*
X1311031Y1411701D01*
Y1346469D01*
X1310459Y1345313D01*
X1306947Y1342147D01*
Y1342146D01*
X1303433Y1338980D01*
X1166154Y1288034D01*
X1154745Y1280715D01*
X1143939Y1269909D01*
X1142850Y1268279D01*
Y1259512D01*
G01X1322402Y1566103D02*
Y1564599D01*
X1322902Y1564099D01*
X1325056D01*
X1326835Y1562320D01*
Y1557782D01*
X1336315Y1548428D01*
X1350400Y1540322D01*
X1386711Y1526155D01*
X1388616Y1524926D01*
X1391309Y1521504D01*
X1392270Y1518811D01*
X1393370Y1459012D01*
X1391790Y1452850D01*
X1389231Y1448401D01*
X1365771Y1428622D01*
X1337850Y1412640D01*
X1336621Y1411411D01*
Y1345820D01*
X1334112Y1340273D01*
X1333658Y1340122D01*
X1174918Y1281929D01*
X1174710Y1281480D01*
X1172878Y1280808D01*
X1172429Y1281016D01*
X1170243Y1280215D01*
X1160396Y1273926D01*
X1156079Y1269609D01*
X1151440Y1262667D01*
Y1259512D01*
G01X1313740Y1565315D02*
Y1566820D01*
X1314240Y1567320D01*
X1315934D01*
X1317063Y1566191D01*
Y1556432D01*
X1318628Y1552996D01*
X1323504Y1548119D01*
X1327741Y1545950D01*
X1327914Y1545411D01*
X1329651Y1544521D01*
X1330189Y1544695D01*
X1331924Y1543807D01*
X1332098Y1543268D01*
X1333835Y1542379D01*
X1334373Y1542552D01*
X1349409Y1534853D01*
X1384437Y1521757D01*
X1385531Y1520870D01*
X1385849Y1520406D01*
X1386512Y1518341D01*
X1387644Y1456724D01*
X1384789Y1451178D01*
X1362962Y1433277D01*
X1338521Y1419533D01*
X1324940Y1413481D01*
X1323271Y1411811D01*
Y1345948D01*
X1321051Y1341082D01*
X1168060Y1284679D01*
X1157140Y1277690D01*
X1152316Y1272866D01*
X1146590Y1264298D01*
Y1259512D01*
G01X1331063Y1565315D02*
Y1566820D01*
X1331563Y1567320D01*
X1333257D01*
X1334386Y1566191D01*
Y1555958D01*
X1335222Y1553843D01*
X1338208Y1551906D01*
X1338311Y1551422D01*
X1339948Y1550360D01*
X1340432Y1550463D01*
X1342067Y1549402D01*
X1342171Y1548918D01*
X1343808Y1547856D01*
X1344292Y1547959D01*
X1345927Y1546898D01*
X1346031Y1546414D01*
X1347668Y1545352D01*
X1348152Y1545455D01*
X1353055Y1542275D01*
X1388116Y1528599D01*
X1390493Y1526880D01*
X1393991Y1522650D01*
X1395282Y1520091D01*
X1396390Y1459723D01*
X1394519Y1452226D01*
X1390237Y1444678D01*
X1368201Y1425774D01*
X1349438Y1413608D01*
X1347751Y1411921D01*
Y1347259D01*
X1345677Y1341100D01*
X1169825Y1276779D01*
X1162319Y1271989D01*
X1157947Y1267617D01*
X1154070Y1261815D01*
Y1259512D01*
G01X1173912Y1260910D02*
X1176429D01*
X1349930Y1324118D01*
X1363344Y1333062D01*
X1368814Y1338849D01*
X1411707Y1451707D01*
X1412449Y1457076D01*
X1411142Y1521008D01*
X1407774Y1530106D01*
X1401088Y1538189D01*
X1391206Y1545270D01*
X1384592Y1547862D01*
X1384074Y1547636D01*
X1382257Y1548347D01*
X1382031Y1548867D01*
X1380216Y1549578D01*
X1379698Y1549352D01*
X1377881Y1550063D01*
X1377655Y1550583D01*
X1375840Y1551294D01*
X1375322Y1551068D01*
X1373505Y1551780D01*
X1373279Y1552299D01*
X1370552Y1553368D01*
X1369032Y1554888D01*
Y1566191D01*
X1367903Y1567320D01*
X1366209D01*
X1365709Y1566820D01*
Y1565315D01*
G01X1169863Y1261910D02*
X1170203Y1262250D01*
X1170567Y1262444D01*
X1175360Y1263398D01*
X1348334Y1326909D01*
X1361633Y1335432D01*
X1366485Y1340356D01*
X1408710Y1451790D01*
X1409476Y1457500D01*
X1408313Y1520977D01*
X1405570Y1528385D01*
X1399037Y1536286D01*
X1391268Y1541916D01*
X1369238Y1550575D01*
X1368035Y1551546D01*
X1361070Y1561910D01*
X1358881Y1564099D01*
X1357547D01*
X1357047Y1564599D01*
Y1566103D01*
G01X1161551Y1259312D02*
Y1260521D01*
X1167129Y1266100D01*
X1169097Y1267356D01*
X1348845Y1333453D01*
X1358115Y1339204D01*
X1362312Y1343212D01*
X1403512Y1452400D01*
X1404374Y1457584D01*
X1403218Y1520689D01*
X1401288Y1525898D01*
X1395765Y1532579D01*
X1389966Y1536780D01*
X1373775Y1543145D01*
X1373321Y1542947D01*
X1371505Y1543661D01*
X1371307Y1544115D01*
X1369493Y1544828D01*
X1369039Y1544630D01*
X1367223Y1545344D01*
X1367025Y1545798D01*
X1365211Y1546511D01*
X1364757Y1546313D01*
X1362941Y1547027D01*
X1362743Y1547481D01*
X1356462Y1549950D01*
X1353783Y1552629D01*
X1351709Y1557587D01*
Y1565361D01*
X1349750Y1567320D01*
X1348886D01*
X1348386Y1566820D01*
Y1565315D01*
G01X1339725Y1566103D02*
Y1564599D01*
X1340274Y1564050D01*
X1341607D01*
X1343320Y1562337D01*
Y1562338D01*
X1350670Y1551210D01*
X1356058Y1546787D01*
X1389101Y1533899D01*
X1394171Y1530232D01*
X1398898Y1524516D01*
X1400242Y1520888D01*
X1401380Y1457782D01*
X1400270Y1452600D01*
X1359940Y1344636D01*
X1356500Y1341355D01*
X1350160Y1337470D01*
X1176343Y1273506D01*
Y1273507D01*
X1176105Y1272992D01*
X1174274Y1272319D01*
X1173761Y1272556D01*
X1170322Y1271291D01*
X1165320Y1268091D01*
X1160145Y1262916D01*
X1158920Y1261082D01*
Y1259512D01*
G01X1339725Y1560985D02*
Y1562440D01*
X1340225Y1562940D01*
X1341147D01*
X1342455Y1561632D01*
X1343529Y1560005D01*
X1343416Y1559451D01*
X1344492Y1557823D01*
X1345046Y1557710D01*
X1346120Y1556083D01*
X1346007Y1555529D01*
X1347083Y1553901D01*
X1347637Y1553788D01*
X1349836Y1550458D01*
X1355490Y1545817D01*
X1388565Y1532916D01*
X1393405Y1529415D01*
X1397922Y1523954D01*
X1399135Y1520679D01*
X1400267Y1457890D01*
X1399201Y1452913D01*
X1358989Y1345263D01*
X1355819Y1342240D01*
X1354139Y1341211D01*
X1353589Y1341343D01*
X1351925Y1340324D01*
X1351793Y1339774D01*
X1349673Y1338475D01*
X1169825Y1272291D01*
X1164620Y1268961D01*
X1159283Y1263624D01*
X1157810Y1261419D01*
Y1259512D01*
G01X1169078Y1262695D02*
X1169534Y1263151D01*
X1170188Y1263501D01*
X1175059Y1264470D01*
X1347837Y1327909D01*
X1360929Y1336300D01*
X1365529Y1340969D01*
X1407626Y1452064D01*
X1408364Y1457564D01*
X1407206Y1520768D01*
X1404594Y1527823D01*
X1398271Y1535470D01*
X1390731Y1540934D01*
X1382038Y1544351D01*
X1381584Y1544153D01*
X1379768Y1544867D01*
X1379570Y1545321D01*
X1377756Y1546034D01*
X1377302Y1545836D01*
X1375486Y1546550D01*
X1375288Y1547004D01*
X1373474Y1547717D01*
X1373020Y1547519D01*
X1371204Y1548233D01*
X1371006Y1548687D01*
X1368673Y1549604D01*
X1367207Y1550787D01*
X1360209Y1561201D01*
X1358421Y1562989D01*
X1357547D01*
X1357047Y1562489D01*
Y1560985D01*
G01X1173912Y1259800D02*
X1176625D01*
X1350435Y1323120D01*
X1364065Y1332207D01*
X1369774Y1338247D01*
X1412790Y1451430D01*
X1413561Y1457011D01*
X1412248Y1521218D01*
X1408750Y1530668D01*
X1401852Y1539008D01*
X1391740Y1546253D01*
X1371173Y1554317D01*
X1370142Y1555348D01*
Y1566651D01*
X1368363Y1568430D01*
X1366209D01*
X1365709Y1568930D01*
Y1570434D01*
G01X1348386D02*
Y1568930D01*
X1348886Y1568430D01*
X1350210D01*
X1352819Y1565821D01*
Y1557810D01*
X1354723Y1553259D01*
X1357084Y1550899D01*
X1390503Y1537762D01*
X1396531Y1533395D01*
X1402264Y1526461D01*
X1404325Y1520898D01*
X1405486Y1457502D01*
X1404590Y1452110D01*
X1363262Y1342583D01*
X1358799Y1338321D01*
X1349334Y1332450D01*
X1177182Y1269146D01*
X1176914Y1268567D01*
X1175083Y1267894D01*
X1174506Y1268161D01*
X1169593Y1266355D01*
X1167829Y1265229D01*
X1162661Y1260061D01*
Y1259312D01*
G01X1245568Y614511D02*
X1246713Y613366D01*
X1249110D01*
X1250296Y614552D01*
Y616125D01*
X1248427Y619362D01*
X1247949Y619491D01*
X1246973Y621180D01*
X1247101Y621658D01*
X1246127Y623346D01*
X1245648Y623474D01*
X1244672Y625164D01*
X1244801Y625642D01*
X1216974Y673843D01*
X1210996Y696149D01*
X1210987Y696247D01*
X1210988D01*
X1195983Y867757D01*
X1199464Y907543D01*
X1209875Y1026550D01*
Y1052825D01*
X1206433Y1061137D01*
Y1068787D01*
G01X1245568Y611111D02*
X1246713Y612256D01*
X1249570D01*
X1251406Y614092D01*
Y616423D01*
X1218009Y674272D01*
X1212094Y696343D01*
X1197098Y867757D01*
X1210985Y1026501D01*
Y1053046D01*
X1207543Y1061358D01*
Y1068787D01*
G01X1235166Y607399D02*
X1236311Y606254D01*
X1248113D01*
X1253098Y611239D01*
X1254099Y613656D01*
Y617166D01*
X1221358Y673877D01*
X1215420Y696041D01*
X1215222Y698312D01*
X1214733Y698721D01*
X1214568Y700615D01*
X1214977Y701103D01*
X1214795Y703184D01*
X1214307Y703593D01*
X1214141Y705487D01*
X1214550Y705974D01*
X1214551Y705975D01*
X1200109Y871062D01*
X1213685Y1026297D01*
Y1053560D01*
X1210173Y1062041D01*
Y1069000D01*
G01X1235166Y603999D02*
X1236311Y605144D01*
X1248573D01*
X1254039Y610610D01*
X1255209Y613435D01*
Y617464D01*
X1222393Y674305D01*
Y674306D01*
X1216518Y696234D01*
X1215779Y704681D01*
X1215658Y706072D01*
X1215657D01*
X1201224Y871062D01*
X1214795Y1026248D01*
Y1053781D01*
X1213157Y1057737D01*
X1213320Y1058129D01*
X1212572Y1059932D01*
X1212181Y1060094D01*
X1211283Y1062262D01*
Y1069000D01*
G01X1213913Y1068787D02*
Y1062945D01*
X1217495Y1054295D01*
Y1026626D01*
X1203927Y871505D01*
X1219226Y696663D01*
X1224954Y675288D01*
X1257909Y618203D01*
Y612727D01*
X1256385Y609047D01*
X1255179Y607242D01*
X1254624Y607132D01*
X1253734Y605801D01*
X1253845Y605246D01*
X1252956Y603916D01*
X1252957D01*
X1252402Y603806D01*
X1251512Y602475D01*
X1251622Y601920D01*
X1250734Y600590D01*
X1249337Y599193D01*
X1246713D01*
X1245568Y600338D01*
G01X1215023Y1068787D02*
Y1063166D01*
X1218605Y1054516D01*
Y1026577D01*
X1205042Y871505D01*
X1220324Y696857D01*
X1225989Y675717D01*
X1259019Y618501D01*
Y612506D01*
X1257369Y608521D01*
X1251596Y599882D01*
X1249797Y598083D01*
X1246713D01*
X1245568Y596938D01*
G01X1217653Y1069000D02*
Y1064239D01*
X1218399Y1062438D01*
X1218236Y1062046D01*
X1218983Y1060243D01*
X1219375Y1060081D01*
X1221305Y1055421D01*
Y1026889D01*
X1207972Y874399D01*
X1215541Y787890D01*
X1223100Y701482D01*
X1222691Y700995D01*
X1222839Y699300D01*
X1223327Y698891D01*
X1223475Y697198D01*
X1229225Y675744D01*
X1261719Y619456D01*
Y611169D01*
X1259776Y606476D01*
X1253303Y596790D01*
X1250617Y594104D01*
X1245732Y592080D01*
X1236311D01*
X1235166Y593225D01*
G01Y589825D02*
X1236311Y590970D01*
X1245953D01*
X1251246Y593163D01*
X1254165Y596082D01*
X1260760Y605950D01*
X1262829Y610948D01*
Y619754D01*
X1230260Y676173D01*
X1224573Y697392D01*
X1209087Y874399D01*
X1222415Y1026840D01*
Y1055642D01*
X1218763Y1064460D01*
Y1069000D01*
G01X1221393Y1068787D02*
Y1066431D01*
X1225115Y1057444D01*
Y1026725D01*
X1211809Y874535D01*
X1219538Y786194D01*
X1219537D01*
X1227267Y697852D01*
X1232668Y677715D01*
X1265513Y620818D01*
Y610298D01*
X1261181Y599841D01*
X1257573Y594441D01*
X1257088Y594345D01*
X1256003Y592722D01*
X1256100Y592237D01*
X1255017Y590616D01*
X1252712Y588311D01*
X1252146D01*
X1250802Y586967D01*
Y586401D01*
X1249421Y585020D01*
X1246713D01*
X1245568Y586165D01*
G01Y582765D02*
X1246713Y583910D01*
X1249881D01*
X1255940Y589969D01*
Y589999D01*
X1262165Y599315D01*
X1266623Y610077D01*
Y621116D01*
X1233703Y678144D01*
X1228365Y698046D01*
X1212924Y874535D01*
X1226225Y1026676D01*
Y1057665D01*
X1222503Y1066652D01*
Y1068787D01*
G01X1235166Y579052D02*
X1236311Y577907D01*
X1244655D01*
X1251896Y580906D01*
X1257139Y586149D01*
X1258222Y587770D01*
X1258125Y588255D01*
X1259210Y589878D01*
X1259695Y589974D01*
X1260778Y591595D01*
X1260681Y592080D01*
X1261765Y593703D01*
X1262251Y593799D01*
X1263689Y595952D01*
X1269339Y609593D01*
Y621812D01*
X1236267Y679103D01*
X1231002Y698740D01*
X1230993Y698838D01*
X1230994D01*
X1215617Y874406D01*
X1228925Y1026635D01*
Y1058163D01*
X1225133Y1067320D01*
Y1069000D01*
G01X1235166Y575652D02*
X1236311Y576797D01*
X1244995D01*
X1245079Y576881D01*
X1252525Y579965D01*
X1258062Y585502D01*
Y585532D01*
X1264673Y595426D01*
X1270449Y609372D01*
Y622110D01*
X1237302Y679532D01*
X1232100Y698934D01*
X1216732Y874406D01*
X1230035Y1026586D01*
Y1058384D01*
X1226243Y1067541D01*
Y1069000D01*
G01X1245568Y571991D02*
X1246713Y570846D01*
X1249039D01*
X1250947Y572754D01*
Y573292D01*
X1252221Y574566D01*
X1252759D01*
X1257120Y578927D01*
X1258584Y581118D01*
X1258487Y581603D01*
X1259571Y583225D01*
X1260057Y583322D01*
X1260056D01*
X1266675Y593227D01*
X1273149Y608855D01*
Y622832D01*
X1239825Y680562D01*
X1234723Y699586D01*
X1219497Y873440D01*
X1232735Y1024910D01*
Y1058792D01*
X1228874Y1068115D01*
Y1068787D01*
G01X1245568Y568591D02*
X1246713Y569736D01*
X1249499D01*
X1257982Y578219D01*
X1267659Y592701D01*
X1274259Y608634D01*
Y623130D01*
X1240860Y680991D01*
X1235821Y699780D01*
X1220612Y873440D01*
X1233845Y1024861D01*
Y1059013D01*
X1229984Y1068336D01*
Y1068787D01*
G01X1245568Y488591D02*
X1246713Y489736D01*
X1249320D01*
X1250639Y491055D01*
X1251459Y493034D01*
X1252482Y498182D01*
X1262022Y520809D01*
X1263903Y522691D01*
X1297119Y602884D01*
Y628282D01*
X1296517Y630535D01*
X1262430Y689602D01*
X1258552Y704057D01*
X1243808Y872552D01*
X1253694Y985792D01*
X1294089Y1046243D01*
X1297648Y1054836D01*
X1298394Y1063397D01*
X1299148Y1072056D01*
X1294276Y1083818D01*
X1259734Y1118360D01*
X1249735Y1122502D01*
X1244463D01*
G01X1245568Y521952D02*
X1246713Y520807D01*
X1249021D01*
X1250944Y522730D01*
Y523295D01*
X1252218Y524569D01*
X1252783D01*
X1255332Y527118D01*
X1256629Y530251D01*
X1256413Y530774D01*
X1257102Y532438D01*
X1257625Y532654D01*
X1258313Y534316D01*
X1258097Y534839D01*
X1258786Y536503D01*
X1259309Y536720D01*
X1259997Y538382D01*
X1259781Y538905D01*
X1260470Y540569D01*
X1260993Y540786D01*
X1261681Y542448D01*
X1261465Y542971D01*
X1262154Y544635D01*
X1262677Y544852D01*
X1263365Y546514D01*
X1263149Y547037D01*
X1263838Y548701D01*
X1264361Y548918D01*
X1265049Y550580D01*
X1264833Y551103D01*
X1265522Y552767D01*
X1266046Y552983D01*
X1273106Y570027D01*
X1274639Y571560D01*
X1274638D01*
X1288389Y604756D01*
Y626978D01*
X1254387Y685894D01*
X1249936Y702492D01*
X1235050Y872648D01*
X1245190Y988758D01*
X1286510Y1050596D01*
X1289166Y1057009D01*
X1290364Y1070701D01*
X1286954Y1078932D01*
X1254842Y1111044D01*
X1247919Y1113912D01*
X1244463D01*
G01X1245568Y518552D02*
X1246713Y519697D01*
X1249481D01*
X1256273Y526489D01*
X1274047Y569398D01*
X1275580Y570931D01*
X1289499Y604535D01*
Y627276D01*
X1255422Y686323D01*
X1251034Y702686D01*
X1236165Y872648D01*
X1246272Y988378D01*
X1287494Y1050070D01*
X1290257Y1056742D01*
X1291494Y1070875D01*
X1287895Y1079561D01*
X1255471Y1111985D01*
X1248140Y1115022D01*
X1244463D01*
G01X1235166Y514839D02*
X1236311Y513694D01*
X1239913D01*
X1240313Y514094D01*
X1242113D01*
X1242513Y513694D01*
X1245685D01*
X1249479Y515266D01*
X1251093Y516880D01*
Y517446D01*
X1252367Y518720D01*
X1252933D01*
X1254205Y519992D01*
Y520558D01*
X1255479Y521832D01*
X1256045D01*
X1258910Y524697D01*
X1259598Y526359D01*
X1259382Y526882D01*
X1260071Y528546D01*
X1260594Y528763D01*
X1261282Y530425D01*
X1261066Y530948D01*
X1261755Y532612D01*
X1262278Y532829D01*
X1262966Y534491D01*
X1262750Y535014D01*
X1263439Y536678D01*
X1263962Y536895D01*
X1264650Y538557D01*
X1264434Y539080D01*
X1265123Y540744D01*
X1265646Y540961D01*
X1277115Y568647D01*
X1277793Y569325D01*
X1292199Y604104D01*
Y627633D01*
X1291962Y628520D01*
X1257835Y687653D01*
X1253658Y703234D01*
X1238856Y872414D01*
X1243873Y929871D01*
X1248905Y987513D01*
X1289818Y1048745D01*
X1292864Y1056100D01*
X1294191Y1071289D01*
X1290142Y1081063D01*
X1256973Y1114232D01*
X1248715Y1117653D01*
X1244557D01*
G01X1235166Y529013D02*
X1236311Y527868D01*
X1239340D01*
X1239760Y528288D01*
X1241560D01*
X1241980Y527868D01*
X1243779D01*
X1245442Y528557D01*
Y528556D01*
X1245670Y529106D01*
X1247334Y529795D01*
X1247883Y529568D01*
X1250610Y530697D01*
X1253374Y533461D01*
X1254062Y535123D01*
X1253835Y535672D01*
X1254524Y537336D01*
X1255074Y537564D01*
X1255073D01*
X1255761Y539226D01*
X1255545Y539749D01*
X1256234Y541413D01*
X1256757Y541630D01*
X1257445Y543292D01*
X1257229Y543815D01*
X1257918Y545479D01*
X1258441Y545696D01*
X1259129Y547358D01*
X1258913Y547881D01*
X1259602Y549545D01*
X1260126Y549761D01*
X1260814Y551423D01*
X1260598Y551946D01*
X1261287Y553610D01*
X1261810Y553827D01*
X1269089Y571399D01*
X1270897Y573207D01*
X1284579Y606239D01*
Y625678D01*
X1250812Y684180D01*
X1246199Y701382D01*
X1231219Y872601D01*
X1231227Y872697D01*
X1231228D01*
X1241497Y990264D01*
X1262483Y1021671D01*
X1283248Y1052748D01*
X1285489Y1058159D01*
X1286446Y1069080D01*
X1283561Y1077006D01*
X1252711Y1107856D01*
X1247116Y1110173D01*
X1244557D01*
G01X1245568Y491991D02*
X1246713Y490846D01*
X1248860D01*
X1249698Y491684D01*
X1250391Y493358D01*
X1251415Y498509D01*
X1252114Y500167D01*
X1251901Y500691D01*
X1252600Y502351D01*
X1253125Y502564D01*
X1253124D01*
X1253823Y504222D01*
X1253824D01*
X1253611Y504746D01*
X1254310Y506406D01*
X1254835Y506619D01*
X1254834D01*
X1255533Y508277D01*
X1255534D01*
X1255321Y508801D01*
X1256020Y510461D01*
X1256545Y510674D01*
X1256544Y510675D01*
X1257243Y512333D01*
X1257030Y512857D01*
X1257729Y514517D01*
X1258254Y514730D01*
X1258953Y516388D01*
X1258740Y516912D01*
X1259439Y518572D01*
X1259964Y518785D01*
X1261083Y521440D01*
X1262962Y523320D01*
X1263671Y525034D01*
X1263455Y525556D01*
X1264144Y527220D01*
X1264667Y527437D01*
X1265355Y529099D01*
X1265139Y529622D01*
X1265828Y531286D01*
X1266351Y531503D01*
X1296009Y603105D01*
Y628136D01*
X1295482Y630107D01*
X1261395Y689173D01*
X1257454Y703863D01*
X1242693Y872552D01*
X1252612Y986172D01*
X1293105Y1046769D01*
X1296557Y1055103D01*
X1298018Y1071882D01*
X1293335Y1083189D01*
X1259105Y1117419D01*
X1249514Y1121392D01*
X1244463D01*
G01X1235166Y525613D02*
X1236311Y526758D01*
X1244001D01*
X1251239Y529756D01*
X1254315Y532832D01*
X1270030Y570770D01*
X1271838Y572578D01*
X1285689Y606018D01*
Y625976D01*
X1251847Y684609D01*
X1247297Y701576D01*
X1232334Y872601D01*
X1242579Y989884D01*
X1284232Y1052222D01*
X1286580Y1057892D01*
X1287574Y1069229D01*
X1284520Y1077617D01*
X1253340Y1108797D01*
X1247337Y1111283D01*
X1244557D01*
G01X1235166Y511439D02*
X1236311Y512584D01*
X1245906D01*
X1250108Y514325D01*
X1259851Y524068D01*
X1278056Y568018D01*
X1278734Y568696D01*
X1293309Y603883D01*
Y627779D01*
X1292997Y628948D01*
X1258870Y688082D01*
X1254756Y703428D01*
X1239971Y872414D01*
X1249987Y987133D01*
X1290802Y1048219D01*
X1293955Y1055833D01*
X1295321Y1071463D01*
X1291083Y1081692D01*
X1257602Y1115173D01*
X1248936Y1118763D01*
X1244557D01*
G01X1235166Y484879D02*
X1236311Y483734D01*
X1242313D01*
X1242713Y484134D01*
X1244513D01*
X1244913Y483734D01*
X1247247D01*
X1252830Y489317D01*
X1254058Y492284D01*
X1254511Y494557D01*
X1255265Y496378D01*
X1255049Y496900D01*
X1255738Y498564D01*
X1256261Y498781D01*
X1256950Y500443D01*
X1256733Y500966D01*
X1257422Y502630D01*
X1257946Y502846D01*
X1258634Y504508D01*
X1258418Y505031D01*
X1259107Y506695D01*
X1259631Y506911D01*
X1259630Y506912D01*
X1260319Y508574D01*
X1260102Y509097D01*
X1260791Y510761D01*
X1261315Y510977D01*
X1261314D01*
X1262003Y512639D01*
X1261786Y513162D01*
X1262475Y514826D01*
X1262999Y515042D01*
X1264728Y519215D01*
X1266729Y521216D01*
X1267417Y522878D01*
X1267201Y523401D01*
X1267890Y525065D01*
X1268413Y525282D01*
X1299819Y601100D01*
Y628639D01*
X1299018Y631636D01*
X1264977Y690623D01*
X1261336Y704196D01*
X1246589Y872745D01*
X1246597Y872841D01*
X1246598D01*
X1256365Y984749D01*
X1296162Y1044305D01*
X1300251Y1054177D01*
X1301852Y1072456D01*
X1296522Y1085321D01*
X1261237Y1120606D01*
X1250307Y1125134D01*
X1244557D01*
G01X1235166Y470706D02*
X1236311Y469561D01*
X1241017D01*
X1241417Y469961D01*
X1243217D01*
X1243617Y469561D01*
X1245417D01*
X1252284Y474148D01*
X1252395Y474703D01*
X1253892Y475704D01*
X1254447Y475594D01*
X1256448Y476930D01*
X1257435Y479314D01*
X1257219Y479837D01*
X1257908Y481501D01*
X1258431Y481717D01*
X1259119Y483380D01*
X1258903Y483902D01*
X1259592Y485566D01*
X1260115Y485783D01*
X1260803Y487446D01*
X1260587Y487968D01*
X1261276Y489632D01*
X1261799Y489849D01*
X1262487Y491511D01*
X1262271Y492034D01*
X1262960Y493698D01*
X1263483Y493915D01*
X1264541Y496470D01*
X1264325Y496993D01*
X1265014Y498657D01*
X1265537Y498874D01*
X1272411Y515468D01*
X1273653Y516710D01*
X1307439Y598274D01*
Y629645D01*
X1306135Y634525D01*
X1272389Y693007D01*
X1268984Y705482D01*
X1254312Y873173D01*
X1263794Y981834D01*
X1302360Y1039546D01*
X1307656Y1052330D01*
X1309509Y1073633D01*
X1302903Y1089578D01*
X1265500Y1126981D01*
X1251900Y1132614D01*
X1244557D01*
G01X1245568Y474418D02*
X1246713Y475563D01*
X1249345D01*
X1254708Y480926D01*
X1269629Y516945D01*
X1270694Y518010D01*
X1304739Y600202D01*
Y629288D01*
X1303635Y633421D01*
X1269686Y692252D01*
X1266163Y705381D01*
X1251544Y872486D01*
X1261171Y982797D01*
X1300075Y1041018D01*
X1305038Y1052998D01*
X1306809Y1073218D01*
X1300654Y1088078D01*
X1263998Y1124734D01*
X1251327Y1129983D01*
X1244463D01*
G01X1245568Y477818D02*
X1246713Y476673D01*
X1248885D01*
X1250655Y478443D01*
Y479009D01*
X1251929Y480283D01*
X1252495D01*
X1253767Y481555D01*
X1254455Y483217D01*
X1254239Y483740D01*
X1254928Y485404D01*
X1255451Y485621D01*
X1258393Y492725D01*
X1258177Y493247D01*
X1258866Y494911D01*
X1259390Y495128D01*
X1259389D01*
X1260077Y496790D01*
X1259861Y497313D01*
X1260550Y498977D01*
X1261074Y499193D01*
X1261073D01*
X1261761Y500855D01*
X1261762D01*
X1261546Y501378D01*
X1262235Y503042D01*
X1262758Y503259D01*
X1263446Y504921D01*
X1263230Y505444D01*
X1263919Y507108D01*
X1264442Y507325D01*
X1265130Y508987D01*
X1264914Y509510D01*
X1265603Y511174D01*
X1266127Y511390D01*
X1266126D01*
X1268688Y517574D01*
X1269753Y518639D01*
X1269752D01*
X1303629Y600423D01*
Y629142D01*
X1302600Y632993D01*
X1268651Y691823D01*
X1265065Y705187D01*
X1250429Y872486D01*
X1250437Y872582D01*
X1250438D01*
X1260089Y983177D01*
X1299091Y1041544D01*
X1301519Y1047405D01*
X1303947Y1053265D01*
X1305679Y1073044D01*
X1299713Y1087449D01*
X1263369Y1123793D01*
X1251106Y1128873D01*
X1244463D01*
G01X1235166Y467306D02*
X1236311Y468451D01*
X1245755D01*
X1257345Y476194D01*
X1273352Y514839D01*
X1274594Y516081D01*
X1308549Y598053D01*
Y629791D01*
X1307170Y634953D01*
X1273422Y693438D01*
X1270082Y705678D01*
X1255427Y873173D01*
X1264876Y981454D01*
X1303344Y1039020D01*
X1306034Y1045514D01*
X1308747Y1052063D01*
X1309689Y1062886D01*
X1310639Y1073807D01*
X1303844Y1090207D01*
X1266129Y1127922D01*
X1252121Y1133724D01*
X1244557D01*
G01X1235166Y481479D02*
X1236311Y482624D01*
X1247707D01*
X1253771Y488688D01*
X1255126Y491960D01*
X1255579Y494233D01*
X1265669Y518586D01*
X1267670Y520587D01*
X1300929Y600879D01*
Y628785D01*
X1300053Y632064D01*
X1266012Y691052D01*
X1262434Y704390D01*
X1247704Y872745D01*
X1257447Y984369D01*
X1297146Y1043779D01*
X1301342Y1053910D01*
X1302982Y1072630D01*
X1297463Y1085950D01*
X1261866Y1121547D01*
X1250528Y1126244D01*
X1244557D01*
G01X1235166Y564879D02*
X1236311Y563734D01*
X1238182D01*
X1240197Y562900D01*
X1243255D01*
X1245056Y563646D01*
X1245245Y564103D01*
X1247048Y564850D01*
X1247505Y564661D01*
X1249841Y565628D01*
X1254198Y569985D01*
Y570480D01*
X1255578Y571860D01*
X1256073D01*
X1257451Y573238D01*
Y573733D01*
X1258831Y575113D01*
X1259326D01*
X1260906Y576693D01*
Y577188D01*
X1262285Y578567D01*
X1262780D01*
X1263675Y579462D01*
X1264758Y581083D01*
X1264662Y581568D01*
X1265746Y583190D01*
X1266232Y583287D01*
X1266231D01*
X1267949Y585857D01*
X1268695Y587658D01*
X1268505Y588115D01*
X1269253Y589918D01*
X1269710Y590107D01*
X1269709D01*
X1276959Y607609D01*
Y623783D01*
X1243470Y681801D01*
X1238655Y699759D01*
X1231023Y786981D01*
X1231024D01*
X1223393Y874202D01*
X1236545Y1024728D01*
Y1028410D01*
X1240095Y1064457D01*
Y1069988D01*
G01X1235166Y561479D02*
X1236311Y562624D01*
X1237961D01*
X1239976Y561790D01*
X1243476D01*
X1250470Y564687D01*
X1264537Y578754D01*
X1268933Y585331D01*
X1278069Y607388D01*
Y624081D01*
X1244505Y682230D01*
X1239753Y699953D01*
X1224508Y874202D01*
X1237655Y1024679D01*
Y1028355D01*
X1241205Y1064402D01*
Y1069988D01*
G01X1245568Y536125D02*
X1246713Y534980D01*
X1248993D01*
X1249693Y535680D01*
X1250790Y538329D01*
X1250563Y538877D01*
X1251251Y540541D01*
X1251801Y540769D01*
X1252544Y542565D01*
X1252317Y543113D01*
X1253006Y544777D01*
X1253556Y545005D01*
X1253555D01*
X1254243Y546667D01*
X1254016Y547216D01*
X1254705Y548880D01*
X1255255Y549107D01*
X1255254D01*
X1255942Y550769D01*
X1255715Y551318D01*
X1256404Y552982D01*
X1256954Y553209D01*
X1256953D01*
X1257641Y554871D01*
X1257414Y555420D01*
X1258103Y557084D01*
X1258653Y557311D01*
X1259341Y558973D01*
X1259114Y559522D01*
X1259803Y561186D01*
X1260353Y561414D01*
X1260352D01*
X1265046Y572745D01*
X1267682Y575381D01*
X1267681D01*
X1280769Y606976D01*
Y624743D01*
X1247160Y682973D01*
X1244779Y691849D01*
X1244780D01*
X1243608Y696217D01*
X1243607D01*
X1243021Y698401D01*
X1243022D01*
X1242412Y700678D01*
X1227393Y872367D01*
X1236015Y971071D01*
X1236016D01*
X1244625Y1069620D01*
X1244143Y1091637D01*
X1241357Y1097285D01*
X1240437Y1098206D01*
G01X1245568Y532725D02*
X1246713Y533870D01*
X1249453D01*
X1250634Y535051D01*
X1265987Y572116D01*
X1268623Y574752D01*
X1281879Y606755D01*
Y625041D01*
X1248195Y683402D01*
X1243510Y700872D01*
X1228508Y872367D01*
X1237122Y970970D01*
X1237123D01*
X1245737Y1069584D01*
X1245248Y1091908D01*
X1242272Y1097940D01*
X1241222Y1098991D01*
G01X1651535Y1612166D02*
Y1610662D01*
X1652035Y1610162D01*
X1653367D01*
X1656089Y1607440D01*
Y1554568D01*
X1652981Y1551460D01*
X1645751Y1548888D01*
X1627513Y1534026D01*
X1621358Y1524864D01*
X1618339Y1516917D01*
X1613631Y1482024D01*
X1595257Y1381708D01*
X1593861Y1377255D01*
X1592603Y1370754D01*
X1589883Y1367264D01*
X1582566Y1364687D01*
X1580833Y1362951D01*
X1579995Y1360928D01*
Y1346516D01*
X1577162Y1342185D01*
X1561395Y1335289D01*
X1487757Y1318413D01*
X1471304Y1313224D01*
X1447851Y1289772D01*
X1441210Y1273737D01*
Y1251415D01*
X1445331Y1241465D01*
X1445330D01*
X1445853Y1241248D01*
X1446600Y1239446D01*
X1446383Y1238923D01*
X1446384D01*
X1447130Y1237122D01*
X1447129D01*
X1447652Y1236905D01*
X1448399Y1235103D01*
X1448182Y1234580D01*
X1448183D01*
X1448928Y1232780D01*
Y1232779D01*
X1449451Y1232562D01*
X1450198Y1230760D01*
X1449981Y1230237D01*
X1450727Y1228436D01*
X1455231Y1220006D01*
X1455773Y1219841D01*
X1456693Y1218121D01*
X1456528Y1217579D01*
X1457447Y1215860D01*
X1457989Y1215695D01*
X1458909Y1213975D01*
X1458744Y1213433D01*
X1459663Y1211714D01*
X1460204Y1211549D01*
X1461125Y1209829D01*
X1460960Y1209287D01*
X1461879Y1207568D01*
X1462420Y1207403D01*
X1463341Y1205683D01*
X1463176Y1205141D01*
X1464801Y1202101D01*
X1474643Y1192258D01*
X1482255Y1189102D01*
X1495415Y1186086D01*
X1514488D01*
G01X1651535Y1607048D02*
Y1608552D01*
X1652035Y1609052D01*
X1652907D01*
X1654979Y1606980D01*
Y1555028D01*
X1652373Y1552422D01*
X1649627Y1551446D01*
X1649116Y1551688D01*
X1647278Y1551035D01*
X1647035Y1550523D01*
X1645198Y1549870D01*
X1640553Y1546085D01*
X1639990Y1546143D01*
X1638478Y1544910D01*
X1638420Y1544347D01*
X1636909Y1543116D01*
X1636346Y1543173D01*
X1634833Y1541940D01*
X1634776Y1541378D01*
X1633265Y1540147D01*
X1632702Y1540204D01*
X1631189Y1538971D01*
X1631132Y1538408D01*
X1626683Y1534783D01*
X1620365Y1525378D01*
X1617256Y1517192D01*
X1612534Y1482198D01*
X1594177Y1381975D01*
X1592783Y1377527D01*
X1591563Y1371227D01*
X1589207Y1368203D01*
X1581958Y1365651D01*
X1579891Y1363580D01*
X1578885Y1361149D01*
Y1346847D01*
X1576413Y1343070D01*
X1561046Y1336348D01*
X1487465Y1319486D01*
X1470711Y1314201D01*
X1446910Y1290401D01*
X1440100Y1273958D01*
Y1251194D01*
X1449722Y1227961D01*
X1454468Y1219077D01*
X1454469Y1219076D01*
X1463899Y1201432D01*
X1474014Y1191317D01*
X1481916Y1188040D01*
X1495289Y1184976D01*
X1514488D01*
G01X1660196Y1616496D02*
Y1614992D01*
X1660696Y1614492D01*
X1662028D01*
X1664780Y1611740D01*
Y1557094D01*
X1663002Y1552802D01*
X1659831Y1549631D01*
X1647040Y1545081D01*
X1630449Y1531560D01*
X1624907Y1523310D01*
X1622204Y1516198D01*
X1617786Y1483455D01*
X1599840Y1385476D01*
X1599407Y1375363D01*
X1591989Y1346104D01*
X1589629Y1343321D01*
X1563168Y1331749D01*
X1488965Y1314725D01*
X1473149Y1309737D01*
X1451076Y1287665D01*
X1445016Y1273034D01*
Y1253184D01*
X1454266Y1230849D01*
X1456552Y1226572D01*
X1456551D01*
X1457093Y1226408D01*
X1458013Y1224687D01*
X1457848Y1224145D01*
X1457849Y1224146D01*
X1458768Y1222426D01*
X1458767D01*
X1459309Y1222261D01*
X1460229Y1220541D01*
X1460064Y1219999D01*
X1460065D01*
X1460984Y1218280D01*
X1460983D01*
X1461525Y1218115D01*
X1462445Y1216395D01*
X1462280Y1215853D01*
X1463199Y1214134D01*
X1463740Y1213969D01*
X1464661Y1212249D01*
X1464496Y1211707D01*
X1465415Y1209988D01*
X1465956Y1209823D01*
X1466877Y1208103D01*
X1466712Y1207561D01*
X1468517Y1204184D01*
X1469895Y1202805D01*
X1470461D01*
X1471840Y1201425D01*
Y1200860D01*
X1473218Y1199481D01*
X1473784D01*
X1475163Y1198101D01*
Y1197535D01*
X1477348Y1195350D01*
X1482564Y1193189D01*
X1492369Y1191733D01*
X1498385Y1189826D01*
X1511388D01*
G01X1668858Y1607048D02*
Y1608552D01*
X1669358Y1609052D01*
X1670230D01*
X1672332Y1606950D01*
Y1556200D01*
X1671492Y1554172D01*
X1669133Y1551813D01*
X1668567D01*
X1667187Y1550433D01*
Y1549867D01*
X1665177Y1547857D01*
X1663236Y1547167D01*
X1662725Y1547410D01*
X1660887Y1546756D01*
X1660644Y1546244D01*
X1658807Y1545591D01*
X1658296Y1545834D01*
X1656458Y1545180D01*
X1656215Y1544668D01*
X1654378Y1544015D01*
X1653867Y1544258D01*
X1652029Y1543604D01*
X1651786Y1543092D01*
X1646495Y1541210D01*
X1632559Y1529856D01*
X1627457Y1522260D01*
X1624986Y1515754D01*
X1620844Y1485060D01*
X1602475Y1384770D01*
X1602026Y1374316D01*
X1594527Y1344731D01*
X1591312Y1340940D01*
X1564601Y1329259D01*
X1490126Y1312172D01*
X1490080D01*
X1474401Y1307227D01*
X1453359Y1286186D01*
X1447712Y1272552D01*
Y1254062D01*
X1454854Y1236817D01*
X1471307Y1206028D01*
X1480314Y1197021D01*
X1482817Y1195983D01*
X1492098Y1194606D01*
X1498879Y1192456D01*
X1511388D01*
G01X1660196Y1611378D02*
Y1612882D01*
X1660696Y1613382D01*
X1661568D01*
X1663670Y1611280D01*
Y1557315D01*
X1662061Y1553431D01*
X1659223Y1550593D01*
X1657161Y1549860D01*
X1656650Y1550103D01*
X1654812Y1549449D01*
X1654569Y1548937D01*
Y1548938D01*
X1646487Y1546063D01*
X1629619Y1532317D01*
X1623914Y1523824D01*
X1621121Y1516473D01*
X1616689Y1483629D01*
X1598734Y1385600D01*
X1598302Y1375525D01*
X1590976Y1346626D01*
X1588948Y1344236D01*
X1562818Y1332808D01*
X1488673Y1315797D01*
X1472556Y1310714D01*
X1450135Y1288294D01*
X1443906Y1273255D01*
Y1252963D01*
X1453261Y1230374D01*
X1467615Y1203515D01*
X1476719Y1194409D01*
X1482265Y1192110D01*
X1492118Y1190648D01*
X1498213Y1188716D01*
X1511388D01*
G01X1668858Y1612166D02*
Y1610662D01*
X1669358Y1610162D01*
X1670690D01*
X1673442Y1607410D01*
Y1555979D01*
X1672433Y1553543D01*
X1665785Y1546895D01*
X1647048Y1540228D01*
X1633389Y1529099D01*
X1628450Y1521746D01*
X1626069Y1515479D01*
X1621941Y1484886D01*
X1608172Y1409707D01*
X1608171D01*
X1603581Y1384646D01*
X1603131Y1374154D01*
X1595540Y1344209D01*
X1591993Y1340025D01*
X1564951Y1328200D01*
X1490252Y1311062D01*
X1490251D01*
X1474994Y1306250D01*
X1454300Y1285557D01*
X1448822Y1272331D01*
Y1254283D01*
X1455859Y1237292D01*
X1458647Y1232075D01*
X1458646D01*
X1459188Y1231911D01*
X1460108Y1230190D01*
X1459944Y1229648D01*
X1460862Y1227929D01*
X1461403Y1227765D01*
X1462323Y1226044D01*
X1462159Y1225502D01*
X1462160D01*
X1463079Y1223785D01*
X1463077Y1223783D01*
X1463619Y1223619D01*
X1464539Y1221898D01*
X1464374Y1221356D01*
X1464375Y1221357D01*
X1465294Y1219638D01*
X1465293Y1219637D01*
X1465835Y1219472D01*
X1466755Y1217752D01*
X1466590Y1217210D01*
X1466591D01*
X1467510Y1215491D01*
X1467509D01*
X1468051Y1215326D01*
X1468971Y1213606D01*
X1468806Y1213064D01*
X1469725Y1211345D01*
X1470266Y1211181D01*
X1471186Y1209460D01*
X1471022Y1208919D01*
X1472209Y1206697D01*
X1474780Y1204126D01*
X1475346D01*
X1476726Y1202746D01*
X1476725Y1202180D01*
X1480943Y1197962D01*
X1483116Y1197062D01*
X1492349Y1195691D01*
X1499051Y1193566D01*
X1511388D01*
G01X1519952Y394401D02*
X1518807Y393256D01*
X1514229D01*
X1512469Y393984D01*
X1512226Y394573D01*
X1510469Y395300D01*
X1509881Y395056D01*
X1504868Y397132D01*
X1502640Y399360D01*
Y399996D01*
X1501296Y401340D01*
X1500660D01*
X1499317Y402683D01*
Y403319D01*
X1497972Y404664D01*
X1497336D01*
X1495993Y406007D01*
Y406643D01*
X1494648Y407988D01*
X1494012D01*
X1492669Y409331D01*
Y409967D01*
X1491324Y411312D01*
X1490688D01*
X1489345Y412655D01*
Y413291D01*
X1488000Y414636D01*
X1487364D01*
X1483182Y418818D01*
X1482116Y421393D01*
X1482359Y421981D01*
X1481613Y423784D01*
X1481024Y424027D01*
X1480278Y425828D01*
X1480522Y426416D01*
X1479776Y428219D01*
X1479187Y428462D01*
X1475151Y438208D01*
X1451918Y514790D01*
Y547590D01*
X1462145Y572280D01*
X1464944Y629296D01*
X1467137Y640321D01*
X1604787Y1046998D01*
Y1068787D01*
G01X1519952Y391001D02*
X1518807Y392146D01*
X1514003D01*
X1504239Y396191D01*
X1482156Y418274D01*
Y418394D01*
X1474104Y437833D01*
X1450808Y514625D01*
Y547811D01*
X1461045Y572527D01*
X1463839Y629432D01*
X1466062Y640608D01*
X1603677Y1047181D01*
Y1068787D01*
G01X1608527Y1069000D02*
Y1046160D01*
X1470947Y639694D01*
X1468724Y628516D01*
X1465903Y571117D01*
X1455728Y546551D01*
Y515205D01*
X1477133Y444645D01*
X1479021Y440087D01*
X1479543Y439870D01*
X1480291Y438068D01*
X1480074Y437545D01*
X1480820Y435744D01*
X1481342Y435527D01*
X1482090Y433725D01*
X1481873Y433202D01*
X1482619Y431401D01*
X1483141Y431184D01*
X1483889Y429382D01*
X1483672Y428859D01*
X1484418Y427058D01*
Y427057D01*
X1484941Y426841D01*
X1485688Y425038D01*
X1485471Y424516D01*
X1486876Y421124D01*
X1489676Y418324D01*
X1490242D01*
X1491622Y416944D01*
Y416378D01*
X1493000Y415000D01*
X1493566D01*
X1494946Y413620D01*
Y413054D01*
X1496324Y411676D01*
X1496890D01*
X1498270Y410296D01*
Y409730D01*
X1499648Y408352D01*
X1500142D01*
X1501487Y407008D01*
Y406513D01*
X1502830Y405170D01*
X1503325D01*
X1504670Y403825D01*
Y403330D01*
X1506634Y401366D01*
X1509043Y400368D01*
X1510805D01*
X1511950Y401513D01*
G01Y398113D02*
X1510805Y399258D01*
X1508822D01*
X1506005Y400425D01*
X1485850Y420580D01*
Y420700D01*
X1476086Y444270D01*
X1454618Y515040D01*
Y546772D01*
X1464803Y571364D01*
X1467619Y628652D01*
X1469872Y639981D01*
X1607417Y1046343D01*
Y1069000D01*
G01X1612267Y1068787D02*
Y1045321D01*
X1474758Y639068D01*
X1472491Y627671D01*
X1469669Y570275D01*
X1459538Y545817D01*
Y515712D01*
X1479123Y451153D01*
X1483996Y439386D01*
X1484585Y439143D01*
X1485331Y437340D01*
X1485087Y436752D01*
X1485833Y434951D01*
X1486422Y434708D01*
X1487168Y432905D01*
X1486924Y432317D01*
X1487670Y430516D01*
X1488259Y430272D01*
X1489005Y428470D01*
X1488761Y427882D01*
X1490134Y424567D01*
X1494071Y420630D01*
X1494707D01*
X1496052Y419285D01*
Y418649D01*
X1497395Y417306D01*
X1498031D01*
X1499376Y415961D01*
Y415325D01*
X1500719Y413982D01*
X1501355D01*
X1502700Y412637D01*
Y412001D01*
X1504043Y410658D01*
X1507175Y409361D01*
X1507763Y409604D01*
X1509519Y408877D01*
X1509763Y408288D01*
Y408290D01*
X1511838Y407429D01*
X1513411D01*
X1513861Y407879D01*
X1515761D01*
X1516211Y407429D01*
X1518807D01*
X1519952Y408574D01*
G01Y405174D02*
X1518807Y406319D01*
X1511617D01*
X1507174Y408159D01*
X1507175D01*
X1503414Y409717D01*
X1489193Y423938D01*
X1478076Y450778D01*
X1458428Y515547D01*
Y546038D01*
X1468569Y570522D01*
X1470680Y613445D01*
X1471386Y627807D01*
X1473683Y639355D01*
X1611157Y1045504D01*
Y1068787D01*
G01X1509550Y412287D02*
X1508405Y413432D01*
X1505798D01*
X1493143Y426087D01*
X1493141D01*
X1479560Y458882D01*
X1462238Y515982D01*
Y545170D01*
X1472326Y569524D01*
X1473732Y598173D01*
Y598172D01*
X1474434Y612461D01*
X1475139Y626823D01*
X1477527Y638828D01*
X1614897Y1044666D01*
Y1069000D01*
G01X1509550Y415687D02*
X1508405Y414542D01*
X1506258D01*
X1504880Y415920D01*
Y416557D01*
X1503500Y417937D01*
X1502863D01*
X1501485Y419315D01*
Y419952D01*
X1500105Y421332D01*
X1499468D01*
X1498090Y422710D01*
Y423276D01*
X1496710Y424656D01*
X1496144D01*
X1494084Y426716D01*
X1494083D01*
X1492697Y430062D01*
X1492941Y430650D01*
X1492195Y432453D01*
X1491606Y432696D01*
X1490860Y434497D01*
X1491104Y435085D01*
X1490358Y436888D01*
X1489769Y437131D01*
X1489770D01*
X1489024Y438932D01*
X1489023D01*
X1489267Y439520D01*
X1488521Y441323D01*
X1487932Y441566D01*
X1487933D01*
X1487187Y443367D01*
X1487431Y443955D01*
X1486685Y445758D01*
X1486096Y446001D01*
X1485350Y447802D01*
X1485594Y448390D01*
X1484848Y450193D01*
X1484259Y450436D01*
X1484260D01*
X1480607Y459257D01*
X1463348Y516147D01*
Y544949D01*
X1473426Y569277D01*
X1476244Y626687D01*
X1478602Y638541D01*
X1616007Y1044483D01*
Y1069000D01*
G01X1677519Y1616496D02*
Y1614992D01*
X1678019Y1614492D01*
X1679351D01*
X1682103Y1611740D01*
Y1559019D01*
X1680398Y1554902D01*
X1669777Y1544281D01*
X1648841Y1536831D01*
X1636329Y1526637D01*
X1631998Y1520192D01*
X1629935Y1514762D01*
X1626096Y1486317D01*
X1607607Y1385372D01*
X1607138Y1374433D01*
X1598942Y1342105D01*
X1594448Y1336803D01*
X1565007Y1323928D01*
X1487746Y1306203D01*
X1476839Y1302763D01*
X1457524Y1283449D01*
X1452628Y1271628D01*
Y1255381D01*
X1454352Y1251220D01*
X1454351D01*
X1454874Y1251004D01*
X1455621Y1249201D01*
X1455405Y1248679D01*
X1457560Y1243475D01*
X1458993Y1240794D01*
X1458992D01*
X1459534Y1240630D01*
X1460454Y1238909D01*
X1460289Y1238367D01*
X1460290D01*
X1461209Y1236648D01*
X1461208D01*
X1461750Y1236483D01*
X1462670Y1234763D01*
X1462505Y1234221D01*
X1462506D01*
X1463425Y1232502D01*
X1463424D01*
X1463966Y1232337D01*
X1464886Y1230617D01*
X1464721Y1230075D01*
X1464722D01*
X1465640Y1228357D01*
Y1228356D01*
X1466181Y1228191D01*
X1467102Y1226471D01*
X1466937Y1225929D01*
X1467856Y1224210D01*
X1468397Y1224045D01*
X1469318Y1222325D01*
X1469153Y1221783D01*
X1470072Y1220064D01*
X1470613Y1219900D01*
X1471533Y1218179D01*
X1471369Y1217637D01*
X1472602Y1215330D01*
X1486602Y1201328D01*
X1494665Y1199686D01*
X1500832Y1197306D01*
X1511388D01*
G01X1677519Y1611378D02*
Y1612882D01*
X1678019Y1613382D01*
X1678891D01*
X1680993Y1611280D01*
Y1559240D01*
X1679457Y1555531D01*
X1678079Y1554153D01*
X1677513D01*
X1676133Y1552773D01*
Y1552207D01*
X1669169Y1545243D01*
X1648288Y1537813D01*
X1635499Y1527394D01*
X1631005Y1520706D01*
X1628852Y1515037D01*
X1624999Y1486491D01*
X1606501Y1385496D01*
X1606033Y1374595D01*
X1597929Y1342627D01*
X1593767Y1337718D01*
X1564657Y1324987D01*
X1487454Y1307275D01*
X1476246Y1303740D01*
X1456583Y1284078D01*
X1451518Y1271849D01*
Y1255160D01*
X1456555Y1243000D01*
X1471700Y1214661D01*
X1486053Y1200307D01*
X1494352Y1198616D01*
X1500625Y1196196D01*
X1511388D01*
G01X1686181Y1607048D02*
Y1608552D01*
X1686681Y1609052D01*
X1687555D01*
X1689626Y1606981D01*
Y1556253D01*
X1687382Y1552183D01*
X1685011Y1550685D01*
X1684459Y1550809D01*
X1682809Y1549767D01*
X1682685Y1549215D01*
X1681037Y1548174D01*
X1680485Y1548298D01*
X1678836Y1547256D01*
X1678711Y1546704D01*
X1669489Y1540877D01*
X1649098Y1533620D01*
X1638443Y1524940D01*
X1634549Y1519143D01*
X1632565Y1513916D01*
X1618663Y1410912D01*
Y1346448D01*
X1616478Y1342999D01*
X1613245Y1341586D01*
X1612719Y1341792D01*
X1610931Y1341009D01*
X1610725Y1340483D01*
X1608939Y1339702D01*
X1608412Y1339908D01*
X1606624Y1339126D01*
X1606418Y1338599D01*
Y1338600D01*
X1566416Y1321106D01*
X1484946Y1302415D01*
X1478091Y1300253D01*
X1459807Y1281970D01*
X1455324Y1271146D01*
Y1257107D01*
X1460137Y1245484D01*
X1475714Y1216336D01*
X1488000Y1204050D01*
X1493834Y1202888D01*
X1501483Y1199937D01*
X1511388D01*
G01X1686181Y1612166D02*
Y1610662D01*
X1686681Y1610162D01*
X1688015D01*
X1690736Y1607441D01*
Y1555967D01*
X1688217Y1551396D01*
X1669978Y1539872D01*
X1649651Y1532638D01*
X1639273Y1524183D01*
X1635542Y1518630D01*
X1633648Y1513641D01*
X1619773Y1410837D01*
Y1346125D01*
X1617234Y1342118D01*
X1566766Y1320047D01*
X1485238Y1301343D01*
X1478684Y1299276D01*
X1460748Y1281341D01*
X1456434Y1270925D01*
Y1257328D01*
X1461142Y1245959D01*
X1465401Y1237991D01*
X1465400Y1237990D01*
X1465942Y1237826D01*
X1466862Y1236105D01*
X1466697Y1235563D01*
X1466698Y1235564D01*
X1467617Y1233845D01*
X1467616Y1233844D01*
X1468158Y1233679D01*
X1469078Y1231959D01*
X1468913Y1231417D01*
X1468914D01*
X1469833Y1229698D01*
X1469832D01*
X1470374Y1229533D01*
X1471294Y1227813D01*
X1471129Y1227271D01*
X1472048Y1225552D01*
X1472590Y1225387D01*
X1473510Y1223667D01*
X1473345Y1223125D01*
X1474264Y1221406D01*
X1474805Y1221242D01*
X1475725Y1219521D01*
X1475561Y1218980D01*
X1476616Y1217005D01*
X1481563Y1212057D01*
X1482129D01*
X1483509Y1210677D01*
Y1210111D01*
X1484887Y1208733D01*
X1485453D01*
X1486833Y1207353D01*
Y1206787D01*
X1488547Y1205073D01*
X1494145Y1203959D01*
X1501690Y1201047D01*
X1511388D01*
G01Y1204787D02*
X1505617D01*
X1500074Y1206176D01*
X1493835Y1209512D01*
X1492457Y1210890D01*
Y1211456D01*
X1491077Y1212836D01*
X1490511D01*
X1489133Y1214214D01*
Y1214780D01*
X1487753Y1216160D01*
X1487187D01*
X1485809Y1217538D01*
Y1218104D01*
X1484429Y1219484D01*
X1483863D01*
X1482326Y1221021D01*
X1480518Y1223761D01*
X1480631Y1224316D01*
X1479556Y1225944D01*
X1479002Y1226058D01*
X1477928Y1227685D01*
X1478042Y1228239D01*
X1476967Y1229868D01*
X1476413Y1229981D01*
X1475339Y1231608D01*
X1475453Y1232162D01*
X1474378Y1233791D01*
X1473824Y1233904D01*
X1472750Y1235531D01*
X1472864Y1236085D01*
X1471789Y1237714D01*
X1471235Y1237827D01*
X1464200Y1248487D01*
X1460240Y1258060D01*
Y1270222D01*
X1463971Y1279238D01*
X1480529Y1295789D01*
X1480530D01*
Y1295788D01*
X1487202Y1297888D01*
X1574229Y1317855D01*
X1628154Y1341426D01*
X1630187Y1343221D01*
X1632013Y1346100D01*
Y1413887D01*
X1636860Y1474954D01*
X1637333Y1511503D01*
X1639106Y1517097D01*
X1642154Y1521634D01*
X1651550Y1529291D01*
X1673076Y1536951D01*
X1692735Y1549371D01*
X1697961Y1554920D01*
X1699397Y1557526D01*
Y1611771D01*
X1696676Y1614492D01*
X1695342D01*
X1694842Y1614992D01*
Y1616496D01*
G01Y1611378D02*
Y1612882D01*
X1695342Y1613382D01*
X1696216D01*
X1698287Y1611311D01*
Y1557812D01*
X1697056Y1555579D01*
X1692023Y1550235D01*
X1672587Y1537956D01*
X1650997Y1530273D01*
X1641324Y1522391D01*
X1638095Y1517584D01*
X1636225Y1511682D01*
X1635750Y1475005D01*
X1630903Y1413931D01*
Y1346423D01*
X1629334Y1343949D01*
X1627549Y1342374D01*
X1624423Y1341008D01*
X1623896Y1341214D01*
X1622109Y1340432D01*
X1621902Y1339905D01*
X1573880Y1318914D01*
X1486911Y1298961D01*
X1479936Y1296766D01*
X1463030Y1279867D01*
X1459130Y1270443D01*
Y1257839D01*
X1463215Y1247964D01*
X1481461Y1220315D01*
X1493166Y1208610D01*
X1499671Y1205132D01*
X1505480Y1203677D01*
X1511388D01*
G01X1703503Y1612166D02*
Y1610662D01*
X1704003Y1610162D01*
X1705337D01*
X1708058Y1607441D01*
Y1555806D01*
X1706281Y1552579D01*
X1677899Y1534647D01*
X1653419Y1525936D01*
X1645065Y1519129D01*
X1642557Y1515397D01*
X1641272Y1510945D01*
X1644253Y1410327D01*
Y1345964D01*
X1642508Y1343212D01*
X1577059Y1314599D01*
X1488479Y1294274D01*
X1482438Y1292372D01*
X1467194Y1277135D01*
X1464010Y1269441D01*
Y1259213D01*
X1467598Y1250541D01*
X1470432Y1246721D01*
X1470990Y1246639D01*
X1472153Y1245071D01*
X1472070Y1244512D01*
X1473231Y1242946D01*
X1473791Y1242863D01*
X1474954Y1241296D01*
X1474871Y1240737D01*
X1476032Y1239171D01*
X1476592Y1239088D01*
X1477755Y1237521D01*
X1477672Y1236962D01*
X1478833Y1235396D01*
X1479393Y1235313D01*
X1480556Y1233746D01*
X1480473Y1233186D01*
X1482772Y1230087D01*
X1491659Y1221200D01*
X1492225D01*
X1493605Y1219820D01*
Y1219254D01*
X1494983Y1217876D01*
X1495549D01*
X1496929Y1216496D01*
Y1215930D01*
X1498307Y1214552D01*
X1498872D01*
X1500252Y1213172D01*
Y1212607D01*
X1502731Y1210128D01*
X1506595Y1208527D01*
X1511388D01*
G01X1703503Y1607048D02*
Y1608552D01*
X1704003Y1609052D01*
X1704877D01*
X1706948Y1606981D01*
Y1556092D01*
X1705446Y1553365D01*
X1702773Y1551677D01*
X1702222Y1551801D01*
X1700572Y1550759D01*
X1700448Y1550207D01*
X1698800Y1549166D01*
X1698248Y1549290D01*
X1696599Y1548248D01*
X1696474Y1547696D01*
X1677410Y1535652D01*
X1652866Y1526918D01*
X1644235Y1519886D01*
X1641538Y1515872D01*
X1640157Y1511086D01*
X1643143Y1410310D01*
Y1346287D01*
X1641752Y1344093D01*
X1638375Y1342617D01*
X1637849Y1342823D01*
X1636061Y1342041D01*
X1635855Y1341514D01*
X1635854Y1341515D01*
X1634068Y1340734D01*
X1634069Y1340733D01*
X1633542Y1340940D01*
X1631754Y1340158D01*
X1631548Y1339631D01*
X1631547Y1339632D01*
X1576710Y1315658D01*
X1488187Y1295347D01*
X1481845Y1293350D01*
X1466253Y1277764D01*
X1462900Y1269662D01*
Y1258992D01*
X1466624Y1249989D01*
X1481881Y1229425D01*
Y1229408D01*
X1502102Y1209187D01*
X1506374Y1207417D01*
X1511388D01*
G01X1619748Y1068787D02*
Y1043647D01*
X1482378Y637812D01*
X1480172Y626721D01*
X1477315Y568606D01*
X1467158Y544086D01*
Y516592D01*
X1482838Y464898D01*
X1485024Y459619D01*
X1485613Y459375D01*
X1486340Y457619D01*
X1486096Y457031D01*
X1487184Y454404D01*
X1487773Y454160D01*
X1488500Y452404D01*
X1488256Y451816D01*
X1488983Y450061D01*
X1489572Y449817D01*
X1490299Y448061D01*
X1490055Y447473D01*
X1490782Y445718D01*
X1491370Y445475D01*
X1492098Y443719D01*
X1491854Y443131D01*
X1492592Y441348D01*
X1493181Y441104D01*
X1493908Y439348D01*
X1493664Y438760D01*
X1494391Y437005D01*
X1494980Y436761D01*
X1495707Y435005D01*
X1495463Y434417D01*
X1496509Y431891D01*
X1500150Y428250D01*
X1500786D01*
X1502131Y426905D01*
Y426269D01*
X1503474Y424926D01*
X1511499Y421602D01*
X1513400D01*
X1513850Y422052D01*
X1515750D01*
X1516200Y421602D01*
X1518807D01*
X1519952Y422747D01*
G01Y419347D02*
X1518807Y420492D01*
X1511278D01*
X1502845Y423985D01*
X1495568Y431262D01*
X1481791Y464523D01*
X1466048Y516427D01*
Y544307D01*
X1476215Y568853D01*
X1479067Y626857D01*
X1481303Y638099D01*
X1618638Y1043830D01*
Y1068787D01*
G01X1623488Y1069000D02*
Y1060475D01*
X1623888Y1060075D01*
Y1058125D01*
X1623488Y1057725D01*
Y1042809D01*
X1486188Y637184D01*
X1483934Y625852D01*
X1481071Y567583D01*
X1470968Y543193D01*
Y517003D01*
X1484983Y470799D01*
X1487288Y465234D01*
X1487680Y465072D01*
X1488427Y463269D01*
X1488264Y462877D01*
X1489010Y461076D01*
X1489599Y460833D01*
X1490346Y459030D01*
X1490102Y458442D01*
X1490848Y456641D01*
X1491436Y456398D01*
X1492183Y454595D01*
X1491939Y454007D01*
X1492685Y452206D01*
X1493273Y451963D01*
X1494020Y450160D01*
X1493776Y449572D01*
X1494522Y447771D01*
X1495111Y447528D01*
X1495857Y445725D01*
X1495613Y445137D01*
X1496359Y443336D01*
X1496948Y443093D01*
X1497694Y441290D01*
X1497450Y440702D01*
X1498196Y438901D01*
X1498785Y438658D01*
X1499531Y436855D01*
X1499287Y436267D01*
X1500033Y434466D01*
X1502630Y431869D01*
X1503096D01*
X1504441Y430525D01*
Y430058D01*
X1505784Y428715D01*
X1508405D01*
X1509550Y429860D01*
G01Y426460D02*
X1508405Y427605D01*
X1505324D01*
X1499007Y433922D01*
Y434042D01*
X1483936Y470424D01*
X1469858Y516838D01*
Y543414D01*
X1479971Y567830D01*
X1482112Y611407D01*
X1482829Y625988D01*
X1485113Y637471D01*
X1622378Y1042992D01*
Y1069000D01*
G01X1519952Y436921D02*
X1518807Y435776D01*
X1516500D01*
X1516050Y436226D01*
X1514150D01*
X1513700Y435776D01*
X1510489D01*
X1508734Y436503D01*
X1508491Y437092D01*
X1506734Y437819D01*
X1506146Y437575D01*
X1503378Y438722D01*
X1502504Y439596D01*
Y439597D01*
X1501758Y441398D01*
X1501948Y441855D01*
X1501201Y443658D01*
X1500743Y443847D01*
X1499997Y445648D01*
X1500187Y446105D01*
X1499440Y447908D01*
X1498982Y448097D01*
X1498983D01*
X1498237Y449899D01*
X1498236Y449898D01*
X1498426Y450355D01*
X1497679Y452158D01*
X1497222Y452348D01*
X1497223D01*
X1496477Y454149D01*
X1496476D01*
X1496666Y454606D01*
X1495919Y456409D01*
X1495462Y456598D01*
X1494716Y458399D01*
X1494906Y458856D01*
X1494159Y460659D01*
X1493702Y460848D01*
X1492956Y462649D01*
X1493146Y463106D01*
X1492399Y464909D01*
X1491942Y465098D01*
X1491196Y466899D01*
X1491386Y467356D01*
X1490639Y469159D01*
X1490182Y469348D01*
X1489436Y471149D01*
X1489626Y471606D01*
X1488879Y473409D01*
X1488422Y473598D01*
X1487424Y476008D01*
X1474778Y517690D01*
Y542325D01*
X1484894Y566744D01*
X1486339Y596194D01*
Y596195D01*
X1487772Y625372D01*
X1489996Y636554D01*
X1627228Y1041971D01*
Y1068787D01*
G01X1629858Y1069000D02*
Y1041317D01*
X1492733Y636215D01*
X1490433Y624651D01*
X1488996Y595413D01*
Y595414D01*
X1487560Y566178D01*
X1477478Y541838D01*
Y518152D01*
X1488601Y481484D01*
X1504622Y442807D01*
X1505651Y441778D01*
X1508405D01*
X1509550Y440633D01*
G01X1626118Y1068787D02*
Y1042154D01*
X1488921Y636841D01*
X1486667Y625508D01*
X1485946Y610837D01*
X1483794Y566991D01*
X1473668Y542546D01*
Y517525D01*
X1486377Y475633D01*
X1501562Y438968D01*
X1502749Y437781D01*
X1506146Y436373D01*
X1506147D01*
X1510268Y434666D01*
X1518807D01*
X1519952Y433521D01*
G01X1509550Y444033D02*
X1508405Y442888D01*
X1506111D01*
X1505563Y443436D01*
X1504581Y445807D01*
X1504825Y446395D01*
X1504079Y448198D01*
X1503490Y448441D01*
X1502744Y450242D01*
X1502988Y450830D01*
X1502242Y452633D01*
X1501653Y452876D01*
X1500907Y454677D01*
X1501151Y455265D01*
X1500405Y457068D01*
X1499816Y457311D01*
X1499070Y459112D01*
X1499314Y459700D01*
X1498568Y461503D01*
X1497979Y461746D01*
X1497233Y463547D01*
X1497477Y464135D01*
X1496731Y465938D01*
X1496142Y466181D01*
X1495396Y467982D01*
X1495640Y468570D01*
X1494894Y470373D01*
X1494305Y470616D01*
X1493559Y472417D01*
X1493803Y473005D01*
X1493057Y474808D01*
X1492468Y475051D01*
X1491722Y476852D01*
X1491966Y477440D01*
X1491220Y479243D01*
X1490631Y479486D01*
X1489648Y481859D01*
X1478588Y518317D01*
Y541617D01*
X1488660Y565931D01*
X1491538Y624515D01*
X1493808Y635928D01*
X1630968Y1041134D01*
Y1069000D01*
G01X1633598Y1068787D02*
Y1040479D01*
X1496543Y635587D01*
X1494235Y623985D01*
X1491357Y565461D01*
X1481288Y541152D01*
Y519159D01*
X1498595Y477377D01*
X1505440Y470532D01*
X1508405D01*
X1509550Y469387D01*
G01X1511388Y1211157D02*
X1507301D01*
X1505136Y1212054D01*
X1485362Y1231828D01*
X1469628Y1253041D01*
X1466700Y1260123D01*
Y1268953D01*
X1469476Y1275661D01*
X1483819Y1289997D01*
X1484079Y1290079D01*
Y1290078D01*
X1488680Y1291527D01*
X1577724Y1311957D01*
X1645481Y1341578D01*
X1647881Y1342415D01*
X1647882D01*
X1648128Y1342925D01*
X1649970Y1343567D01*
X1650480Y1343321D01*
X1653595Y1344407D01*
X1655383Y1346969D01*
Y1410307D01*
X1646008Y1457624D01*
X1644045Y1510558D01*
X1645135Y1514390D01*
X1647165Y1517411D01*
X1654335Y1523256D01*
X1680364Y1532518D01*
X1708252Y1550138D01*
X1714423Y1556308D01*
X1715610Y1559248D01*
Y1611311D01*
X1713539Y1613382D01*
X1712665D01*
X1712165Y1612882D01*
Y1611378D01*
G01X1511388Y1212267D02*
X1507522D01*
X1505765Y1212995D01*
X1500003Y1218757D01*
Y1219323D01*
X1498623Y1220703D01*
X1498057D01*
X1496679Y1222081D01*
Y1222647D01*
X1495299Y1224027D01*
X1494733D01*
X1493355Y1225405D01*
Y1225971D01*
X1491975Y1227351D01*
X1491409D01*
X1486205Y1232555D01*
X1484392Y1235000D01*
X1484475Y1235560D01*
X1483312Y1237127D01*
X1482752Y1237210D01*
X1481591Y1238776D01*
X1481674Y1239335D01*
X1480511Y1240903D01*
X1479952Y1240986D01*
X1478791Y1242552D01*
X1478874Y1243111D01*
X1477711Y1244679D01*
X1477152Y1244762D01*
X1475991Y1246328D01*
X1476074Y1246887D01*
X1474911Y1248454D01*
X1474352Y1248537D01*
X1470602Y1253592D01*
X1467810Y1260344D01*
Y1268732D01*
X1470417Y1275032D01*
X1484412Y1289019D01*
X1488971Y1290454D01*
X1578073Y1310898D01*
X1645887Y1340544D01*
X1654300Y1343477D01*
X1656493Y1346620D01*
Y1410416D01*
X1647115Y1457753D01*
X1645161Y1510423D01*
X1646155Y1513917D01*
X1647995Y1516654D01*
X1654888Y1522274D01*
X1680853Y1531513D01*
X1708950Y1549265D01*
X1715368Y1555683D01*
X1716720Y1559032D01*
Y1611771D01*
X1713999Y1614492D01*
X1712665D01*
X1712165Y1614992D01*
Y1616496D01*
G01X1634708Y1068787D02*
Y1040296D01*
X1497618Y635300D01*
X1495340Y623849D01*
X1493905Y594668D01*
X1492457Y565214D01*
X1482398Y540931D01*
Y519380D01*
X1485145Y512749D01*
X1485668Y512533D01*
X1486396Y510776D01*
X1486179Y510254D01*
X1486996Y508281D01*
X1486995D01*
X1487519Y508065D01*
X1488246Y506308D01*
X1488029Y505786D01*
X1488756Y504031D01*
Y504030D01*
X1489280Y503814D01*
X1490007Y502057D01*
X1489790Y501535D01*
X1490517Y499780D01*
Y499779D01*
X1491041Y499563D01*
X1491768Y497806D01*
X1491551Y497284D01*
X1492278Y495529D01*
X1492277D01*
X1492801Y495313D01*
X1493528Y493556D01*
X1493311Y493034D01*
X1494038Y491279D01*
X1494562Y491063D01*
X1495289Y489306D01*
X1495072Y488784D01*
X1495799Y487029D01*
X1495798D01*
X1496322Y486813D01*
X1497049Y485056D01*
X1496832Y484534D01*
X1497559Y482779D01*
X1498082Y482563D01*
X1498809Y480806D01*
X1498593Y480284D01*
X1499536Y478006D01*
X1501681Y475861D01*
X1502317D01*
X1503661Y474517D01*
Y473881D01*
X1505900Y471642D01*
X1508405D01*
X1509550Y472787D01*
G01X1638448Y1069000D02*
Y1039456D01*
X1501463Y634776D01*
X1499092Y622857D01*
X1496214Y564293D01*
X1486208Y540138D01*
Y521189D01*
X1488614Y515381D01*
Y515380D01*
X1489071Y515191D01*
X1489819Y513388D01*
X1489629Y512931D01*
X1490375Y511130D01*
X1490374D01*
X1490831Y510941D01*
X1491579Y509138D01*
X1491389Y508681D01*
X1492135Y506880D01*
Y506879D01*
X1492592Y506690D01*
X1493340Y504887D01*
X1493150Y504430D01*
X1493896Y502629D01*
Y502628D01*
X1494353Y502439D01*
X1495101Y500636D01*
X1494911Y500179D01*
X1495657Y498378D01*
X1495656D01*
X1496113Y498189D01*
X1496861Y496386D01*
X1496671Y495929D01*
X1497417Y494128D01*
Y494127D01*
X1497874Y493938D01*
X1498622Y492135D01*
X1498432Y491678D01*
X1499178Y489877D01*
Y489876D01*
X1499635Y489687D01*
X1500382Y487885D01*
X1500193Y487427D01*
X1501578Y484082D01*
X1503037Y482623D01*
X1503603D01*
X1504983Y481243D01*
Y480677D01*
X1506906Y478754D01*
X1509550D01*
X1509900Y479104D01*
X1511500D01*
X1511850Y478754D01*
X1513450D01*
X1513800Y479104D01*
X1515400D01*
X1515750Y478754D01*
X1518807D01*
X1519952Y479899D01*
G01Y476499D02*
X1518807Y477644D01*
X1506446D01*
X1500637Y483453D01*
X1485098Y520968D01*
Y540359D01*
X1495114Y564540D01*
X1497987Y622993D01*
X1500388Y635063D01*
X1637338Y1039639D01*
Y1069000D01*
G01X1509550Y483560D02*
X1508405Y484705D01*
X1505440D01*
X1504015Y486130D01*
X1488908Y522603D01*
Y539438D01*
X1499031Y563877D01*
X1501910Y622383D01*
X1504463Y635219D01*
X1641079Y1038803D01*
Y1068787D01*
G01X1509550Y486960D02*
X1508405Y485815D01*
X1505900D01*
X1504956Y486759D01*
X1504021Y489017D01*
X1504265Y489605D01*
X1503538Y491361D01*
X1502949Y491605D01*
X1502222Y493360D01*
X1502466Y493948D01*
X1501739Y495704D01*
X1501150Y495948D01*
X1500423Y497703D01*
X1500667Y498291D01*
X1499940Y500047D01*
X1499351Y500291D01*
Y500292D01*
X1498624Y502047D01*
X1498868Y502635D01*
X1498141Y504391D01*
X1497552Y504635D01*
X1496825Y506390D01*
X1497069Y506978D01*
X1496342Y508734D01*
X1495753Y508978D01*
X1495026Y510733D01*
X1495270Y511321D01*
X1494543Y513077D01*
X1493954Y513321D01*
Y513322D01*
X1492933Y515788D01*
X1493177Y516376D01*
X1492449Y518132D01*
X1491860Y518375D01*
X1491861D01*
X1490940Y520599D01*
X1490941D01*
X1490018Y522824D01*
Y539217D01*
X1500131Y563630D01*
X1503015Y622247D01*
X1504077Y627587D01*
X1504548Y627902D01*
X1504919Y629766D01*
X1504604Y630236D01*
X1505538Y634931D01*
X1642189Y1038620D01*
Y1068787D01*
G01X1519952Y494073D02*
X1518807Y492928D01*
X1516572D01*
X1512948Y496552D01*
X1510158Y500728D01*
X1510254Y501214D01*
X1509309Y502628D01*
X1508823Y502725D01*
X1507769Y504303D01*
X1507866Y504788D01*
X1506920Y506203D01*
X1506435Y506299D01*
X1505352Y507920D01*
X1505476Y508544D01*
X1504392Y510166D01*
X1503768Y510291D01*
X1502685Y511912D01*
X1502809Y512536D01*
X1501725Y514158D01*
X1501101Y514282D01*
X1500018Y515903D01*
X1500142Y516527D01*
X1499058Y518149D01*
X1498434Y518273D01*
X1496974Y520458D01*
X1493828Y528054D01*
Y538482D01*
X1495236Y541881D01*
X1495825Y542125D01*
X1496571Y543927D01*
X1496328Y544515D01*
X1497074Y546316D01*
X1497663Y546560D01*
X1498409Y548362D01*
X1498165Y548950D01*
X1498911Y550751D01*
X1499500Y550995D01*
X1500246Y552797D01*
X1500002Y553385D01*
X1500748Y555186D01*
X1501205Y555375D01*
X1501952Y557178D01*
X1501763Y557635D01*
X1503967Y562957D01*
X1505363Y591341D01*
X1506746Y619453D01*
X1510200Y636820D01*
X1645929Y1037782D01*
Y1069000D01*
G01X1644819D02*
Y1037965D01*
X1509125Y637107D01*
X1505641Y619589D01*
X1502867Y563204D01*
X1492718Y538703D01*
Y527833D01*
X1495990Y519932D01*
X1512086Y495844D01*
X1516112Y491818D01*
X1518807D01*
X1519952Y490673D01*
G01X1648559Y1068787D02*
Y1037127D01*
X1512899Y636375D01*
X1509727Y620421D01*
X1506773Y560368D01*
X1496528Y535633D01*
Y528502D01*
X1497614Y525880D01*
X1500521Y521527D01*
X1500522D01*
X1503710Y516755D01*
X1503711D01*
X1504684Y515298D01*
X1505866Y514666D01*
X1508405D01*
X1509550Y513521D01*
G01X1652299Y1069000D02*
Y1036289D01*
X1517778Y638902D01*
X1513404Y616915D01*
X1510519Y558273D01*
X1500290Y533582D01*
Y530486D01*
X1501334Y527966D01*
X1505788Y523512D01*
X1509974Y521778D01*
X1518807D01*
X1519952Y520633D01*
G01X1649669Y1068787D02*
Y1036944D01*
X1513974Y636088D01*
X1512861Y630491D01*
X1511749Y624895D01*
X1512103Y624366D01*
X1511732Y622502D01*
X1511202Y622148D01*
X1511203D01*
X1510832Y620285D01*
X1507873Y560121D01*
X1506633Y557127D01*
X1506876Y556539D01*
X1506149Y554783D01*
X1505560Y554539D01*
X1504834Y552784D01*
X1505077Y552196D01*
X1504350Y550439D01*
X1503762Y550196D01*
X1503035Y548441D01*
X1503279Y547853D01*
X1502552Y546096D01*
X1501963Y545853D01*
X1501236Y544098D01*
X1501480Y543510D01*
X1500753Y541753D01*
X1500164Y541510D01*
X1499437Y539755D01*
X1499681Y539167D01*
X1498954Y537410D01*
X1498365Y537167D01*
X1497638Y535412D01*
Y528723D01*
X1498598Y526406D01*
X1500466Y523610D01*
X1501090Y523485D01*
X1502146Y521905D01*
X1502022Y521280D01*
X1503077Y519701D01*
X1503701Y519577D01*
X1504758Y517996D01*
X1504634Y517372D01*
X1505453Y516146D01*
X1506145Y515776D01*
X1508405D01*
X1509550Y516921D01*
G01X1653409Y1069000D02*
Y1036106D01*
X1518853Y638615D01*
X1514509Y616779D01*
X1512987Y585821D01*
X1513415Y585349D01*
X1513319Y583401D01*
X1512846Y582973D01*
X1512751Y581026D01*
X1513179Y580554D01*
X1513083Y578606D01*
X1512610Y578178D01*
X1512515Y576231D01*
X1512943Y575759D01*
X1512847Y573810D01*
X1512374Y573383D01*
X1512279Y571436D01*
X1512707Y570965D01*
X1512611Y569016D01*
X1512138Y568589D01*
X1512038Y566538D01*
X1512466Y566067D01*
X1512370Y564118D01*
X1511897Y563691D01*
X1511619Y558026D01*
X1509124Y552002D01*
X1509367Y551414D01*
X1508621Y549612D01*
X1508032Y549368D01*
X1507286Y547567D01*
X1507529Y546979D01*
X1506783Y545176D01*
X1506194Y544933D01*
X1501400Y533361D01*
Y530707D01*
X1502275Y528595D01*
X1506417Y524453D01*
X1510195Y522888D01*
X1512400D01*
X1512850Y523338D01*
X1514750D01*
X1515200Y522888D01*
X1518807D01*
X1519952Y524033D01*
G01X1656039Y1068787D02*
Y1035407D01*
X1549798Y721559D01*
X1515957Y551223D01*
X1514567Y547867D01*
X1507378Y540678D01*
X1504100Y532768D01*
Y531324D01*
X1504585Y530154D01*
X1505900Y528839D01*
X1508405D01*
X1509550Y527694D01*
G01Y531094D02*
X1508405Y529949D01*
X1506360D01*
X1505526Y530783D01*
X1505210Y531545D01*
Y532547D01*
X1505937Y534299D01*
Y534300D01*
X1506526Y534543D01*
X1507253Y536300D01*
X1507009Y536888D01*
X1508319Y540049D01*
X1509662Y541392D01*
X1510298D01*
X1511643Y542737D01*
Y543373D01*
X1515508Y547238D01*
X1517025Y550899D01*
X1517404Y552811D01*
X1517935Y553165D01*
X1518315Y555078D01*
X1517961Y555607D01*
X1518340Y557519D01*
X1518871Y557873D01*
X1519251Y559786D01*
X1518897Y560315D01*
X1519276Y562227D01*
X1519807Y562581D01*
X1520186Y564494D01*
X1519833Y565023D01*
X1520212Y566935D01*
X1520743Y567289D01*
X1521122Y569202D01*
X1520769Y569731D01*
X1521148Y571643D01*
X1521679Y571997D01*
X1522058Y573910D01*
X1521705Y574440D01*
X1522084Y576352D01*
X1522614Y576706D01*
X1522994Y578619D01*
X1522641Y579149D01*
X1550873Y721272D01*
X1657149Y1035224D01*
Y1068787D01*
G01X1511288Y1214897D02*
X1508162D01*
X1504974Y1218085D01*
X1503661Y1220634D01*
X1503008Y1237597D01*
X1508380Y1266416D01*
X1511297Y1275388D01*
X1517461Y1283821D01*
X1526664Y1290433D01*
X1609739Y1316733D01*
X1637122Y1329645D01*
X1637123Y1329646D01*
X1664507Y1342559D01*
X1667623Y1347063D01*
Y1408843D01*
X1660010Y1436601D01*
X1659558Y1436859D01*
X1658998Y1438899D01*
X1659255Y1439351D01*
X1658741Y1441231D01*
X1658187Y1441546D01*
X1657671Y1443428D01*
X1657986Y1443981D01*
X1657470Y1445861D01*
X1657471D01*
X1656917Y1446176D01*
X1656401Y1448057D01*
X1656716Y1448610D01*
X1654980Y1454942D01*
Y1504618D01*
X1652909Y1506689D01*
X1652035D01*
X1651535Y1506189D01*
Y1504685D01*
G01Y1509804D02*
Y1508299D01*
X1652035Y1507799D01*
X1653369D01*
X1656090Y1505078D01*
Y1455092D01*
X1668733Y1408993D01*
Y1346716D01*
X1665251Y1341681D01*
X1610145Y1315697D01*
X1542951Y1294424D01*
Y1294425D01*
X1542657Y1293859D01*
X1540797Y1293271D01*
X1540233Y1293564D01*
X1538374Y1292975D01*
Y1292976D01*
X1538080Y1292410D01*
X1536220Y1291822D01*
X1535656Y1292115D01*
X1533797Y1291526D01*
Y1291527D01*
X1533504Y1290961D01*
X1531644Y1290373D01*
X1531079Y1290666D01*
X1527168Y1289428D01*
X1518253Y1283023D01*
X1512298Y1274876D01*
X1509459Y1266141D01*
X1505714Y1246048D01*
X1506074Y1245523D01*
X1505716Y1243605D01*
X1505191Y1243245D01*
X1504123Y1237516D01*
X1504492Y1227915D01*
X1504960Y1227482D01*
X1505035Y1225533D01*
X1504602Y1225066D01*
X1504761Y1220923D01*
X1505882Y1218748D01*
X1508144Y1216485D01*
X1508622Y1216007D01*
X1511288D01*
G01X1514417Y1224200D02*
X1511432Y1227185D01*
X1510710Y1228928D01*
Y1236697D01*
X1510448Y1245322D01*
X1511148Y1254418D01*
X1513134Y1265072D01*
X1515722Y1273035D01*
X1519409Y1278080D01*
X1530213Y1285843D01*
X1607998Y1310466D01*
X1671762Y1340553D01*
X1678485Y1343070D01*
X1680973Y1346669D01*
Y1410374D01*
X1664751Y1453530D01*
Y1509409D01*
X1662030Y1512130D01*
X1660696D01*
X1660196Y1512630D01*
Y1514134D01*
G01X1513632Y1223415D02*
X1510491Y1226556D01*
X1509600Y1228707D01*
Y1236680D01*
X1509336Y1245348D01*
X1510045Y1254563D01*
X1512055Y1265347D01*
X1514721Y1273547D01*
X1518617Y1278878D01*
X1529709Y1286848D01*
X1607592Y1311502D01*
X1671329Y1341577D01*
X1677770Y1343988D01*
X1679863Y1347016D01*
Y1410172D01*
X1678160Y1414701D01*
X1678161D01*
X1677581Y1414964D01*
X1676894Y1416790D01*
X1677157Y1417369D01*
X1670766Y1434371D01*
X1670429Y1434524D01*
X1669646Y1436609D01*
X1669798Y1436946D01*
X1669113Y1438771D01*
X1668674Y1438970D01*
X1667946Y1440908D01*
X1668145Y1441346D01*
X1667459Y1443171D01*
X1666943Y1443405D01*
X1666257Y1445231D01*
X1666491Y1445746D01*
X1665805Y1447571D01*
X1665289Y1447804D01*
X1664603Y1449631D01*
X1664837Y1450146D01*
X1663641Y1453328D01*
Y1508949D01*
X1661570Y1511020D01*
X1660696D01*
X1660196Y1510520D01*
Y1509016D01*
G01X1659779Y1069000D02*
Y1033900D01*
X1556789Y729659D01*
X1520943Y549172D01*
X1519275Y545145D01*
X1514400Y540270D01*
Y537499D01*
X1515948Y535951D01*
X1518807D01*
X1519952Y534806D01*
G01X1660889Y1069000D02*
Y1033717D01*
X1557864Y729372D01*
X1529376Y585917D01*
X1529730Y585388D01*
X1529350Y583474D01*
X1528820Y583120D01*
X1528441Y581208D01*
X1528755Y580738D01*
X1528376Y578825D01*
X1527904Y578510D01*
X1527525Y576598D01*
X1527839Y576128D01*
X1527460Y574215D01*
X1526988Y573900D01*
X1526609Y571988D01*
X1526923Y571518D01*
X1526544Y569605D01*
X1526072Y569290D01*
X1525693Y567378D01*
X1526007Y566908D01*
X1525628Y564995D01*
X1525156Y564680D01*
X1524777Y562768D01*
X1525091Y562298D01*
X1524712Y560385D01*
X1524240Y560070D01*
X1523861Y558158D01*
X1524175Y557688D01*
X1523796Y555775D01*
X1523324Y555460D01*
X1522945Y553548D01*
X1523259Y553078D01*
X1522889Y551213D01*
X1522418Y550899D01*
X1522011Y548848D01*
X1520216Y544516D01*
X1518873Y543173D01*
Y542607D01*
X1517528Y541263D01*
X1516963D01*
X1515510Y539810D01*
Y537959D01*
X1516408Y537061D01*
X1518807D01*
X1519952Y538206D01*
G01X1668858Y1509804D02*
Y1508299D01*
X1669358Y1507799D01*
X1670692D01*
X1673413Y1505078D01*
Y1454695D01*
X1693213Y1410099D01*
Y1345190D01*
X1692059Y1343522D01*
X1667736Y1334416D01*
X1607082Y1305818D01*
X1531049Y1281750D01*
X1522279Y1275448D01*
X1518763Y1266960D01*
Y1255712D01*
G01X1668858Y1504685D02*
Y1506189D01*
X1669358Y1506689D01*
X1670232D01*
X1672303Y1504618D01*
Y1454459D01*
X1673723Y1451259D01*
X1673495Y1450666D01*
X1674286Y1448882D01*
X1674881Y1448654D01*
X1674880Y1448653D01*
X1675671Y1446872D01*
X1675672D01*
X1675443Y1446278D01*
X1676234Y1444495D01*
X1676829Y1444266D01*
X1676828D01*
X1677619Y1442484D01*
X1677620D01*
X1677391Y1441890D01*
X1678182Y1440107D01*
X1678777Y1439878D01*
X1678776D01*
X1685284Y1425220D01*
X1685132Y1424824D01*
X1685924Y1423041D01*
X1686320Y1422889D01*
X1687111Y1421107D01*
X1686882Y1420513D01*
X1687673Y1418729D01*
X1688268Y1418501D01*
X1689059Y1416719D01*
X1688830Y1416126D01*
X1689621Y1414342D01*
X1690216Y1414114D01*
X1690215D01*
X1692103Y1409863D01*
Y1345537D01*
X1691344Y1344440D01*
X1667304Y1335440D01*
X1606676Y1306854D01*
X1530545Y1282755D01*
X1521374Y1276166D01*
X1517653Y1267181D01*
Y1255712D01*
G01X1694842Y1509016D02*
Y1510520D01*
X1695342Y1511020D01*
X1696216D01*
X1698287Y1508949D01*
Y1451207D01*
X1700678Y1448016D01*
X1700679D01*
X1700608Y1447526D01*
X1701779Y1445964D01*
X1702269Y1445894D01*
X1702268D01*
X1703437Y1444334D01*
X1703438D01*
X1703368Y1443844D01*
X1704538Y1442283D01*
X1705028Y1442213D01*
X1705027D01*
X1706196Y1440653D01*
X1706197D01*
X1706127Y1440163D01*
X1707297Y1438602D01*
X1707787Y1438532D01*
X1707786D01*
X1728823Y1410464D01*
Y1345349D01*
X1728291Y1344582D01*
X1655229Y1317220D01*
X1605280Y1293673D01*
X1533809Y1271049D01*
X1530876Y1268941D01*
X1528874Y1264106D01*
Y1259424D01*
G01X1686181Y1504685D02*
Y1506189D01*
X1686681Y1506689D01*
X1687555D01*
X1689626Y1504618D01*
Y1451674D01*
X1692924Y1446709D01*
X1692826Y1446224D01*
X1693907Y1444599D01*
X1694392Y1444501D01*
X1694391D01*
X1695470Y1442877D01*
X1695471D01*
X1695373Y1442392D01*
X1696453Y1440767D01*
X1696938Y1440669D01*
X1696937D01*
X1698016Y1439044D01*
X1698017Y1439045D01*
X1697919Y1438560D01*
X1698999Y1436935D01*
X1699484Y1436837D01*
X1699483D01*
X1700562Y1435213D01*
X1700563D01*
X1700465Y1434728D01*
X1701545Y1433103D01*
X1702030Y1433005D01*
X1702029Y1433004D01*
X1716583Y1411098D01*
Y1345142D01*
X1716180Y1344560D01*
X1658857Y1323093D01*
X1606391Y1298363D01*
X1532925Y1275108D01*
X1527801Y1271425D01*
X1525135Y1264987D01*
Y1259424D01*
G01X1686181Y1509804D02*
Y1508299D01*
X1686681Y1507799D01*
X1688015D01*
X1690736Y1505078D01*
Y1452010D01*
X1717693Y1411434D01*
Y1344795D01*
X1716895Y1343642D01*
X1659289Y1322069D01*
X1606797Y1297327D01*
X1547632Y1278599D01*
X1547404Y1278159D01*
X1545544Y1277571D01*
X1545105Y1277799D01*
X1533429Y1274103D01*
X1528706Y1270708D01*
X1526245Y1264766D01*
Y1259424D01*
G01X1694842Y1514134D02*
Y1512630D01*
X1695342Y1512130D01*
X1696676D01*
X1699397Y1509409D01*
Y1451577D01*
X1729933Y1410834D01*
Y1345002D01*
X1729006Y1343664D01*
X1655661Y1316196D01*
X1605686Y1292637D01*
X1543701Y1273016D01*
X1543466Y1272563D01*
X1541606Y1271975D01*
X1541154Y1272209D01*
X1534313Y1270044D01*
X1531781Y1268224D01*
X1529984Y1263885D01*
Y1259424D01*
G01X1677519Y1509016D02*
Y1510520D01*
X1678019Y1511020D01*
X1678893D01*
X1680964Y1508949D01*
Y1453572D01*
X1685100Y1446038D01*
X1684961Y1445563D01*
X1685901Y1443852D01*
X1686376Y1443714D01*
X1686375D01*
X1689815Y1437447D01*
X1689816D01*
X1689678Y1436972D01*
X1690617Y1435261D01*
X1691092Y1435123D01*
X1692030Y1433414D01*
X1691892Y1432939D01*
X1692831Y1431229D01*
X1693306Y1431090D01*
X1704343Y1410985D01*
Y1345345D01*
X1703760Y1344507D01*
X1663145Y1329293D01*
X1606733Y1302697D01*
X1601162Y1300729D01*
X1532275Y1279358D01*
X1524586Y1273831D01*
X1521394Y1266123D01*
Y1259424D01*
G01X1677519Y1514134D02*
Y1512630D01*
X1678019Y1512130D01*
X1679353D01*
X1682074Y1509409D01*
Y1453857D01*
X1705453Y1411270D01*
Y1344998D01*
X1704476Y1343588D01*
X1663577Y1328269D01*
X1607156Y1301669D01*
X1601511Y1299675D01*
X1551705Y1284223D01*
Y1284224D01*
X1551468Y1283772D01*
X1549604Y1283194D01*
X1549154Y1283431D01*
X1532780Y1278352D01*
X1532776Y1278351D01*
X1525491Y1273114D01*
X1522504Y1265902D01*
Y1259424D01*
G01X1712165Y1509016D02*
Y1510520D01*
X1712665Y1511020D01*
X1713537D01*
X1715640Y1508917D01*
Y1455503D01*
X1718057Y1448093D01*
X1720810Y1444322D01*
X1720745Y1443903D01*
X1721895Y1442327D01*
X1722315Y1442261D01*
X1723464Y1440687D01*
X1723399Y1440267D01*
X1724550Y1438691D01*
X1724969Y1438626D01*
X1726118Y1437052D01*
X1726053Y1436632D01*
X1727204Y1435056D01*
X1727623Y1434991D01*
X1742756Y1414261D01*
X1745530Y1408515D01*
X1745513Y1344293D01*
X1743109Y1341048D01*
X1730738Y1337271D01*
X1658003Y1310022D01*
X1602044Y1283633D01*
X1537647Y1263248D01*
X1536354Y1261955D01*
Y1259424D01*
G01X1712165Y1514134D02*
Y1512630D01*
X1712665Y1512130D01*
X1713997D01*
X1716750Y1509377D01*
Y1455680D01*
X1719058Y1448605D01*
X1743713Y1414835D01*
X1746641Y1408769D01*
X1746623Y1343926D01*
X1743783Y1340093D01*
X1731095Y1336219D01*
X1658436Y1308998D01*
X1602450Y1282597D01*
X1551610Y1266503D01*
X1551375Y1266051D01*
X1549515Y1265462D01*
X1549063Y1265697D01*
X1538241Y1262271D01*
X1537464Y1261495D01*
Y1259424D01*
G01X1703503Y1504685D02*
Y1506189D01*
X1704003Y1506689D01*
X1704877D01*
X1706948Y1504618D01*
Y1454907D01*
X1708611Y1450377D01*
X1713694Y1444090D01*
X1713641Y1443583D01*
X1714868Y1442066D01*
X1715374Y1442012D01*
X1716600Y1440496D01*
X1716546Y1439990D01*
X1717773Y1438472D01*
X1718279Y1438419D01*
X1719505Y1436903D01*
X1719451Y1436397D01*
X1720678Y1434879D01*
X1721184Y1434826D01*
X1722410Y1433310D01*
X1722356Y1432804D01*
X1723583Y1431286D01*
X1724089Y1431233D01*
X1739686Y1411942D01*
X1741199Y1408806D01*
X1741182Y1344960D01*
X1740760Y1344392D01*
X1731380Y1341528D01*
X1655779Y1313215D01*
X1603648Y1288640D01*
X1536482Y1267379D01*
X1533580Y1265296D01*
X1532615Y1262965D01*
Y1259424D01*
G01X1703503Y1509804D02*
Y1508299D01*
X1704003Y1507799D01*
X1705337D01*
X1708058Y1505078D01*
Y1455105D01*
X1709590Y1450932D01*
X1740630Y1412540D01*
X1742310Y1409060D01*
X1742292Y1344593D01*
X1741434Y1343436D01*
X1731737Y1340476D01*
X1656211Y1312191D01*
X1604054Y1287604D01*
X1548174Y1269915D01*
Y1269916D01*
X1547940Y1269463D01*
X1546080Y1268875D01*
X1545628Y1269109D01*
X1536986Y1266374D01*
X1534485Y1264578D01*
X1533725Y1262744D01*
Y1259424D01*
G01X1592187Y-69306D02*
X1593332Y-70451D01*
X1608606D01*
X1609768Y-71425D01*
X1612176Y-85080D01*
X1613681Y-86135D01*
X1617680Y-85428D01*
X1618735Y-83923D01*
X1614867Y-61984D01*
X1616449Y-59727D01*
X1621360Y-58860D01*
X1623617Y-60443D01*
X1627976Y-85168D01*
X1629481Y-86223D01*
X1633480Y-85516D01*
X1634535Y-84011D01*
X1630648Y-61964D01*
X1632230Y-59707D01*
X1637139Y-58840D01*
X1639397Y-60422D01*
X1643791Y-85343D01*
X1645296Y-86398D01*
X1649295Y-85691D01*
X1650350Y-84186D01*
X1646432Y-61961D01*
X1648014Y-59704D01*
X1652923Y-58837D01*
X1655181Y-60419D01*
X1659557Y-85241D01*
X1661062Y-86296D01*
X1665061Y-85589D01*
X1666116Y-84083D01*
X1662216Y-61958D01*
X1663798Y-59701D01*
X1668707Y-58834D01*
X1670965Y-60416D01*
X1675331Y-85180D01*
X1676835Y-86235D01*
X1680834Y-85528D01*
X1681889Y-84022D01*
X1677998Y-61949D01*
X1679580Y-59692D01*
X1684489Y-58825D01*
X1686747Y-60407D01*
X1691112Y-85163D01*
X1692616Y-86218D01*
X1696615Y-85511D01*
X1697671Y-84005D01*
X1693783Y-61965D01*
X1695365Y-59707D01*
X1700274Y-58840D01*
X1702534Y-60423D01*
X1706906Y-85223D01*
X1708411Y-86278D01*
X1712410Y-85571D01*
X1713465Y-84066D01*
X1709565Y-61949D01*
X1711147Y-59692D01*
X1716056Y-58825D01*
X1718315Y-60409D01*
X1719940Y-69620D01*
X1721085Y-70423D01*
X1735260D01*
X1736405Y-69278D01*
G01X1592187Y-72706D02*
X1593332Y-71561D01*
X1608202D01*
X1608745Y-72016D01*
X1611162Y-85726D01*
X1613421Y-87309D01*
X1618326Y-86442D01*
X1619909Y-84184D01*
X1616041Y-62245D01*
X1617095Y-60741D01*
X1621099Y-60034D01*
X1622603Y-61089D01*
X1626962Y-85814D01*
X1629221Y-87397D01*
X1634126Y-86530D01*
X1635709Y-84272D01*
X1631822Y-62225D01*
X1632876Y-60721D01*
X1636879Y-60014D01*
X1638383Y-61068D01*
X1642777Y-85989D01*
X1645036Y-87572D01*
X1649941Y-86705D01*
X1651524Y-84447D01*
X1647606Y-62222D01*
X1648660Y-60718D01*
X1652663Y-60011D01*
X1654167Y-61065D01*
X1658543Y-85887D01*
X1660802Y-87470D01*
X1665707Y-86603D01*
X1667290Y-84344D01*
X1663390Y-62219D01*
X1664444Y-60715D01*
X1668447Y-60008D01*
X1669951Y-61062D01*
X1674317Y-85826D01*
X1676575Y-87409D01*
X1681480Y-86542D01*
X1683063Y-84283D01*
X1679172Y-62210D01*
X1680226Y-60706D01*
X1684229Y-59999D01*
X1685733Y-61053D01*
X1690098Y-85809D01*
X1692356Y-87392D01*
X1697261Y-86525D01*
X1698845Y-84266D01*
X1694957Y-62225D01*
X1696011Y-60721D01*
X1700014Y-60014D01*
X1701520Y-61069D01*
X1705892Y-85869D01*
X1708151Y-87452D01*
X1713056Y-86585D01*
X1714639Y-84327D01*
X1710739Y-62210D01*
X1711793Y-60706D01*
X1715795Y-59999D01*
X1717301Y-61055D01*
X1718926Y-70266D01*
X1720734Y-71533D01*
X1735260D01*
X1736405Y-72678D01*
G01X1582187Y-33786D02*
X1583332Y-32641D01*
X1596082D01*
X1598018Y-34577D01*
X1600811Y-50408D01*
X1603069Y-51991D01*
X1607974Y-51124D01*
X1609557Y-48865D01*
X1604454Y-19921D01*
X1605508Y-18417D01*
X1609511Y-17710D01*
X1611015Y-18764D01*
X1616610Y-50491D01*
X1618867Y-52073D01*
X1623771Y-51205D01*
X1625355Y-48945D01*
X1620240Y-19935D01*
X1621294Y-18431D01*
X1625297Y-17724D01*
X1626801Y-18778D01*
X1632466Y-50898D01*
X1634724Y-52481D01*
X1639629Y-51614D01*
X1641212Y-49356D01*
X1636029Y-19960D01*
X1637083Y-18456D01*
X1641086Y-17749D01*
X1642590Y-18803D01*
X1648259Y-50959D01*
X1650520Y-52542D01*
X1655425Y-51675D01*
X1657008Y-49419D01*
X1651809Y-19934D01*
X1652863Y-18430D01*
X1656866Y-17723D01*
X1658370Y-18777D01*
X1664011Y-50772D01*
X1666270Y-52355D01*
X1671175Y-51488D01*
X1672758Y-49230D01*
X1667589Y-19915D01*
X1668643Y-18411D01*
X1672646Y-17704D01*
X1674150Y-18758D01*
X1679780Y-50689D01*
X1682039Y-52272D01*
X1686944Y-51405D01*
X1688527Y-49147D01*
X1683378Y-19946D01*
X1684432Y-18442D01*
X1688435Y-17735D01*
X1689940Y-18790D01*
X1695580Y-50777D01*
X1697839Y-52360D01*
X1702744Y-51493D01*
X1704327Y-49235D01*
X1699167Y-19972D01*
X1700221Y-18468D01*
X1704224Y-17761D01*
X1705729Y-18815D01*
X1711395Y-50952D01*
X1713654Y-52535D01*
X1718559Y-51668D01*
X1720142Y-49410D01*
X1714948Y-19951D01*
X1716002Y-18447D01*
X1720005Y-17740D01*
X1721509Y-18794D01*
X1727161Y-50850D01*
X1729420Y-52433D01*
X1734325Y-51566D01*
X1735908Y-49308D01*
X1730723Y-19897D01*
X1731777Y-18393D01*
X1735780Y-17686D01*
X1737284Y-18740D01*
X1742926Y-50740D01*
X1745185Y-52323D01*
X1750090Y-51456D01*
X1751673Y-49198D01*
X1746510Y-19916D01*
X1747564Y-18412D01*
X1751567Y-17705D01*
X1753071Y-18759D01*
X1758698Y-50675D01*
X1760957Y-52258D01*
X1765862Y-51391D01*
X1767446Y-49132D01*
X1762297Y-19942D01*
X1763351Y-18438D01*
X1767354Y-17731D01*
X1768860Y-18786D01*
X1774493Y-50735D01*
X1776752Y-52318D01*
X1781657Y-51451D01*
X1783240Y-49193D01*
X1778097Y-20025D01*
X1779151Y-18521D01*
X1783153Y-17814D01*
X1784659Y-18870D01*
X1786882Y-31476D01*
X1788690Y-32743D01*
X1800616D01*
X1801761Y-33888D01*
G01X1582187Y-30386D02*
X1583332Y-31531D01*
X1596542D01*
X1599051Y-34039D01*
X1601825Y-49762D01*
X1603329Y-50817D01*
X1607328Y-50110D01*
X1608383Y-48604D01*
X1603280Y-19660D01*
X1604862Y-17403D01*
X1609771Y-16536D01*
X1612029Y-18118D01*
X1617624Y-49845D01*
X1619127Y-50899D01*
X1623125Y-50192D01*
X1624181Y-48685D01*
X1619066Y-19674D01*
X1620648Y-17417D01*
X1625557Y-16550D01*
X1627815Y-18132D01*
X1633480Y-50252D01*
X1634984Y-51307D01*
X1638983Y-50600D01*
X1640038Y-49095D01*
X1634855Y-19699D01*
X1636437Y-17442D01*
X1641346Y-16575D01*
X1643604Y-18157D01*
X1649273Y-50313D01*
X1650780Y-51368D01*
X1654779Y-50661D01*
X1655834Y-49158D01*
X1650635Y-19673D01*
X1652217Y-17416D01*
X1657126Y-16549D01*
X1659384Y-18131D01*
X1665025Y-50126D01*
X1666530Y-51181D01*
X1670529Y-50474D01*
X1671584Y-48969D01*
X1666415Y-19654D01*
X1667997Y-17397D01*
X1672906Y-16530D01*
X1675164Y-18112D01*
X1680794Y-50043D01*
X1682299Y-51098D01*
X1686298Y-50391D01*
X1687353Y-48886D01*
X1682204Y-19685D01*
X1683786Y-17428D01*
X1688696Y-16561D01*
X1690954Y-18144D01*
X1696594Y-50131D01*
X1698099Y-51186D01*
X1702098Y-50479D01*
X1703153Y-48974D01*
X1697993Y-19711D01*
X1699575Y-17454D01*
X1704484Y-16587D01*
X1706743Y-18169D01*
X1712409Y-50306D01*
X1713914Y-51361D01*
X1717913Y-50654D01*
X1718968Y-49149D01*
X1713774Y-19690D01*
X1715356Y-17433D01*
X1720265Y-16566D01*
X1722523Y-18148D01*
X1728175Y-50204D01*
X1729680Y-51259D01*
X1733679Y-50552D01*
X1734734Y-49047D01*
X1729549Y-19636D01*
X1731131Y-17379D01*
X1736040Y-16512D01*
X1738298Y-18094D01*
X1743940Y-50094D01*
X1745445Y-51149D01*
X1749444Y-50442D01*
X1750499Y-48937D01*
X1745336Y-19655D01*
X1746918Y-17398D01*
X1751827Y-16531D01*
X1754085Y-18113D01*
X1759712Y-50029D01*
X1761217Y-51084D01*
X1765216Y-50377D01*
X1766272Y-48871D01*
X1761123Y-19682D01*
X1762705Y-17424D01*
X1767614Y-16557D01*
X1769874Y-18140D01*
X1775507Y-50089D01*
X1777012Y-51144D01*
X1781011Y-50437D01*
X1782066Y-48932D01*
X1776923Y-19764D01*
X1778505Y-17507D01*
X1783414Y-16640D01*
X1785673Y-18224D01*
X1787896Y-30830D01*
X1789041Y-31633D01*
X1800616D01*
X1801761Y-30488D01*
G01X1702655Y614511D02*
X1703800Y613366D01*
X1706197D01*
X1707383Y614552D01*
Y616125D01*
X1705514Y619362D01*
X1705036Y619491D01*
X1704060Y621180D01*
X1704188Y621658D01*
X1703214Y623346D01*
X1702735Y623474D01*
X1701759Y625164D01*
X1701888Y625642D01*
X1674061Y673843D01*
X1668083Y696149D01*
X1668074Y696247D01*
X1668075D01*
X1653070Y867757D01*
X1656551Y907543D01*
X1666962Y1026550D01*
Y1052825D01*
X1663520Y1061137D01*
Y1068787D01*
G01X1702655Y611111D02*
X1703800Y612256D01*
X1706657D01*
X1708493Y614092D01*
Y616423D01*
X1675096Y674272D01*
X1669181Y696343D01*
X1654185Y867757D01*
X1668072Y1026501D01*
Y1053046D01*
X1664630Y1061358D01*
Y1068787D01*
G01X1667260Y1069000D02*
Y1062041D01*
X1670772Y1053560D01*
Y1026297D01*
X1657196Y871062D01*
X1671228Y710655D01*
X1670909Y710276D01*
X1671079Y708332D01*
X1671460Y708014D01*
X1671629Y706072D01*
X1671310Y705693D01*
X1671480Y703749D01*
X1671861Y703431D01*
X1672030Y701489D01*
X1671712Y701110D01*
X1671882Y699167D01*
X1672262Y698849D01*
X1672507Y696041D01*
X1678445Y673877D01*
X1711186Y617166D01*
Y613656D01*
X1710185Y611239D01*
X1705200Y606254D01*
X1693398D01*
X1692253Y607399D01*
G01Y603999D02*
X1693398Y605144D01*
X1705660D01*
X1711126Y610610D01*
X1712296Y613435D01*
Y617464D01*
X1679480Y674305D01*
Y674306D01*
X1673605Y696234D01*
X1658311Y871062D01*
X1671882Y1026248D01*
Y1053781D01*
X1670244Y1057737D01*
X1670407Y1058129D01*
X1669659Y1059932D01*
X1669268Y1060094D01*
X1668370Y1062262D01*
Y1069000D01*
G01X1671000Y1068787D02*
Y1062945D01*
X1674582Y1054295D01*
Y1026626D01*
X1661014Y871505D01*
X1676313Y696663D01*
X1682041Y675288D01*
X1714996Y618203D01*
Y612727D01*
X1713472Y609047D01*
X1712266Y607242D01*
X1711711Y607132D01*
X1710821Y605801D01*
X1710932Y605246D01*
X1710043Y603916D01*
X1710044D01*
X1709489Y603806D01*
X1708599Y602475D01*
X1708709Y601920D01*
X1707821Y600590D01*
X1706424Y599193D01*
X1703800D01*
X1702655Y600338D01*
G01X1672110Y1068787D02*
Y1063166D01*
X1675692Y1054516D01*
Y1026577D01*
X1662129Y871505D01*
X1677411Y696857D01*
X1683076Y675717D01*
X1716106Y618501D01*
Y612506D01*
X1714456Y608521D01*
X1708683Y599882D01*
X1706884Y598083D01*
X1703800D01*
X1702655Y596938D01*
G01X1674740Y1069000D02*
Y1064239D01*
X1675486Y1062438D01*
X1675323Y1062046D01*
X1676070Y1060243D01*
X1676462Y1060081D01*
X1678392Y1055421D01*
Y1026889D01*
X1665059Y874399D01*
X1672628Y787890D01*
X1680187Y701482D01*
X1679778Y700995D01*
X1679926Y699300D01*
X1680414Y698891D01*
X1680562Y697198D01*
X1686312Y675744D01*
X1718806Y619456D01*
Y611169D01*
X1716863Y606476D01*
X1710390Y596790D01*
X1707704Y594104D01*
X1702819Y592080D01*
X1693398D01*
X1692253Y593225D01*
G01Y589825D02*
X1693398Y590970D01*
X1703040D01*
X1708333Y593163D01*
X1711252Y596082D01*
X1717847Y605950D01*
X1719916Y610948D01*
Y619754D01*
X1687347Y676173D01*
X1681660Y697392D01*
X1666174Y874399D01*
X1679502Y1026840D01*
Y1055642D01*
X1675850Y1064460D01*
Y1069000D01*
G01X1678480Y1068787D02*
Y1066431D01*
X1682202Y1057444D01*
Y1026725D01*
X1668896Y874535D01*
X1676625Y786194D01*
X1676624D01*
X1684354Y697852D01*
X1689755Y677715D01*
X1722600Y620818D01*
Y610298D01*
X1718268Y599841D01*
X1715821Y596179D01*
X1715336Y596083D01*
X1714252Y594460D01*
X1714348Y593975D01*
X1712104Y590616D01*
X1709799Y588311D01*
X1709233D01*
X1707889Y586967D01*
Y586401D01*
X1706508Y585020D01*
X1703800D01*
X1702655Y586165D01*
G01Y582765D02*
X1703800Y583910D01*
X1706968D01*
X1713027Y589969D01*
Y589999D01*
X1719252Y599315D01*
X1723710Y610077D01*
Y621116D01*
X1690790Y678144D01*
X1685452Y698046D01*
X1670011Y874535D01*
X1683312Y1026676D01*
Y1057665D01*
X1679590Y1066652D01*
Y1068787D01*
G01X1692253Y575652D02*
X1693398Y576797D01*
X1702082D01*
X1702166Y576881D01*
X1709612Y579965D01*
X1715149Y585502D01*
Y585532D01*
X1721760Y595426D01*
X1727536Y609372D01*
Y622110D01*
X1694389Y679532D01*
X1689187Y698934D01*
X1673819Y874406D01*
X1687122Y1026586D01*
Y1058384D01*
X1683330Y1067541D01*
Y1069000D01*
G01X1692253Y579052D02*
X1693398Y577907D01*
X1701742D01*
X1708983Y580906D01*
X1714226Y586149D01*
X1715309Y587770D01*
X1715212Y588255D01*
X1716297Y589878D01*
X1716782Y589974D01*
X1717865Y591595D01*
X1717768Y592080D01*
X1718852Y593703D01*
X1719338Y593799D01*
X1720776Y595952D01*
X1726426Y609593D01*
Y621812D01*
X1693354Y679103D01*
X1688089Y698740D01*
X1688080Y698838D01*
X1688081D01*
X1672704Y874406D01*
X1686012Y1026635D01*
Y1058163D01*
X1682220Y1067320D01*
Y1069000D01*
G01X1692253Y529013D02*
X1693398Y527868D01*
X1696427D01*
X1696847Y528288D01*
X1698647D01*
X1699067Y527868D01*
X1700866D01*
X1702529Y528557D01*
Y528556D01*
X1702757Y529106D01*
X1704421Y529795D01*
X1704970Y529568D01*
X1707697Y530697D01*
X1710461Y533461D01*
X1711149Y535123D01*
X1710922Y535672D01*
X1711611Y537336D01*
X1712161Y537564D01*
X1712160D01*
X1712848Y539226D01*
X1712632Y539749D01*
X1713321Y541413D01*
X1713844Y541630D01*
X1714532Y543292D01*
X1714316Y543815D01*
X1715005Y545479D01*
X1715528Y545696D01*
X1716216Y547358D01*
X1716000Y547881D01*
X1716689Y549545D01*
X1717213Y549761D01*
X1717901Y551423D01*
X1717685Y551946D01*
X1718374Y553610D01*
X1718897Y553827D01*
X1726176Y571399D01*
X1727984Y573207D01*
X1741666Y606239D01*
Y625678D01*
X1707899Y684180D01*
X1703286Y701382D01*
X1688306Y872601D01*
X1688314Y872697D01*
X1688315D01*
X1698584Y990264D01*
X1719570Y1021671D01*
X1740335Y1052748D01*
X1742576Y1058159D01*
X1743533Y1069080D01*
X1740648Y1077006D01*
X1709798Y1107856D01*
X1704203Y1110173D01*
X1701644D01*
G01X1702655Y491991D02*
X1703800Y490846D01*
X1705947D01*
X1706785Y491684D01*
X1707478Y493358D01*
X1708502Y498509D01*
X1709201Y500167D01*
X1708988Y500691D01*
X1709687Y502351D01*
X1710212Y502564D01*
X1710211D01*
X1710910Y504222D01*
X1710911D01*
X1710698Y504746D01*
X1711397Y506406D01*
X1711922Y506619D01*
X1711921D01*
X1712620Y508277D01*
X1712621D01*
X1712408Y508801D01*
X1713107Y510461D01*
X1713632Y510674D01*
X1713631Y510675D01*
X1714330Y512333D01*
X1714117Y512857D01*
X1714816Y514517D01*
X1715341Y514730D01*
X1716040Y516388D01*
X1715827Y516912D01*
X1716526Y518572D01*
X1717051Y518785D01*
X1718170Y521440D01*
X1720049Y523320D01*
X1720758Y525034D01*
X1720542Y525556D01*
X1721231Y527220D01*
X1721754Y527437D01*
X1722442Y529099D01*
X1722226Y529622D01*
X1722915Y531286D01*
X1723438Y531503D01*
X1753096Y603105D01*
Y628136D01*
X1752569Y630107D01*
X1718482Y689173D01*
X1714541Y703863D01*
X1699780Y872552D01*
X1709699Y986172D01*
X1750192Y1046769D01*
X1753644Y1055103D01*
X1755105Y1071882D01*
X1750422Y1083189D01*
X1716192Y1117419D01*
X1706601Y1121392D01*
X1701550D01*
G01X1692253Y511439D02*
X1693398Y512584D01*
X1702993D01*
X1707195Y514325D01*
X1716938Y524068D01*
X1735143Y568018D01*
X1735821Y568696D01*
X1750396Y603883D01*
Y627779D01*
X1750084Y628948D01*
X1715957Y688082D01*
X1711843Y703428D01*
X1697058Y872414D01*
X1707074Y987133D01*
X1747889Y1048219D01*
X1751042Y1055833D01*
X1752408Y1071463D01*
X1748170Y1081692D01*
X1714689Y1115173D01*
X1706023Y1118763D01*
X1701644D01*
G01X1692253Y525613D02*
X1693398Y526758D01*
X1701088D01*
X1708326Y529756D01*
X1711402Y532832D01*
X1727117Y570770D01*
X1728925Y572578D01*
X1742776Y606018D01*
Y625976D01*
X1708934Y684609D01*
X1704384Y701576D01*
X1689421Y872601D01*
X1699666Y989884D01*
X1741319Y1052222D01*
X1743667Y1057892D01*
X1744661Y1069229D01*
X1741607Y1077617D01*
X1710427Y1108797D01*
X1704424Y1111283D01*
X1701644D01*
G01Y1117653D02*
X1705802D01*
X1714060Y1114232D01*
X1747229Y1081063D01*
X1751278Y1071289D01*
X1749951Y1056100D01*
X1746905Y1048745D01*
X1705992Y987513D01*
X1700960Y929871D01*
X1695943Y872414D01*
X1710745Y703234D01*
X1714922Y687653D01*
X1749049Y628520D01*
X1749286Y627633D01*
Y604104D01*
X1734880Y569325D01*
X1734202Y568647D01*
X1722733Y540961D01*
X1722210Y540744D01*
X1721521Y539080D01*
X1721737Y538557D01*
X1721049Y536895D01*
X1720526Y536678D01*
X1719837Y535014D01*
X1720053Y534491D01*
X1719365Y532829D01*
X1718842Y532612D01*
X1718153Y530948D01*
X1718369Y530425D01*
X1717681Y528763D01*
X1717158Y528546D01*
X1716469Y526882D01*
X1716685Y526359D01*
X1715997Y524697D01*
X1713132Y521832D01*
X1712566D01*
X1711292Y520558D01*
Y519992D01*
X1710020Y518720D01*
X1709454D01*
X1708180Y517446D01*
Y516880D01*
X1706566Y515266D01*
X1702772Y513694D01*
X1699825D01*
X1699475Y514044D01*
X1697525D01*
X1697175Y513694D01*
X1693398D01*
X1692253Y514839D01*
G01X1702655Y488591D02*
X1703800Y489736D01*
X1706407D01*
X1707726Y491055D01*
X1708546Y493034D01*
X1709569Y498182D01*
X1719109Y520809D01*
X1720990Y522691D01*
X1754206Y602884D01*
Y628282D01*
X1753604Y630535D01*
X1719517Y689602D01*
X1715639Y704057D01*
X1700895Y872552D01*
X1710781Y985792D01*
X1751176Y1046243D01*
X1754735Y1054836D01*
X1755481Y1063397D01*
X1756235Y1072056D01*
X1751363Y1083818D01*
X1716821Y1118360D01*
X1706822Y1122502D01*
X1701550D01*
G01X1702655Y521952D02*
X1703800Y520807D01*
X1706108D01*
X1708031Y522730D01*
Y523295D01*
X1709305Y524569D01*
X1709870D01*
X1712419Y527118D01*
X1713716Y530251D01*
X1713500Y530774D01*
X1714189Y532438D01*
X1714712Y532654D01*
X1715400Y534316D01*
X1715184Y534839D01*
X1715873Y536503D01*
X1716396Y536720D01*
X1717084Y538382D01*
X1716868Y538905D01*
X1717557Y540569D01*
X1718080Y540786D01*
X1718768Y542448D01*
X1718552Y542971D01*
X1719241Y544635D01*
X1719764Y544852D01*
X1720452Y546514D01*
X1720236Y547037D01*
X1720925Y548701D01*
X1721448Y548918D01*
X1722136Y550580D01*
X1721920Y551103D01*
X1722609Y552767D01*
X1723133Y552983D01*
X1730193Y570027D01*
X1731726Y571560D01*
X1731725D01*
X1745476Y604756D01*
Y626978D01*
X1711474Y685894D01*
X1707023Y702492D01*
X1692137Y872648D01*
X1702277Y988758D01*
X1743597Y1050596D01*
X1746253Y1057009D01*
X1747451Y1070701D01*
X1744041Y1078932D01*
X1711929Y1111044D01*
X1705006Y1113912D01*
X1701550D01*
G01X1702655Y518552D02*
X1703800Y519697D01*
X1706568D01*
X1713360Y526489D01*
X1731134Y569398D01*
X1732667Y570931D01*
X1746586Y604535D01*
Y627276D01*
X1712509Y686323D01*
X1708121Y702686D01*
X1693252Y872648D01*
X1703359Y988378D01*
X1744581Y1050070D01*
X1747344Y1056742D01*
X1748581Y1070875D01*
X1744982Y1079561D01*
X1712558Y1111985D01*
X1705227Y1115022D01*
X1701550D01*
G01X1702655Y477818D02*
X1703800Y476673D01*
X1705972D01*
X1707742Y478443D01*
Y479009D01*
X1709016Y480283D01*
X1709582D01*
X1710854Y481555D01*
X1711542Y483217D01*
X1711326Y483740D01*
X1712015Y485404D01*
X1712538Y485621D01*
X1715480Y492725D01*
X1715264Y493247D01*
X1715953Y494911D01*
X1716477Y495128D01*
X1716476D01*
X1717164Y496790D01*
X1716948Y497313D01*
X1717637Y498977D01*
X1718161Y499193D01*
X1718160D01*
X1718848Y500855D01*
X1718849D01*
X1718633Y501378D01*
X1719322Y503042D01*
X1719845Y503259D01*
X1720533Y504921D01*
X1720317Y505444D01*
X1721006Y507108D01*
X1721529Y507325D01*
X1722217Y508987D01*
X1722001Y509510D01*
X1722690Y511174D01*
X1723214Y511390D01*
X1723213D01*
X1725775Y517574D01*
X1726840Y518639D01*
X1726839D01*
X1760716Y600423D01*
Y629142D01*
X1759687Y632993D01*
X1725738Y691823D01*
X1722152Y705187D01*
X1707516Y872486D01*
X1707524Y872582D01*
X1707525D01*
X1717176Y983177D01*
X1756178Y1041544D01*
X1758606Y1047405D01*
X1761034Y1053265D01*
X1762766Y1073044D01*
X1756800Y1087449D01*
X1720456Y1123793D01*
X1708193Y1128873D01*
X1701550D01*
G01X1692253Y467306D02*
X1693398Y468451D01*
X1702842D01*
X1714432Y476194D01*
X1730439Y514839D01*
X1731681Y516081D01*
X1765636Y598053D01*
Y629791D01*
X1764257Y634953D01*
X1730509Y693438D01*
X1727169Y705678D01*
X1712514Y873173D01*
X1721963Y981454D01*
X1760431Y1039020D01*
X1763121Y1045514D01*
X1765834Y1052063D01*
X1766776Y1062886D01*
X1767726Y1073807D01*
X1760931Y1090207D01*
X1723216Y1127922D01*
X1709208Y1133724D01*
X1701644D01*
G01X1702655Y474418D02*
X1703800Y475563D01*
X1706432D01*
X1711795Y480926D01*
X1726716Y516945D01*
X1727781Y518010D01*
X1761826Y600202D01*
Y629288D01*
X1760722Y633421D01*
X1726773Y692252D01*
X1723250Y705381D01*
X1708631Y872486D01*
X1718258Y982797D01*
X1757162Y1041018D01*
X1762125Y1052998D01*
X1763896Y1073218D01*
X1757741Y1088078D01*
X1721085Y1124734D01*
X1708414Y1129983D01*
X1701550D01*
G01X1692253Y484879D02*
X1693398Y483734D01*
X1699400D01*
X1699800Y484134D01*
X1701600D01*
X1702000Y483734D01*
X1704334D01*
X1709917Y489317D01*
X1711145Y492284D01*
X1711598Y494557D01*
X1712352Y496378D01*
X1712136Y496900D01*
X1712825Y498564D01*
X1713348Y498781D01*
X1714037Y500443D01*
X1713820Y500966D01*
X1714509Y502630D01*
X1715033Y502846D01*
X1715721Y504508D01*
X1715505Y505031D01*
X1716194Y506695D01*
X1716718Y506911D01*
X1716717Y506912D01*
X1717406Y508574D01*
X1717189Y509097D01*
X1717878Y510761D01*
X1718402Y510977D01*
X1718401D01*
X1719090Y512639D01*
X1718873Y513162D01*
X1719562Y514826D01*
X1720086Y515042D01*
X1721815Y519215D01*
X1723816Y521216D01*
X1724504Y522878D01*
X1724288Y523401D01*
X1724977Y525065D01*
X1725500Y525282D01*
X1756906Y601100D01*
Y628639D01*
X1756105Y631636D01*
X1722064Y690623D01*
X1718423Y704196D01*
X1703676Y872745D01*
X1703684Y872841D01*
X1703685D01*
X1713452Y984749D01*
X1753249Y1044305D01*
X1757338Y1054177D01*
X1758939Y1072456D01*
X1753609Y1085321D01*
X1718324Y1120606D01*
X1707394Y1125134D01*
X1701644D01*
G01X1692253Y481479D02*
X1693398Y482624D01*
X1704794D01*
X1710858Y488688D01*
X1712213Y491960D01*
X1712666Y494233D01*
X1722756Y518586D01*
X1724757Y520587D01*
X1758016Y600879D01*
Y628785D01*
X1757140Y632064D01*
X1723099Y691052D01*
X1719521Y704390D01*
X1704791Y872745D01*
X1714534Y984369D01*
X1754233Y1043779D01*
X1758429Y1053910D01*
X1760069Y1072630D01*
X1754550Y1085950D01*
X1718953Y1121547D01*
X1707615Y1126244D01*
X1701644D01*
G01X1692253Y470706D02*
X1693398Y469561D01*
X1698104D01*
X1698504Y469961D01*
X1700304D01*
X1700704Y469561D01*
X1702504D01*
X1709371Y474148D01*
X1709482Y474703D01*
X1710979Y475704D01*
X1711534Y475594D01*
X1713535Y476930D01*
X1714522Y479314D01*
X1714306Y479837D01*
X1714995Y481501D01*
X1715518Y481717D01*
X1716206Y483380D01*
X1715990Y483902D01*
X1716679Y485566D01*
X1717202Y485783D01*
X1717890Y487446D01*
X1717674Y487968D01*
X1718363Y489632D01*
X1718886Y489849D01*
X1719574Y491511D01*
X1719358Y492034D01*
X1720047Y493698D01*
X1720570Y493915D01*
X1721628Y496470D01*
X1721412Y496993D01*
X1722101Y498657D01*
X1722624Y498874D01*
X1729498Y515468D01*
X1730740Y516710D01*
X1764526Y598274D01*
Y629645D01*
X1763222Y634525D01*
X1729476Y693007D01*
X1726071Y705482D01*
X1711399Y873173D01*
X1720881Y981834D01*
X1759447Y1039546D01*
X1764743Y1052330D01*
X1766596Y1073633D01*
X1759990Y1089578D01*
X1722587Y1126981D01*
X1708987Y1132614D01*
X1701644D01*
G01X1692253Y561479D02*
X1693398Y562624D01*
X1695048D01*
X1697063Y561790D01*
X1700563D01*
X1707557Y564687D01*
X1721624Y578754D01*
X1726020Y585331D01*
X1735156Y607388D01*
Y624081D01*
X1701592Y682230D01*
X1696840Y699953D01*
X1681595Y874202D01*
X1694742Y1024679D01*
Y1028355D01*
X1698292Y1064402D01*
Y1069988D01*
G01X1692253Y564879D02*
X1693398Y563734D01*
X1695269D01*
X1697284Y562900D01*
X1700342D01*
X1702143Y563646D01*
X1702332Y564103D01*
X1704135Y564850D01*
X1704592Y564661D01*
X1706928Y565628D01*
X1711285Y569985D01*
Y570480D01*
X1712665Y571860D01*
X1713160D01*
X1714538Y573238D01*
Y573733D01*
X1715918Y575113D01*
X1716413D01*
X1717993Y576693D01*
Y577188D01*
X1719372Y578567D01*
X1719867D01*
X1720762Y579462D01*
X1721845Y581083D01*
X1721749Y581568D01*
X1722833Y583190D01*
X1723319Y583287D01*
X1723318D01*
X1725036Y585857D01*
X1725782Y587658D01*
X1725592Y588115D01*
X1726340Y589918D01*
X1726797Y590107D01*
X1726796D01*
X1734046Y607609D01*
Y623783D01*
X1700557Y681801D01*
X1695742Y699759D01*
X1688110Y786981D01*
X1688111D01*
X1680480Y874202D01*
X1693632Y1024728D01*
Y1028410D01*
X1697182Y1064457D01*
Y1069988D01*
G01X1702655Y571991D02*
X1703800Y570846D01*
X1706126D01*
X1708034Y572754D01*
Y573292D01*
X1709308Y574566D01*
X1709846D01*
X1714207Y578927D01*
X1715305Y580570D01*
X1715208Y581055D01*
X1716292Y582678D01*
X1716778Y582774D01*
X1716777D01*
X1723762Y593227D01*
X1730236Y608855D01*
Y622832D01*
X1696912Y680562D01*
X1691810Y699586D01*
X1676584Y873440D01*
X1689822Y1024910D01*
Y1058792D01*
X1685961Y1068115D01*
Y1068787D01*
G01X1702655Y568591D02*
X1703800Y569736D01*
X1706586D01*
X1715069Y578219D01*
X1724746Y592701D01*
X1731346Y608634D01*
Y623130D01*
X1697947Y680991D01*
X1692908Y699780D01*
X1677699Y873440D01*
X1690932Y1024861D01*
Y1059013D01*
X1687071Y1068336D01*
Y1068787D01*
G01X1702655Y536125D02*
X1703800Y534980D01*
X1706080D01*
X1706780Y535680D01*
X1707877Y538329D01*
X1707650Y538877D01*
X1708338Y540541D01*
X1708888Y540769D01*
X1709631Y542565D01*
X1709404Y543113D01*
X1710093Y544777D01*
X1710643Y545005D01*
X1710642D01*
X1711330Y546667D01*
X1711103Y547216D01*
X1711792Y548880D01*
X1712342Y549107D01*
X1712341D01*
X1713029Y550769D01*
X1712802Y551318D01*
X1713491Y552982D01*
X1714041Y553209D01*
X1714040D01*
X1714728Y554871D01*
X1714501Y555420D01*
X1715190Y557084D01*
X1715740Y557311D01*
X1716428Y558973D01*
X1716201Y559522D01*
X1716890Y561186D01*
X1717440Y561414D01*
X1717439D01*
X1722133Y572745D01*
X1724769Y575381D01*
X1724768D01*
X1737856Y606976D01*
Y624743D01*
X1704247Y682973D01*
X1701866Y691849D01*
X1701867D01*
X1700695Y696217D01*
X1700694D01*
X1700108Y698401D01*
X1700109D01*
X1699499Y700678D01*
X1684480Y872367D01*
X1693102Y971071D01*
X1693103D01*
X1701712Y1069620D01*
X1701230Y1091637D01*
X1698444Y1097285D01*
X1697524Y1098206D01*
G01X1702655Y532725D02*
X1703800Y533870D01*
X1706540D01*
X1707721Y535051D01*
X1723074Y572116D01*
X1725710Y574752D01*
X1738966Y606755D01*
Y625041D01*
X1705282Y683402D01*
X1700597Y700872D01*
X1685595Y872367D01*
X1694209Y970970D01*
X1694210D01*
X1702824Y1069584D01*
X1702335Y1091908D01*
X1699359Y1097940D01*
X1698309Y1098991D01*
G54D27*
X1734069Y1797909D03*
Y1807909D03*
G54D18*
X109882Y1622402D03*
X118543Y1452717D03*
X127205Y1622402D03*
X135866Y1452717D03*
X153189D03*
X170512D03*
X179173Y1489331D03*
Y1494449D03*
Y1591693D03*
Y1596811D03*
Y1607048D03*
Y1612166D03*
Y1622402D03*
X187835Y1452717D03*
Y1493662D03*
Y1498780D03*
Y1580670D03*
Y1585788D03*
X283110Y1473977D03*
X291771Y1478308D03*
X283110Y1479095D03*
X291771Y1483426D03*
X283110Y1560985D03*
X291771Y1565315D03*
X283110Y1566103D03*
X291771Y1570434D03*
X283110Y1622402D03*
X300433Y1473977D03*
X309094Y1478308D03*
X300433Y1479095D03*
X309094Y1483426D03*
X300433Y1560985D03*
X309094Y1565315D03*
X300433Y1566103D03*
X309094Y1570434D03*
X300433Y1622402D03*
X317756Y1473977D03*
X326417Y1478308D03*
X317756Y1479095D03*
X326417Y1483426D03*
X317756Y1560985D03*
X326417Y1565315D03*
X317756Y1566103D03*
X326417Y1570434D03*
X317756Y1622402D03*
X335078Y1473977D03*
X343740Y1478308D03*
X335078Y1479095D03*
X343740Y1483426D03*
X335078Y1560985D03*
X343740Y1565315D03*
X335078Y1566103D03*
X343740Y1570434D03*
X335078Y1622402D03*
X352401Y1591693D03*
Y1596811D03*
Y1607048D03*
Y1612166D03*
Y1622402D03*
X456339D03*
X465000Y1452717D03*
X473662Y1622402D03*
X482323Y1452717D03*
X490985Y1622402D03*
X499646Y1452717D03*
X516969D03*
X508307Y1622402D03*
X534292Y1452717D03*
Y1585788D03*
X525630Y1591693D03*
Y1596811D03*
Y1607048D03*
Y1612166D03*
Y1622402D03*
X629567Y1504685D03*
Y1509804D03*
Y1607048D03*
Y1612166D03*
Y1622402D03*
X646890Y1504685D03*
Y1509804D03*
X638228Y1509016D03*
Y1514134D03*
X646890Y1607048D03*
Y1612166D03*
X638228Y1611378D03*
X646890Y1622402D03*
X638228Y1616496D03*
X664213Y1504685D03*
Y1509804D03*
X655551Y1509016D03*
Y1514134D03*
X664213Y1607048D03*
Y1612166D03*
X655551Y1611378D03*
Y1616496D03*
X681535Y1504685D03*
Y1509804D03*
X672874Y1509016D03*
Y1514134D03*
X681535Y1607048D03*
Y1612166D03*
X672874Y1611378D03*
X681535Y1622402D03*
X672874Y1616496D03*
X690197Y1509016D03*
Y1514134D03*
X698858Y1596811D03*
Y1612166D03*
X690197Y1611378D03*
Y1616496D03*
X707520Y1585788D03*
X1131850Y1622402D03*
X1149173D03*
X1166496D03*
X1183818D03*
X1305079Y1473977D03*
X1313740Y1478308D03*
X1305079Y1479095D03*
X1313740Y1483426D03*
X1305079Y1560985D03*
X1313740Y1565315D03*
X1305079Y1566103D03*
X1313740Y1570434D03*
X1305079Y1622402D03*
X1322402Y1473977D03*
X1331063Y1478308D03*
X1322402Y1479095D03*
X1331063Y1483426D03*
X1322402Y1560985D03*
X1331063Y1565315D03*
X1322402Y1566103D03*
X1331063Y1570434D03*
X1322402Y1622402D03*
X1339725Y1473977D03*
X1348386Y1478308D03*
X1339725Y1479095D03*
X1348386Y1483426D03*
X1339725Y1560985D03*
X1348386Y1565315D03*
X1339725Y1566103D03*
X1348386Y1570434D03*
X1339725Y1622402D03*
X1357047Y1473977D03*
X1365709Y1478308D03*
X1357047Y1479095D03*
X1365709Y1483426D03*
X1357047Y1560985D03*
X1365709Y1565315D03*
X1357047Y1566103D03*
X1365709Y1570434D03*
X1357047Y1622402D03*
X1486968Y1452717D03*
X1495630Y1622402D03*
X1504291Y1452717D03*
X1521614D03*
X1530275Y1622402D03*
X1538937Y1452717D03*
X1556260D03*
Y1585788D03*
X1547598Y1591693D03*
Y1596811D03*
Y1612166D03*
X1651535Y1504685D03*
X1660196Y1509016D03*
X1651535Y1509804D03*
X1660196Y1514134D03*
X1651535Y1607048D03*
X1660196Y1611378D03*
X1651535Y1612166D03*
X1660196Y1616496D03*
X1668858Y1504685D03*
Y1509804D03*
Y1607048D03*
Y1612166D03*
X1686181Y1504685D03*
Y1509804D03*
X1677519Y1509016D03*
Y1514134D03*
X1686181Y1607048D03*
Y1612166D03*
X1677519Y1611378D03*
Y1616496D03*
X1703503Y1504685D03*
Y1509804D03*
X1694842Y1509016D03*
Y1514134D03*
X1703503Y1607048D03*
Y1612166D03*
X1694842Y1611378D03*
X1703503Y1622402D03*
X1694842Y1616496D03*
X1712165Y1509016D03*
Y1514134D03*
X1720826Y1591693D03*
Y1607048D03*
X1712165Y1611378D03*
X1720826Y1622402D03*
X1712165Y1616496D03*
X1729488Y1580670D03*
G54D28*
X1795453Y812874D03*
Y834922D03*
G54D19*
X173829Y455492D03*
Y583957D03*
X202844Y455492D03*
Y583957D03*
X266841Y421555D03*
Y550020D03*
X295856Y421555D03*
Y550020D03*
X630915Y455492D03*
Y583957D03*
X659930Y455492D03*
Y583957D03*
X723927Y421555D03*
Y550020D03*
X752942Y421555D03*
Y550020D03*
X1088002Y455492D03*
Y583957D03*
X1117017Y455492D03*
Y583957D03*
X1181014Y421555D03*
Y550020D03*
X1210029Y421555D03*
Y550020D03*
X1545089Y455492D03*
Y583957D03*
X1574104Y455492D03*
Y583957D03*
X1638101Y550020D03*
X1667116D03*
G54D29*
X1803917Y823898D03*
M02*
